G04 ================== begin FILE IDENTIFICATION RECORD ==================*
G04 Layout Name:  9324_DA0F0TMBIJ0_F0T_Motherboard_J_v01_20230324_0910.brd*
G04 Film Name:    sst*
G04 File Format:  Gerber RS274X*
G04 File Origin:  Cadence Allegro 17.2-S081*
G04 Origin Date:  Sat Mar 25 08:45:18 2023*
G04 *
G04 Layer:  DRAWING FORMAT/TITLE_BLOCK_A*
G04 Layer:  BOARD GEOMETRY/DESIGN_OUTLINE*
G04 Layer:  BOARD GEOMETRY/CUTOUT*
G04 Layer:  DRAWING FORMAT/TITLE_BLOCK*
G04 Layer:  MANUFACTURING/TP_TEXT_TOP*
G04 Layer:  REF DES/SILKSCREEN_TOP*
G04 Layer:  PACKAGE GEOMETRY/SILKSCREEN_TOP*
G04 Layer:  MANUFACTURING/PHOTOPLOT_OUTLINE*
G04 Layer:  DRAWING FORMAT/TITLE_DATA_SST*
G04 Layer:  BOARD GEOMETRY/SILKSCREEN_TOP*
G04 *
G04 Offset:    (0.00 0.00)*
G04 Mirror:    No*
G04 Mode:      Positive*
G04 Rotation:  0*
G04 FullContactRelief:  No*
G04 UndefLineWidth:     6.00*
G04 ================== end FILE IDENTIFICATION RECORD ====================*
%FSLAX25Y25*MOIN*%
%IR0*IPPOS*OFA0.00000B0.00000*MIA0B0*SFA1.00000B1.00000*%
%ADD10C,.01*%
%ADD11C,.04*%
%ADD12C,.006*%
%ADD14C,.065*%
%ADD15C,.06501*%
%ADD13C,.067*%
G75*
%LPD*%
G75*
G36*
G01X7340Y300637D02*
X11340Y298637D01*
X7340Y296637D01*
Y300637D01*
G37*
G36*
G01X17820Y396475D02*
X21820Y394475D01*
X17820Y392475D01*
Y396475D01*
G37*
G36*
G01X22997Y1267034D02*
X26468Y1265298D01*
X22997Y1263562D01*
Y1267034D01*
G37*
G36*
G01X46115Y304202D02*
X44115Y300202D01*
X42115Y304202D01*
X46115D01*
G37*
G36*
G01X50916Y242077D02*
X54916Y240077D01*
X50916Y238077D01*
Y242077D01*
G37*
G36*
G01X53362Y1266903D02*
X56452Y1265358D01*
X53362Y1263813D01*
Y1266903D01*
G37*
G36*
G01X47514Y1327988D02*
X51514Y1325988D01*
X47514Y1323988D01*
Y1327988D01*
G37*
G36*
G01X47377Y1632701D02*
X51377Y1630701D01*
X47377Y1628701D01*
Y1632701D01*
G37*
G36*
G01X62162Y400771D02*
X63367Y404389D01*
X65779Y401977D01*
X62162Y400771D01*
G37*
G36*
G01X70917Y1525845D02*
X73746Y1523017D01*
X75160Y1527259D01*
X70917Y1525845D01*
G37*
G36*
G01X90805Y285321D02*
X89070Y284454D01*
Y286188D01*
X90805Y285321D01*
G37*
G36*
G01X91225Y302821D02*
X89490Y301954D01*
Y303688D01*
X91225Y302821D01*
G37*
G36*
G01X85159Y718066D02*
X85509Y714730D01*
X82630Y716451D01*
X85159Y718066D01*
G37*
G36*
G01D02*
X85509Y714730D01*
X82630Y716451D01*
X85159Y718066D01*
G37*
G36*
G01X82716Y1263768D02*
X86020Y1265420D01*
X82780Y1267040D01*
X82716Y1263768D01*
G37*
G36*
G01X108222Y445521D02*
X106222Y441521D01*
X104222Y445521D01*
X108222D01*
G37*
G36*
G01D02*
X106222Y441521D01*
X104222Y445521D01*
X108222D01*
G37*
G36*
G01D02*
X106222Y441521D01*
X104222Y445521D01*
X108222D01*
G37*
G36*
G01D02*
X106222Y441521D01*
X104222Y445521D01*
X108222D01*
G37*
G36*
G01X103280Y1594922D02*
X104257Y1591991D01*
X101326Y1592968D01*
X103280Y1594922D01*
G37*
G36*
G01X103095Y1607850D02*
X104072Y1604918D01*
X101140Y1605895D01*
X103095Y1607850D01*
G37*
G36*
G01X108422Y1627479D02*
X107040Y1624716D01*
X105658Y1627479D01*
X108422D01*
G37*
G36*
G01X106818Y1642717D02*
X105436Y1645481D01*
X108200D01*
X106818Y1642717D01*
G37*
G36*
G01X98120Y1687861D02*
X95120Y1686361D01*
Y1689361D01*
X98120Y1687861D01*
G37*
G36*
G01X98280Y1699061D02*
X95280Y1697561D01*
Y1700561D01*
X98280Y1699061D01*
G37*
G36*
G01X120286Y496572D02*
X117990D01*
X119138Y498868D01*
X120286Y496572D01*
G37*
G36*
G01X118196Y661887D02*
X119820Y660264D01*
X117384Y659452D01*
X118196Y661887D01*
G37*
G36*
G01X118224Y661899D02*
X119848Y660275D01*
X117413Y659463D01*
X118224Y661899D01*
G37*
G36*
G01D02*
X119848Y660275D01*
X117413Y659463D01*
X118224Y661899D01*
G37*
G36*
G01D02*
X119848Y660275D01*
X117413Y659463D01*
X118224Y661899D01*
G37*
G36*
G01X112737Y1266944D02*
X116028Y1265298D01*
X112737Y1263652D01*
Y1266944D01*
G37*
G36*
G01X142381Y1267132D02*
X145668Y1265488D01*
X142381Y1263844D01*
Y1267132D01*
G37*
G36*
G01X142154Y1403228D02*
X146154Y1401228D01*
X142154Y1399228D01*
Y1403228D01*
G37*
G36*
G01X147463Y410595D02*
X145463Y406595D01*
X143463Y410595D01*
X147463D01*
G37*
G36*
G01D02*
X145463Y406595D01*
X143463Y410595D01*
X147463D01*
G37*
G36*
G01D02*
X145463Y406595D01*
X143463Y410595D01*
X147463D01*
G37*
G36*
G01D02*
X145463Y406595D01*
X143463Y410595D01*
X147463D01*
G37*
G36*
G01X170301Y1324690D02*
G02X148647I-10827J0D01*
G01X170301D01*
G37*
G36*
G01X161299Y642289D02*
G03X188071I13386J0D01*
G01X161299D01*
G37*
G36*
G01X161007Y673433D02*
G03X187779I13386J0D01*
G01X161007D01*
G37*
G36*
G01X172029Y1267178D02*
X175548Y1265418D01*
X172029Y1263658D01*
Y1267178D01*
G37*
G36*
G01X194674Y1324715D02*
G02X173020I-10827J0D01*
G01X194674D01*
G37*
G36*
G01X167694Y1538930D02*
X165394D01*
Y1536630D01*
X167694D01*
Y1538930D01*
G37*
G36*
G01X165168Y1716759D02*
X167348Y1715467D01*
X165168Y1714299D01*
Y1716759D01*
G37*
G36*
G01X168252Y1724126D02*
X166072Y1725418D01*
X168252Y1726586D01*
Y1724126D01*
G37*
G36*
G01X180977Y1403208D02*
X184977Y1401208D01*
X180977Y1399208D01*
Y1403208D01*
G37*
G36*
G01X205043Y561977D02*
X207043Y565977D01*
X209043Y561977D01*
X205043D01*
G37*
G36*
G01D02*
X207043Y565977D01*
X209043Y561977D01*
X205043D01*
G37*
G36*
G01X205143Y595937D02*
X209143D01*
X207143Y599937D01*
X205143Y595937D01*
G37*
G36*
G01X205063Y629857D02*
X209063D01*
X207063Y633857D01*
X205063Y629857D01*
G37*
G36*
G01X201940Y676753D02*
X202680Y675272D01*
X201200D01*
X201940Y676753D01*
G37*
G36*
G01X201668Y1267126D02*
X205220Y1265350D01*
X201668Y1263574D01*
Y1267126D01*
G37*
G36*
G01X219074Y1324715D02*
G02X197420I-10827J0D01*
G01X219074D01*
G37*
G36*
G01X200237Y1416648D02*
G03Y1443420I0J13386D01*
G01Y1416648D01*
G37*
G36*
G01X221949Y453974D02*
Y449974D01*
X225949Y451974D01*
X221949Y453974D01*
G37*
G36*
G01X219913Y1731859D02*
Y1736565D01*
X224619Y1734212D01*
X219913Y1731859D01*
G37*
G36*
G01X237195Y161544D02*
X239959Y160162D01*
X237195Y158780D01*
Y161544D01*
G37*
G36*
G01X231377Y1266984D02*
X234668Y1265338D01*
X231377Y1263692D01*
Y1266984D01*
G37*
G36*
G01X256755Y142898D02*
X253991Y144280D01*
X256755Y145662D01*
Y142898D01*
G37*
G36*
G01X257019Y1459D02*
X261019D01*
X259019Y5459D01*
X257019Y1459D01*
G37*
G36*
G01X261799Y231192D02*
X265799Y229192D01*
X261799Y227192D01*
Y231192D01*
G37*
G36*
G01X286116Y579639D02*
G02X264462I-10827J0D01*
G01X286116D01*
G37*
G36*
G01Y603798D02*
G02X264462I-10827J0D01*
G01X286116D01*
G37*
G36*
G01Y627952D02*
G02X264462I-10827J0D01*
G01X286116D01*
G37*
G36*
G01Y652106D02*
G02X264462I-10827J0D01*
G01X286116D01*
G37*
G36*
G01X277331Y120978D02*
X279702Y118608D01*
X276146Y117422D01*
X277331Y120978D01*
G37*
G36*
G01X280338Y163390D02*
X278794Y160301D01*
X277250Y163390D01*
X280338D01*
G37*
G36*
G01X274189Y687087D02*
G02Y665433I0J-10827D01*
G01Y687087D01*
G37*
G36*
G01Y711241D02*
G02Y689587I0J-10827D01*
G01Y711241D01*
G37*
G36*
G01X305459Y85567D02*
Y82457D01*
X302459D01*
Y88567D01*
X308490D01*
Y85567D01*
X305459D01*
G37*
G36*
G01X298703Y590158D02*
X294703Y588158D01*
Y592158D01*
X298703Y590158D01*
G37*
G36*
G01X303441Y1341135D02*
X304855Y1336892D01*
X300612Y1338306D01*
X303441Y1341135D01*
G37*
G36*
G01X304380Y1363460D02*
X307197Y1361215D01*
X307301Y1364778D01*
X304380Y1363460D01*
G37*
G36*
G01X289163Y1735542D02*
X293163Y1733542D01*
X289163Y1731542D01*
Y1735542D01*
G37*
G36*
G01X324438Y143308D02*
X325899Y141941D01*
X326535Y144085D01*
X324438Y143308D01*
G37*
G36*
G01X332049Y225207D02*
X328939D01*
Y228207D01*
X335049D01*
Y222176D01*
X332049D01*
Y225207D01*
G37*
G36*
G01X328114Y381864D02*
X330878Y380482D01*
X328114Y379100D01*
Y381864D01*
G37*
G36*
G01Y369643D02*
X330878Y368261D01*
X328114Y366879D01*
Y369643D01*
G37*
G36*
G01X336832Y1317800D02*
X338246Y1313557D01*
X334003Y1314971D01*
X336832Y1317800D01*
G37*
G36*
G01X341054Y1341797D02*
X339054Y1337797D01*
X337054Y1341797D01*
X341054D01*
G37*
G36*
G01X340900Y131062D02*
Y129062D01*
X343900Y130062D01*
X340900Y131062D01*
G37*
G36*
G01X348960Y161052D02*
X347960Y159052D01*
X346960Y161052D01*
X348960D01*
G37*
G36*
G01X344851Y388413D02*
X347851Y389913D01*
Y386913D01*
X344851Y388413D01*
G37*
G36*
G01X345171Y400531D02*
X348171Y402031D01*
Y399031D01*
X345171Y400531D01*
G37*
G36*
G01X364507Y369341D02*
X361507Y367841D01*
Y370841D01*
X364507Y369341D01*
G37*
G36*
G01X361249Y396118D02*
X364013Y394736D01*
X361249Y393354D01*
Y396118D01*
G37*
G36*
G01X366657Y383775D02*
X365157Y386775D01*
X368157D01*
X366657Y383775D01*
G37*
G36*
G01X368566Y1304774D02*
X369980Y1300531D01*
X365738Y1301945D01*
X368566Y1304774D01*
G37*
G36*
G01X373368Y1327969D02*
X371368Y1323969D01*
X369368Y1327969D01*
X373368D01*
G37*
G36*
G01X366629Y1621812D02*
X368011Y1624576D01*
X369393Y1621812D01*
X366629D01*
G37*
G36*
G01X383920Y328143D02*
X386684Y326761D01*
X383920Y325379D01*
Y328143D01*
G37*
G36*
G01X376007Y400631D02*
X379007Y402131D01*
Y399131D01*
X376007Y400631D01*
G37*
G36*
G01X383867Y1678224D02*
X382485Y1675460D01*
X381103Y1678224D01*
X383867D01*
G37*
G36*
G01X390770Y161071D02*
X388330Y159851D01*
Y162291D01*
X390770Y161071D01*
G37*
G36*
G01X394406Y229367D02*
X393114Y227187D01*
X391946Y229367D01*
X394406D01*
G37*
G36*
G01X402415Y237785D02*
Y240785D01*
X405415Y239285D01*
X402415Y237785D01*
G37*
G36*
G01X390312Y372943D02*
X391289Y370012D01*
X388357Y370989D01*
X390312Y372943D01*
G37*
G36*
G01X394978Y386051D02*
X393596Y383287D01*
X392214Y386051D01*
X394978D01*
G37*
G36*
G01X395012Y398982D02*
X393630Y396218D01*
X392248Y398982D01*
X395012D01*
G37*
G36*
G01X395013Y411983D02*
X393631Y409219D01*
X392249Y411983D01*
X395013D01*
G37*
G36*
G01X391834Y1253612D02*
G02Y1231958I0J-10827D01*
G01Y1253612D01*
G37*
G36*
G01X400450Y1304389D02*
X401864Y1300146D01*
X397622Y1301560D01*
X400450Y1304389D01*
G37*
G36*
G01X405518Y1328121D02*
X403518Y1324121D01*
X401518Y1328121D01*
X405518D01*
G37*
G36*
G01X388145Y1341060D02*
G03Y1367832I0J13386D01*
G01Y1341060D01*
G37*
G36*
G01X404064Y1685987D02*
X402064Y1681987D01*
X400064Y1685987D01*
X404064D01*
G37*
G36*
G01X416234Y1253612D02*
G02Y1231958I0J-10827D01*
G01Y1253612D01*
G37*
G36*
G01X417911Y1341060D02*
G03Y1367832I0J13386D01*
G01Y1341060D01*
G37*
G36*
G01X413900Y1610177D02*
Y1612941D01*
X416664Y1611559D01*
X413900Y1610177D01*
G37*
G36*
G01X436604Y77697D02*
X434604Y73697D01*
X432604Y77697D01*
X436604D01*
G37*
G36*
G01X420100Y120793D02*
X422540Y122013D01*
Y119573D01*
X420100Y120793D01*
G37*
G36*
G01X422952Y373953D02*
X421570Y371189D01*
X420188Y373953D01*
X422952D01*
G37*
G36*
G01X422610Y387079D02*
X421228Y384315D01*
X419846Y387079D01*
X422610D01*
G37*
G36*
G01X422847Y413240D02*
X421465Y410476D01*
X420083Y413240D01*
X422847D01*
G37*
G36*
G01X422602Y399933D02*
X421220Y397169D01*
X419838Y399933D01*
X422602D01*
G37*
G36*
G01X432262Y1304968D02*
X433676Y1300725D01*
X429433Y1302139D01*
X432262Y1304968D01*
G37*
G36*
G01X437678Y1328163D02*
X435678Y1324163D01*
X433678Y1328163D01*
X437678D01*
G37*
G36*
G01X421090Y1545105D02*
X422930Y1544492D01*
X421704Y1543265D01*
X421090Y1545105D01*
G37*
G36*
G01X437239Y108602D02*
X439239Y107602D01*
X437239Y106602D01*
Y108602D01*
G37*
G36*
G01X440556Y1253612D02*
G02Y1231958I0J-10827D01*
G01Y1253612D01*
G37*
G36*
G01X448247Y1341060D02*
G03Y1367832I0J13386D01*
G01Y1341060D01*
G37*
G36*
G01X436735Y1427139D02*
X436135Y1425778D01*
X435545Y1427139D01*
X436735D01*
G37*
G36*
G01X436135Y1425778D02*
X435545Y1427139D01*
X436735D01*
X436135Y1425778D01*
G37*
G36*
G01X453635Y1558541D02*
X450871Y1559923D01*
X453635Y1561305D01*
Y1558541D01*
G37*
G36*
G01X437460Y1577334D02*
X438327Y1575599D01*
X436593D01*
X437460Y1577334D01*
G37*
G36*
G01D02*
X438327Y1575599D01*
X436593D01*
X437460Y1577334D01*
G37*
G36*
G01X465320Y226694D02*
Y229154D01*
X467500Y227862D01*
X465320Y226694D01*
G37*
G36*
G01X464577Y237873D02*
X469170Y239577D01*
X467777Y234880D01*
X464577Y237873D01*
G37*
G36*
G01X465121Y387649D02*
X462941Y388941D01*
X465121Y390109D01*
Y387649D01*
G37*
G36*
G01X460213Y462683D02*
X458921Y460503D01*
X457753Y462683D01*
X460213D01*
G37*
G36*
G01X457118Y543522D02*
Y539522D01*
X461118Y541522D01*
X457118Y543522D01*
G37*
G36*
G01X464956Y1253612D02*
G02Y1231958I0J-10827D01*
G01Y1253612D01*
G37*
G36*
G01X464357Y1305247D02*
X465771Y1301004D01*
X461528Y1302419D01*
X464357Y1305247D01*
G37*
G36*
G01X469498Y1328185D02*
X467498Y1324185D01*
X465498Y1328185D01*
X469498D01*
G37*
G36*
G01X463521Y1366276D02*
G03Y1393048I0J13386D01*
G01Y1366276D01*
G37*
G36*
G01X467485Y1569091D02*
X464721Y1570473D01*
X467485Y1571855D01*
Y1569091D01*
G37*
G36*
G01X464375Y1609805D02*
X461444Y1608828D01*
X462421Y1611759D01*
X464375Y1609805D01*
G37*
G36*
G01X458563Y1622565D02*
Y1617859D01*
X453857Y1620212D01*
X458563Y1622565D01*
G37*
G36*
G01X454419Y1648322D02*
X452919Y1651322D01*
X455919D01*
X454419Y1648322D01*
G37*
G36*
G01X471998Y156966D02*
X470706Y154786D01*
X469538Y156966D01*
X471998D01*
G37*
G36*
G01X475718Y304527D02*
Y301763D01*
X472954Y303145D01*
X475718Y304527D01*
G37*
G36*
G01X477621Y1340576D02*
G03Y1367348I0J13386D01*
G01Y1340576D01*
G37*
G36*
G01X482278Y1420085D02*
Y1416085D01*
X486278Y1418085D01*
X482278Y1420085D01*
G37*
G36*
G01X499070Y385219D02*
X500570Y388219D01*
X497570D01*
X499070Y385219D01*
G37*
G36*
G01X486670Y385112D02*
X488170Y388112D01*
X485170D01*
X486670Y385112D01*
G37*
G36*
G01X496862Y462542D02*
X495570Y460362D01*
X494402Y462542D01*
X496862D01*
G37*
G36*
G01X496372Y596967D02*
X498563Y601349D01*
X500754Y596967D01*
X496372D01*
G37*
G36*
G01X489356Y1253612D02*
G02Y1231958I0J-10827D01*
G01Y1253612D01*
G37*
G36*
G01X490450Y1309937D02*
X494450Y1307937D01*
X490450Y1305937D01*
Y1309937D01*
G37*
G36*
G01D02*
X494450Y1307937D01*
X490450Y1305937D01*
Y1309937D01*
G37*
G36*
G01X501804Y1341267D02*
X499804Y1337267D01*
X497804Y1341267D01*
X501804D01*
G37*
G36*
G01X484897Y1735722D02*
X488897Y1733722D01*
X484897Y1731722D01*
Y1735722D01*
G37*
G36*
G01X508888Y303777D02*
Y301013D01*
X506124Y302395D01*
X508888Y303777D01*
G37*
G36*
G01X515670Y385112D02*
X517170Y388112D01*
X514170D01*
X515670Y385112D01*
G37*
G36*
G01X513170Y414112D02*
X514670Y417112D01*
X511670D01*
X513170Y414112D01*
G37*
G36*
G01X539864Y1444874D02*
G02X513092I-13386J0D01*
G01X539864D01*
G37*
G36*
G01X524760Y132861D02*
Y135861D01*
X527760Y134361D01*
X524760Y132861D01*
G37*
G36*
G01Y150861D02*
Y153861D01*
X527760Y152361D01*
X524760Y150861D01*
G37*
G36*
G01X524215Y165785D02*
Y168785D01*
X527215Y167285D01*
X524215Y165785D01*
G37*
G36*
G01X526920Y185303D02*
X529684Y183921D01*
X526920Y182539D01*
Y185303D01*
G37*
G36*
G01X518085Y267491D02*
X520600Y272520D01*
X523115Y267491D01*
X518085D01*
G37*
G36*
G01X532170Y385112D02*
X533670Y388112D01*
X530670D01*
X532170Y385112D01*
G37*
G36*
G01X531612Y411830D02*
X534612Y410330D01*
Y413330D01*
X531612Y411830D01*
G37*
G36*
G01X521854Y474947D02*
X520854Y472947D01*
X519854Y474947D01*
X521854D01*
G37*
G36*
G01X523195Y1335637D02*
X527195Y1333637D01*
X523195Y1331637D01*
Y1335637D01*
G37*
G36*
G01X533722Y1364439D02*
X531722Y1360439D01*
X529722Y1364439D01*
X533722D01*
G37*
G36*
G01X548500Y311616D02*
X545500Y310116D01*
Y313116D01*
X548500Y311616D01*
G37*
G36*
G01X545266Y453693D02*
X543851Y452279D01*
X545973Y451572D01*
X545266Y453693D01*
G37*
G36*
G01X535370Y493680D02*
Y489680D01*
X539370Y491680D01*
X535370Y493680D01*
G37*
G36*
G01X548896Y1434639D02*
X551087Y1430257D01*
X546705D01*
X548896Y1434639D01*
G37*
G36*
G01X562510Y145791D02*
Y148791D01*
X565510Y147291D01*
X562510Y145791D01*
G37*
G36*
G01X567239Y260390D02*
X565239Y264390D01*
X569239D01*
X567239Y260390D01*
G37*
G36*
G01X555946Y1733752D02*
X553150Y1732354D01*
Y1735150D01*
X555946Y1733752D01*
G37*
G36*
G01X568879Y138652D02*
X571879D01*
X570379Y135652D01*
X568879Y138652D01*
G37*
G36*
G01X581040Y154575D02*
X585040Y152575D01*
X581040Y150575D01*
Y154575D01*
G37*
G36*
G01X583463Y172459D02*
X581463Y176459D01*
X585463D01*
X583463Y172459D01*
G37*
G36*
G01X569141Y396139D02*
X566961Y397431D01*
X569141Y398599D01*
Y396139D01*
G37*
G36*
G01X592507Y212308D02*
X593921Y208066D01*
X589678Y209480D01*
X592507Y212308D01*
G37*
G36*
G01X591715Y228626D02*
Y231626D01*
X594715Y230126D01*
X591715Y228626D01*
G37*
G36*
G01X597428Y426581D02*
X593428Y424581D01*
Y428581D01*
X597428Y426581D01*
G37*
G36*
G01X594146Y462829D02*
Y465593D01*
X596910Y464211D01*
X594146Y462829D01*
G37*
G36*
G01X596225Y490660D02*
X591982Y492074D01*
X594811Y494902D01*
X596225Y490660D01*
G37*
G36*
G01X598590Y513276D02*
X596536Y514303D01*
X598590Y515330D01*
Y513276D01*
G37*
G36*
G01X609263Y260278D02*
X608396Y262013D01*
X610130D01*
X609263Y260278D01*
G37*
G36*
G01X627474Y159501D02*
X628680Y163120D01*
X631092Y160708D01*
X627474Y159501D01*
G37*
G36*
G01X624772Y288661D02*
X628772Y290661D01*
Y286661D01*
X624772Y288661D01*
G37*
G36*
G01X615820Y1267420D02*
Y1263420D01*
X619820Y1265420D01*
X615820Y1267420D01*
G37*
G36*
G01X645520D02*
Y1263420D01*
X649520Y1265420D01*
X645520Y1267420D01*
G37*
G36*
G01X665573Y408958D02*
X673054D01*
Y405958D01*
X662573D01*
Y416439D01*
X665573D01*
Y408958D01*
G37*
G36*
G01D02*
X673054D01*
Y405958D01*
X662573D01*
Y416439D01*
X665573D01*
Y408958D01*
G37*
G36*
G01D02*
X673054D01*
Y405958D01*
X662573D01*
Y416439D01*
X665573D01*
Y408958D01*
G37*
G36*
G01X662146Y514057D02*
X659170Y513226D01*
X660291Y516106D01*
X662146Y514057D01*
G37*
G36*
G01D02*
X659170Y513226D01*
X660291Y516106D01*
X662146Y514057D01*
G37*
G36*
G01X683920Y1324715D02*
G02X662266I-10827J0D01*
G01X683920D01*
G37*
G36*
G01X656493Y1402893D02*
X660493Y1400893D01*
X656493Y1398893D01*
Y1402893D01*
G37*
G36*
G01X650517Y1688374D02*
X649225Y1686194D01*
X648057Y1688374D01*
X650517D01*
G37*
G36*
G01X651059Y1725852D02*
X649559Y1728852D01*
X652559D01*
X651059Y1725852D01*
G37*
G36*
G01D02*
X649559Y1728852D01*
X652559D01*
X651059Y1725852D01*
G37*
G36*
G01X676519Y1267128D02*
X679918Y1265428D01*
X676519Y1263728D01*
Y1267128D01*
G37*
G36*
G01X682782Y1621900D02*
X678400Y1619709D01*
Y1624091D01*
X682782Y1621900D01*
G37*
G36*
G01X673496Y1661320D02*
X676260Y1659938D01*
X673496Y1658556D01*
Y1661320D01*
G37*
G36*
G01X674489Y1676052D02*
X672989Y1679052D01*
X675989D01*
X674489Y1676052D01*
G37*
G36*
G01X708293Y1324740D02*
G02X686639I-10827J0D01*
G01X708293D01*
G37*
G36*
G01X694306Y1403073D02*
X698306Y1401073D01*
X694306Y1399073D01*
Y1403073D01*
G37*
G36*
G01X680010Y1629810D02*
X681392Y1632574D01*
X682774Y1629810D01*
X680010D01*
G37*
G36*
G01D02*
X681392Y1632574D01*
X682774Y1629810D01*
X680010D01*
G37*
G36*
G01X701711Y21597D02*
X705711D01*
X703711Y25597D01*
X701711Y21597D01*
G37*
G36*
G01X705781Y124728D02*
X709133D01*
X707457Y121375D01*
X705781Y124728D01*
G37*
G36*
G01X705012Y219653D02*
X701012Y221653D01*
X705012Y223653D01*
Y219653D01*
G37*
G36*
G01X706033Y1266966D02*
X709208Y1265378D01*
X706033Y1263790D01*
Y1266966D01*
G37*
G36*
G01X732693Y1324740D02*
G02X711039I-10827J0D01*
G01X732693D01*
G37*
G36*
G01X711918Y1627456D02*
X711919Y1623456D01*
X715918Y1625456D01*
X711918Y1627456D01*
G37*
G36*
G01X713716Y1416193D02*
G03Y1442965I0J13386D01*
G01Y1416193D01*
G37*
G36*
G01X715013Y1667701D02*
X712833Y1668993D01*
X715013Y1670161D01*
Y1667701D01*
G37*
G36*
G01D02*
X712833Y1668993D01*
X715013Y1670161D01*
Y1667701D01*
G37*
G36*
G01X740035Y105052D02*
Y101942D01*
X737035D01*
Y108052D01*
X743066D01*
Y105052D01*
X740035D01*
G37*
G36*
G01X735691Y1267382D02*
X738918Y1265768D01*
X735691Y1264154D01*
Y1267382D01*
G37*
G36*
G01X742575Y1596321D02*
X740575Y1600321D01*
X744575D01*
X742575Y1596321D01*
G37*
G36*
G01X772576Y164982D02*
X770873Y167561D01*
X773958Y167376D01*
X772576Y164982D01*
G37*
G36*
G01X771842Y280228D02*
X767599Y278814D01*
X769013Y283056D01*
X771842Y280228D01*
G37*
G36*
G01X772700Y453162D02*
X770700Y449162D01*
X768700Y453162D01*
X772700D01*
G37*
G36*
G01X765309Y1267028D02*
X768728Y1265318D01*
X765309Y1263608D01*
Y1267028D01*
G37*
G36*
G01X763013Y1718140D02*
X762013Y1716140D01*
X761013Y1718140D01*
X763013D01*
G37*
G36*
G01X794060Y365030D02*
X798060D01*
X796060Y369030D01*
X794060Y365030D01*
G37*
G36*
G01X794993Y1267326D02*
X798428Y1265608D01*
X794993Y1263890D01*
Y1267326D01*
G37*
G36*
G01X800108Y1572313D02*
X798694Y1576556D01*
X802936Y1575142D01*
X800108Y1572313D01*
G37*
G36*
G01D02*
X798694Y1576556D01*
X802936Y1575142D01*
X800108Y1572313D01*
G37*
G36*
G01X814593Y128433D02*
X818836Y129847D01*
X817422Y125605D01*
X814593Y128433D01*
G37*
G36*
G01X814624Y268316D02*
Y271080D01*
X817388Y269698D01*
X814624Y268316D01*
G37*
G36*
G01X824617Y1267344D02*
X828148Y1265578D01*
X824617Y1263812D01*
Y1267344D01*
G37*
G36*
G01X837828Y99070D02*
X832628Y97170D01*
Y101570D01*
X837828Y99070D01*
G37*
G36*
G01X837760Y218652D02*
X840457Y217304D01*
X837760Y215956D01*
Y218652D01*
G37*
G36*
G01X835041Y394620D02*
Y398620D01*
X839041Y396620D01*
X835041Y394620D01*
G37*
G36*
G01X832014Y426155D02*
X832813Y428553D01*
X830416Y427753D01*
X832014Y426155D01*
G37*
G36*
G01X843474Y470815D02*
X841739Y471682D01*
X843474Y472549D01*
Y470815D01*
G37*
G36*
G01X836373Y523098D02*
X839403D01*
X837888Y520068D01*
X836373Y523098D01*
G37*
G36*
G01D02*
X839403D01*
X837888Y520068D01*
X836373Y523098D01*
G37*
G36*
G01X834568Y532719D02*
X833723Y534254D01*
X835412D01*
X834568Y532719D01*
G37*
G36*
G01X842366Y1571946D02*
X840952Y1576189D01*
X845194Y1574775D01*
X842366Y1571946D01*
G37*
G36*
G01D02*
X840952Y1576189D01*
X845194Y1574775D01*
X842366Y1571946D01*
G37*
G36*
G01X849168Y87128D02*
X847876Y84948D01*
X846708Y87128D01*
X849168D01*
G37*
G36*
G01X856979Y405938D02*
X860192Y404866D01*
X858050Y402724D01*
X856979Y405938D01*
G37*
G36*
G01X847181Y497350D02*
X849181Y493350D01*
X845181D01*
X847181Y497350D01*
G37*
G36*
G01X862385Y168064D02*
X864825Y169284D01*
Y166844D01*
X862385Y168064D01*
G37*
G36*
G01X866345Y283111D02*
Y280001D01*
X863345D01*
Y286111D01*
X869376D01*
Y283111D01*
X866345D01*
G37*
G36*
G01X874953Y885276D02*
Y888276D01*
X877953Y886776D01*
X874953Y885276D01*
G37*
G36*
G01X884379Y1572253D02*
X882965Y1576496D01*
X887208Y1575082D01*
X884379Y1572253D01*
G37*
G36*
G01D02*
X882965Y1576496D01*
X887208Y1575082D01*
X884379Y1572253D01*
G37*
G36*
G01X907079Y159516D02*
X903752Y162843D01*
X908742Y164507D01*
X907079Y159516D01*
G37*
G36*
G01X938740Y482433D02*
X937326Y486675D01*
X941568Y485261D01*
X938740Y482433D01*
G37*
G36*
G01X937160Y980663D02*
X934860D01*
Y978363D01*
X937160D01*
Y980663D01*
G37*
G36*
G01X931290Y1524166D02*
X935290D01*
X933290Y1528166D01*
X931290Y1524166D01*
G37*
G36*
G01X927579Y1573312D02*
X926164Y1577554D01*
X930407Y1576140D01*
X927579Y1573312D01*
G37*
G36*
G01D02*
X926164Y1577554D01*
X930407Y1576140D01*
X927579Y1573312D01*
G37*
G36*
G01X940780Y1734190D02*
X936780D01*
X938780Y1730190D01*
X940780Y1734190D01*
G37*
G36*
G01X946404Y1555364D02*
X944754Y1551264D01*
X947904D01*
X946404Y1555364D01*
G37*
G36*
G01X963174Y977250D02*
X966585Y978955D01*
Y975544D01*
X963174Y977250D01*
G37*
G36*
G01X969770Y1555364D02*
X968120Y1551264D01*
X971270D01*
X969770Y1555364D01*
G37*
G36*
G01X987399Y352411D02*
Y349000D01*
X983988Y350706D01*
X987399Y352411D01*
G37*
G36*
G01X985325Y406776D02*
Y402776D01*
X989325Y404776D01*
X985325Y406776D01*
G37*
G36*
G01X999499Y168541D02*
X996389D01*
Y171541D01*
X1002499D01*
Y165510D01*
X999499D01*
Y168541D01*
G37*
G36*
G01X1002948Y1266410D02*
X998948Y1264410D01*
Y1268410D01*
X1002948Y1266410D01*
G37*
G36*
G01X993136Y1555364D02*
X991486Y1551264D01*
X994636D01*
X993136Y1555364D01*
G37*
G36*
G01X1009720Y187136D02*
X1006817Y185460D01*
X1006592Y189201D01*
X1009720Y187136D01*
G37*
G36*
G01X1016502Y1555364D02*
X1014852Y1551264D01*
X1018002D01*
X1016502Y1555364D01*
G37*
G36*
G01X1035717Y163357D02*
X1031335Y161166D01*
Y165548D01*
X1035717Y163357D01*
G37*
G36*
G01X1039101Y294150D02*
X1035101D01*
X1037101Y290150D01*
X1039101Y294150D01*
G37*
G36*
G01X1029488Y1267416D02*
X1032988Y1265666D01*
X1029488Y1263916D01*
Y1267416D01*
G37*
G36*
G01X1050687Y163131D02*
X1047810Y161692D01*
Y164570D01*
X1050687Y163131D01*
G37*
G36*
G01X1039868Y1555364D02*
X1038218Y1551264D01*
X1041368D01*
X1039868Y1555364D01*
G37*
G36*
G01X1069009Y509790D02*
X1071449Y511010D01*
Y508570D01*
X1069009Y509790D01*
G37*
G36*
G01X1059106Y1267632D02*
X1062538Y1265916D01*
X1059106Y1264200D01*
Y1267632D01*
G37*
G36*
G01X1063234Y1555364D02*
X1061584Y1551264D01*
X1064734D01*
X1063234Y1555364D01*
G37*
G36*
G01X1074349Y64162D02*
X1076349Y63162D01*
X1074349Y62162D01*
Y64162D01*
G37*
G36*
G01X1086600Y1555364D02*
X1084950Y1551264D01*
X1088100D01*
X1086600Y1555364D01*
G37*
G36*
G01X1100151Y70819D02*
X1102151Y66819D01*
X1098151D01*
X1100151Y70819D01*
G37*
G36*
G01X1111627Y255425D02*
G02X1089973I-10827J0D01*
G01X1111627D01*
G37*
G36*
G01X1111527Y279725D02*
G02X1089873I-10827J0D01*
G01X1111527D01*
G37*
G36*
G01X1088938Y1267596D02*
X1092938Y1265596D01*
X1088938Y1263596D01*
Y1267596D01*
G37*
G36*
G01X1090295Y1650037D02*
X1087265Y1648523D01*
Y1651552D01*
X1090295Y1650037D01*
G37*
G36*
G01X1089870Y1724761D02*
X1094252Y1722570D01*
X1089870Y1720379D01*
Y1724761D01*
G37*
G36*
G01X1110643Y387417D02*
X1108643Y383417D01*
X1106643Y387417D01*
X1110643D01*
G37*
G36*
G01X1118546Y1267402D02*
X1121978Y1265686D01*
X1118546Y1263970D01*
Y1267402D01*
G37*
G36*
G01X1130845Y69926D02*
X1134845Y67926D01*
X1130845Y65926D01*
Y69926D01*
G37*
G36*
G01X1141927Y1361025D02*
G02X1120273I-10827J0D01*
G01X1141927D01*
G37*
G36*
G01X1128245Y1442087D02*
X1126245Y1438087D01*
X1124245Y1442087D01*
X1128245D01*
G37*
G36*
G01X1131338Y1630209D02*
X1132315Y1627277D01*
X1129383Y1628254D01*
X1131338Y1630209D01*
G37*
G36*
G01X1150822Y191567D02*
X1152204Y194331D01*
X1153586Y191567D01*
X1150822D01*
G37*
G36*
G01X1148188Y1267846D02*
X1151768Y1266056D01*
X1148188Y1264266D01*
Y1267846D01*
G37*
G36*
G01X1166327Y1361025D02*
G02X1144673I-10827J0D01*
G01X1166327D01*
G37*
G36*
G01X1157204Y235217D02*
X1155822Y232453D01*
X1154440Y235217D01*
X1157204D01*
G37*
G36*
G01X1166575Y1442624D02*
X1164575Y1438624D01*
X1162575Y1442624D01*
X1166575D01*
G37*
G36*
G01X1166081Y1631716D02*
X1163252Y1628887D01*
X1167495Y1627473D01*
X1166081Y1631716D01*
G37*
G36*
G01X1166619Y1660435D02*
X1168001Y1663199D01*
X1169383Y1660435D01*
X1166619D01*
G37*
G36*
G01X1154800Y1662383D02*
X1157731Y1663360D01*
X1156754Y1660429D01*
X1154800Y1662383D01*
G37*
G36*
G01X1177954Y1267518D02*
X1181538Y1265726D01*
X1177954Y1263934D01*
Y1267518D01*
G37*
G36*
G01X1190727Y1361025D02*
G02X1169073I-10827J0D01*
G01X1190727D01*
G37*
G36*
G01X1173548Y1452977D02*
G03Y1479749I0J13386D01*
G01Y1452977D01*
G37*
G36*
G01X1175150Y1553366D02*
X1171150D01*
X1173150Y1549366D01*
X1175150Y1553366D01*
G37*
G36*
G01X1177589Y1659945D02*
X1178971Y1662709D01*
X1180353Y1659945D01*
X1177589D01*
G37*
G36*
G01X1188279Y1660285D02*
X1189661Y1663049D01*
X1191043Y1660285D01*
X1188279D01*
G37*
G36*
G01X1187063Y1707652D02*
X1189994Y1708629D01*
X1189017Y1705698D01*
X1187063Y1707652D01*
G37*
G36*
G01X1199209Y1706120D02*
X1200591Y1708884D01*
X1201973Y1706120D01*
X1199209D01*
G37*
G36*
G01X1201600Y109540D02*
Y105540D01*
X1205600Y107540D01*
X1201600Y109540D01*
G37*
G36*
G01X1204670Y227237D02*
X1201670Y225737D01*
Y228737D01*
X1204670Y227237D01*
G37*
G36*
G01X1207416Y1267352D02*
X1210948Y1265586D01*
X1207416Y1263820D01*
Y1267352D01*
G37*
G36*
G01X1207898Y1658940D02*
X1208765Y1657205D01*
X1207031D01*
X1207898Y1658940D01*
G37*
G36*
G01X1210079Y1705825D02*
X1211461Y1708589D01*
X1212843Y1705825D01*
X1210079D01*
G37*
G36*
G01X1232098Y48711D02*
X1233098Y50711D01*
X1234098Y48711D01*
X1232098D01*
G37*
G36*
G01X1228308Y1735592D02*
X1232308Y1733592D01*
X1228308Y1731592D01*
Y1735592D01*
G37*
G36*
G01X1283070Y230748D02*
X1280070D01*
Y239025D01*
X1288347D01*
Y236025D01*
X1283070D01*
Y230748D01*
G37*
G36*
G01D02*
X1280070D01*
Y239025D01*
X1288347D01*
Y236025D01*
X1283070D01*
Y230748D01*
G37*
G36*
G01X1281735Y1340871D02*
X1283149Y1336628D01*
X1278907Y1338043D01*
X1281735Y1340871D01*
G37*
G36*
G01X1285318Y1364624D02*
X1283318Y1360624D01*
X1281318Y1364624D01*
X1285318D01*
G37*
G36*
G01X1295927Y1735922D02*
X1299927Y1733922D01*
X1295927Y1731922D01*
Y1735922D01*
G37*
G36*
G01X1299356Y59756D02*
X1300450Y63037D01*
X1302637Y60850D01*
X1299356Y59756D01*
G37*
G36*
G01X1303451Y268433D02*
X1299151Y266533D01*
Y270733D01*
X1303451Y268433D01*
G37*
G36*
G01X1313484Y1317842D02*
X1314898Y1313599D01*
X1310655Y1315014D01*
X1313484Y1317842D01*
G37*
G36*
G01X1317164Y1341466D02*
X1315164Y1337466D01*
X1313164Y1341466D01*
X1317164D01*
G37*
G36*
G01X1319662Y95699D02*
X1322484Y94679D01*
X1320053Y92368D01*
X1319662Y95699D01*
G37*
G36*
G01X1335416Y82255D02*
Y79255D01*
X1332416Y80755D01*
X1335416Y82255D01*
G37*
G36*
G01X1344956Y1305195D02*
X1346370Y1300952D01*
X1342128Y1302367D01*
X1344956Y1305195D01*
G37*
G36*
G01X1349288Y1328018D02*
X1347288Y1324018D01*
X1345288Y1328018D01*
X1349288D01*
G37*
G36*
G01X1360964Y1536254D02*
X1360837Y1537664D01*
X1357711Y1534436D01*
X1357061Y1534386D01*
X1356561Y1534936D01*
X1360696Y1539234D01*
X1360207Y1544664D01*
X1356361Y1548636D01*
X1356611Y1549336D01*
X1357311Y1549436D01*
X1360032Y1546608D01*
X1359924Y1547804D01*
X1361164Y1548804D01*
X1362164Y1548854D01*
X1363114Y1549304D01*
X1365264D01*
X1365814Y1549054D01*
X1366964Y1548204D01*
X1367164D01*
X1367564Y1548604D01*
X1368364Y1548504D01*
X1368714Y1548104D01*
Y1547568D01*
X1370511Y1549436D01*
X1371211Y1549336D01*
X1371461Y1548636D01*
X1368714Y1545799D01*
Y1544754D01*
X1368464Y1544454D01*
X1367864D01*
X1367268Y1539087D01*
X1367362Y1538989D01*
X1367414Y1538954D01*
G02X1368037Y1538287I-1089J-1641D01*
G01X1371261Y1534936D01*
X1370761Y1534386D01*
X1370111Y1534436D01*
X1368117Y1536495D01*
G02X1364664Y1536254I-1792J818D01*
G01X1360964D01*
G37*
G36*
G01X1367975Y1253612D02*
G02Y1231958I0J-10827D01*
G01Y1253612D01*
G37*
G36*
G01X1376529Y1305075D02*
X1377944Y1300832D01*
X1373701Y1302246D01*
X1376529Y1305075D01*
G37*
G36*
G01X1381448Y1328070D02*
X1379448Y1324070D01*
X1377448Y1328070D01*
X1381448D01*
G37*
G36*
G01X1364286Y1340560D02*
G03Y1367332I0J13386D01*
G01Y1340560D01*
G37*
G36*
G01X1392375Y1253612D02*
G02Y1231958I0J-10827D01*
G01Y1253612D01*
G37*
G36*
G01X1394052Y1340560D02*
G03Y1367332I0J13386D01*
G01Y1340560D01*
G37*
G36*
G01X1409086Y1304910D02*
X1410500Y1300667D01*
X1406258Y1302081D01*
X1409086Y1304910D01*
G37*
G36*
G01X1413428Y1327982D02*
X1411428Y1323982D01*
X1409428Y1327982D01*
X1413428D01*
G37*
G36*
G01X1404434Y1591974D02*
X1406389Y1593929D01*
X1407366Y1590997D01*
X1404434Y1591974D01*
G37*
G36*
G01X1406075Y1605841D02*
X1404340Y1604974D01*
Y1606708D01*
X1406075Y1605841D01*
G37*
G36*
G01X1410700Y1638539D02*
Y1641303D01*
X1413464Y1639921D01*
X1410700Y1638539D01*
G37*
G36*
G01X1416697Y1253612D02*
G02Y1231958I0J-10827D01*
G01Y1253612D01*
G37*
G36*
G01X1424388Y1340560D02*
G03Y1367332I0J13386D01*
G01Y1340560D01*
G37*
G36*
G01X1412876Y1427139D02*
X1412276Y1425778D01*
X1411686Y1427139D01*
X1412876D01*
G37*
G36*
G01X1412276Y1425778D02*
X1411686Y1427139D01*
X1412876D01*
X1412276Y1425778D01*
G37*
G36*
G01X1427733Y1525476D02*
X1430497Y1524094D01*
X1427733Y1522712D01*
Y1525476D01*
G37*
G36*
G01X1425585Y1574831D02*
X1424293Y1572651D01*
X1423125Y1574831D01*
X1425585D01*
G37*
G36*
G01X1427915Y1593360D02*
X1425915Y1597360D01*
X1429915D01*
X1427915Y1593360D01*
G37*
G36*
G01X1430703Y239240D02*
X1432883Y237948D01*
X1430703Y236780D01*
Y239240D01*
G37*
G36*
G01D02*
X1432883Y237948D01*
X1430703Y236780D01*
Y239240D01*
G37*
G36*
G01X1430200Y267734D02*
X1432380Y266442D01*
X1430200Y265274D01*
Y267734D01*
G37*
G36*
G01D02*
X1432380Y266442D01*
X1430200Y265274D01*
Y267734D01*
G37*
G36*
G01D02*
X1432380Y266442D01*
X1430200Y265274D01*
Y267734D01*
G37*
G36*
G01D02*
X1432380Y266442D01*
X1430200Y265274D01*
Y267734D01*
G37*
G36*
G01X1441097Y1253612D02*
G02Y1231958I0J-10827D01*
G01Y1253612D01*
G37*
G36*
G01X1441571Y1304548D02*
X1442986Y1300305D01*
X1438743Y1301720D01*
X1441571Y1304548D01*
G37*
G36*
G01X1445868Y1328114D02*
X1443868Y1324114D01*
X1441868Y1328114D01*
X1445868D01*
G37*
G36*
G01X1439121Y1365976D02*
G03Y1392748I0J13386D01*
G01Y1365976D01*
G37*
G36*
G01X1428123Y1552516D02*
X1430887Y1551134D01*
X1428123Y1549752D01*
Y1552516D01*
G37*
G36*
G01X1427973Y1541296D02*
X1430737Y1539914D01*
X1427973Y1538532D01*
Y1541296D01*
G37*
G36*
G01X1432547Y1621720D02*
X1430592Y1619766D01*
X1429615Y1622698D01*
X1432547Y1621720D01*
G37*
G36*
G01X1451934Y379747D02*
X1454114Y378455D01*
X1451934Y377287D01*
Y379747D01*
G37*
G36*
G01X1454154Y1340560D02*
G03Y1367332I0J13386D01*
G01Y1340560D01*
G37*
G36*
G01X1458419Y1420011D02*
Y1416011D01*
X1462419Y1418011D01*
X1458419Y1420011D01*
G37*
G36*
G01X1446694Y1611204D02*
X1448648Y1613159D01*
X1449626Y1610227D01*
X1446694Y1611204D01*
G37*
G36*
G01X1465552Y54170D02*
X1466966Y55584D01*
X1464138Y56999D01*
X1465552Y54170D01*
G37*
G36*
G01X1465497Y1253612D02*
G02Y1231958I0J-10827D01*
G01Y1253612D01*
G37*
G36*
G01X1467361Y1309257D02*
X1471361Y1307257D01*
X1467361Y1305257D01*
Y1309257D01*
G37*
G36*
G01X1477824Y1341566D02*
X1475824Y1337566D01*
X1473824Y1341566D01*
X1477824D01*
G37*
G36*
G01X1469048Y1683042D02*
X1467757Y1680459D01*
X1466466Y1683042D01*
X1469048D01*
G37*
G36*
G01X1516342Y1444452D02*
G02X1489570I-13386J0D01*
G01X1516342D01*
G37*
G36*
G01X1492441Y1736212D02*
X1496441Y1734212D01*
X1492441Y1732212D01*
Y1736212D01*
G37*
G36*
G01X1498646Y400966D02*
X1496466Y402258D01*
X1498646Y403426D01*
Y400966D01*
G37*
G36*
G01X1499926Y1335717D02*
X1503926Y1333717D01*
X1499926Y1331717D01*
Y1335717D01*
G37*
G36*
G01X1509922Y1364368D02*
X1507922Y1360368D01*
X1505922Y1364368D01*
X1509922D01*
G37*
G36*
G01X1518921Y296879D02*
X1520761Y296265D01*
X1519534Y295038D01*
X1518921Y296879D01*
G37*
G36*
G01X1526923Y106622D02*
X1528923Y105622D01*
X1526923Y104622D01*
Y106622D01*
G37*
G36*
G01X1542401Y135387D02*
X1543401Y133387D01*
X1541401D01*
X1542401Y135387D01*
G37*
G36*
G01X1531100Y121122D02*
Y123122D01*
X1529100Y122122D01*
X1531100Y121122D01*
G37*
G36*
G01X1538324Y252952D02*
X1534724Y251202D01*
Y254602D01*
X1538324Y252952D01*
G37*
G36*
G01X1587827Y595825D02*
G02X1566173I-10827J0D01*
G01X1587827D01*
G37*
G36*
G01X1561206Y623764D02*
Y620764D01*
X1558206Y622264D01*
X1561206Y623764D01*
G37*
G36*
G01X1587827Y620325D02*
G02X1566173I-10827J0D01*
G01X1587827D01*
G37*
G36*
G01Y644825D02*
G02X1566173I-10827J0D01*
G01X1587827D01*
G37*
G36*
G01Y669225D02*
G02X1566173I-10827J0D01*
G01X1587827D01*
G37*
G36*
G01Y693725D02*
G02X1566173I-10827J0D01*
G01X1587827D01*
G37*
G36*
G01Y718225D02*
G02X1566173I-10827J0D01*
G01X1587827D01*
G37*
G36*
G01X1563710Y1733902D02*
X1560690Y1732392D01*
Y1735412D01*
X1563710Y1733902D01*
G37*
G36*
G01X1595890Y1265810D02*
X1591890Y1263810D01*
Y1267810D01*
X1595890Y1265810D01*
G37*
G36*
G01X1615466Y167155D02*
X1613466Y163155D01*
X1611466Y167155D01*
X1615466D01*
G37*
G36*
G01X1621948Y1267306D02*
X1625948Y1265306D01*
X1621948Y1263306D01*
Y1267306D01*
G37*
G36*
G01X1645086Y1358311D02*
G02X1623432I-10827J0D01*
G01X1645086D01*
G37*
G36*
G01X1629887Y1439903D02*
X1627887Y1435903D01*
X1625887Y1439903D01*
X1629887D01*
G37*
G36*
G01D02*
X1627887Y1435903D01*
X1625887Y1439903D01*
X1629887D01*
G37*
G36*
G01X1648179Y420976D02*
X1649593Y416734D01*
X1645350Y418148D01*
X1648179Y420976D01*
G37*
G36*
G01X1655671Y613249D02*
X1654925Y611756D01*
X1654178Y613249D01*
X1655671D01*
G37*
G36*
G01X1646710Y655275D02*
X1644710Y659275D01*
X1648710D01*
X1646710Y655275D01*
G37*
G36*
G01X1646640Y689125D02*
X1644640Y693125D01*
X1648640D01*
X1646640Y689125D01*
G37*
G36*
G01X1648298Y725952D02*
X1646890Y723135D01*
X1645482Y725952D01*
X1648298D01*
G37*
G36*
G01X1652436Y1267072D02*
X1655748Y1265416D01*
X1652436Y1263760D01*
Y1267072D01*
G37*
G36*
G01X1669459Y1358336D02*
G02X1647805I-10827J0D01*
G01X1669459D01*
G37*
G36*
G01X1667769Y523269D02*
X1668917Y525565D01*
X1670065Y523269D01*
X1667769D01*
G37*
G36*
G01X1669496Y623096D02*
G03X1696268I13386J0D01*
G01X1669496D01*
G37*
G36*
G01Y674031D02*
G03X1696268I13386J0D01*
G01X1669496D01*
G37*
G36*
G01X1667837Y1439650D02*
X1665837Y1435650D01*
X1663837Y1439650D01*
X1667837D01*
G37*
G36*
G01D02*
X1665837Y1435650D01*
X1663837Y1439650D01*
X1667837D01*
G37*
G36*
G01X1681456Y186029D02*
X1679456Y182029D01*
X1677456Y186029D01*
X1681456D01*
G37*
G36*
G01X1682010Y1267010D02*
X1685470Y1265280D01*
X1682010Y1263550D01*
Y1267010D01*
G37*
G36*
G01X1693859Y1358336D02*
G02X1672205I-10827J0D01*
G01X1693859D01*
G37*
G36*
G01X1675022Y1450269D02*
G03Y1477041I0J13386D01*
G01Y1450269D01*
G37*
G36*
G01X1683571Y1509014D02*
X1682189Y1506250D01*
X1680807Y1509014D01*
X1683571D01*
G37*
G36*
G01X1683231Y1528734D02*
X1681849Y1525970D01*
X1680467Y1528734D01*
X1683231D01*
G37*
G36*
G01X1683331Y1549814D02*
X1681949Y1547050D01*
X1680567Y1549814D01*
X1683331D01*
G37*
G36*
G01X1683200Y1569234D02*
X1681818Y1566470D01*
X1680436Y1569234D01*
X1683200D01*
G37*
G36*
G01D02*
X1681818Y1566470D01*
X1680436Y1569234D01*
X1683200D01*
G37*
G36*
G01D02*
X1681818Y1566470D01*
X1680436Y1569234D01*
X1683200D01*
G37*
G36*
G01D02*
X1681818Y1566470D01*
X1680436Y1569234D01*
X1683200D01*
G37*
G36*
G01X1683100Y1589334D02*
X1681718Y1586570D01*
X1680336Y1589334D01*
X1683100D01*
G37*
G36*
G01X1704208Y421643D02*
X1701098D01*
Y424643D01*
X1707208D01*
Y418612D01*
X1704208D01*
Y421643D01*
G37*
G36*
G01X1692384Y472965D02*
X1694819Y473777D01*
X1694008Y471342D01*
X1692384Y472965D01*
G37*
G36*
G01X1699336Y718378D02*
X1696154Y719439D01*
X1698275Y721560D01*
X1699336Y718378D01*
G37*
G36*
G01X1710935Y228085D02*
X1709435Y232185D01*
X1712585D01*
X1710935Y228085D01*
G37*
G36*
G01X1711906Y1267084D02*
X1715014Y1265530D01*
X1711906Y1263976D01*
Y1267084D01*
G37*
G36*
G01X1731878Y859D02*
X1735878D01*
X1733878Y4859D01*
X1731878Y859D01*
G37*
G36*
G01X1725445Y398559D02*
X1726859Y397144D01*
X1727566Y399266D01*
X1725445Y398559D01*
G37*
G36*
G01X1729701Y1461501D02*
X1731201Y1457401D01*
X1728051D01*
X1729701Y1461501D01*
G37*
G36*
G01X1747746Y121727D02*
X1751098D01*
X1749422Y118374D01*
X1747746Y121727D01*
G37*
G36*
G01X1738010Y161597D02*
X1742010Y159597D01*
X1738010Y157597D01*
Y161597D01*
G37*
G36*
G01X1740210Y180001D02*
X1737770Y178781D01*
Y181221D01*
X1740210Y180001D01*
G37*
G36*
G01X1753180Y296996D02*
X1754443Y296365D01*
X1753180Y295734D01*
Y296996D01*
G37*
G36*
G01X1743820Y366448D02*
X1742014Y367351D01*
X1743820Y368254D01*
Y366448D01*
G37*
G36*
G01X1741452Y1267098D02*
X1744848Y1265400D01*
X1741452Y1263702D01*
Y1267098D01*
G37*
G36*
G01X1744866Y1330851D02*
X1742866Y1326851D01*
X1740866Y1330851D01*
X1744866D01*
G37*
G36*
G01X1770580Y86691D02*
Y83581D01*
X1767580D01*
Y89691D01*
X1773611D01*
Y86691D01*
X1770580D01*
G37*
G36*
G01X1783176Y199711D02*
G02X1756404I-13386J0D01*
G01X1783176D01*
G37*
G36*
G01X1783248Y154642D02*
Y157082D01*
X1785688Y155862D01*
X1783248Y154642D01*
G37*
G36*
G01X1773150Y456862D02*
X1772150Y458862D01*
X1774150D01*
X1773150Y456862D01*
G37*
G36*
G01X1783362Y469092D02*
Y465092D01*
X1787362Y467092D01*
X1783362Y469092D01*
G37*
G36*
G01X1771264Y1267078D02*
X1774540Y1265440D01*
X1771264Y1263802D01*
Y1267078D01*
G37*
G36*
G01X1777175Y1624646D02*
X1781557Y1626837D01*
Y1622455D01*
X1777175Y1624646D01*
G37*
G36*
G01X1812736Y199711D02*
G02X1785964I-13386J0D01*
G01X1812736D01*
G37*
G36*
G01X1802547Y371171D02*
X1798547Y369171D01*
Y373171D01*
X1802547Y371171D01*
G37*
G36*
G01X1796004Y410615D02*
X1794269Y409748D01*
Y411482D01*
X1796004Y410615D01*
G37*
G36*
G01X1795993Y423893D02*
X1794258Y423026D01*
Y424760D01*
X1795993Y423893D01*
G37*
G36*
G01X1801050Y1267060D02*
X1804298Y1265436D01*
X1801050Y1263812D01*
Y1267060D01*
G37*
G36*
G01X1793857Y1504480D02*
X1797857D01*
X1795857Y1508480D01*
X1793857Y1504480D01*
G37*
G36*
G01X1814466Y169387D02*
X1813084Y166623D01*
X1811702Y169387D01*
X1814466D01*
G37*
G36*
G01X1814426Y169357D02*
X1813044Y166593D01*
X1811662Y169357D01*
X1814426D01*
G37*
G36*
G01X1816563Y180361D02*
Y184361D01*
X1820563Y182361D01*
X1816563Y180361D01*
G37*
G36*
G01X1805279Y392835D02*
X1803279Y396835D01*
X1807279D01*
X1805279Y392835D01*
G37*
G36*
G01X1832370Y161985D02*
X1830988Y159221D01*
X1829606Y161985D01*
X1832370D01*
G37*
G36*
G01X1831326Y256377D02*
G03Y283149I0J13386D01*
G01Y256377D01*
G37*
G36*
G01Y285670D02*
G03Y312442I0J13386D01*
G01Y285670D01*
G37*
G36*
G01X1879155Y579849D02*
X1876155Y573849D01*
X1882155D01*
X1879155Y579849D01*
G37*
G36*
G01Y827749D02*
X1876155Y821749D01*
X1882155D01*
X1879155Y827749D01*
G37*
G36*
G01X1889155Y481897D02*
X1892155Y487897D01*
X1886155D01*
X1889155Y481897D01*
G37*
G36*
G01Y729797D02*
X1892155Y735797D01*
X1886155D01*
X1889155Y729797D01*
G37*
G36*
G01X1900275Y951709D02*
X1897275Y945709D01*
X1903275D01*
X1900275Y951709D01*
G37*
G36*
G01X1910275Y853757D02*
X1913275Y859757D01*
X1907275D01*
X1910275Y853757D01*
G37*
G36*
G01X1931270Y-4420D02*
X1928270Y1580D01*
X1934270D01*
X1931270Y-4420D01*
G37*
G36*
G01X1921395Y579869D02*
X1924395Y573869D01*
X1918395D01*
X1921395Y579869D01*
G37*
G36*
G01X1942395Y1192249D02*
X1945395Y1186249D01*
X1939395D01*
X1942395Y1192249D01*
G37*
G36*
G01X1963362Y580011D02*
X1966362Y574011D01*
X1960362D01*
X1963362Y580011D01*
G37*
G36*
G01X1952395Y606047D02*
X1949395Y612047D01*
X1955395D01*
X1952395Y606047D01*
G37*
G36*
G01X1973200Y-3840D02*
X1970200Y2160D01*
X1976200D01*
X1973200Y-3840D01*
G37*
G36*
G01X1994482Y607919D02*
X1991482Y613919D01*
X1997482D01*
X1994482Y607919D01*
G37*
G36*
G01X1984482Y1192221D02*
X1987482Y1186221D01*
X1981482D01*
X1984482Y1192221D01*
G37*
G36*
G01X2015800Y-3920D02*
X2012800Y2080D01*
X2018800D01*
X2015800Y-3920D01*
G37*
G36*
G01X2005292Y578031D02*
X2008292Y572031D01*
X2002292D01*
X2005292Y578031D01*
G37*
G36*
G01X2026452Y1192401D02*
X2029452Y1186401D01*
X2023452D01*
X2026452Y1192401D01*
G37*
G36*
G01X2047419Y577923D02*
X2050419Y571923D01*
X2044419D01*
X2047419Y577923D01*
G37*
G36*
G01X2036202Y608019D02*
X2033202Y614019D01*
X2039202D01*
X2036202Y608019D01*
G37*
G36*
G01X2056990Y-3340D02*
X2053990Y2660D01*
X2059990D01*
X2056990Y-3340D01*
G37*
G36*
G01X2078209Y608241D02*
X2075209Y614241D01*
X2081209D01*
X2078209Y608241D01*
G37*
G36*
G01X2068539Y1192373D02*
X2071539Y1186373D01*
X2065539D01*
X2068539Y1192373D01*
G37*
%LPC*%
G75*
G36*
G01X1363911Y1542576D02*
X1361545Y1545035D01*
X1361464Y1546304D01*
X1366364D01*
X1366285Y1545044D01*
X1363911Y1542576D01*
G37*
G36*
G01X1363073Y1541705D02*
X1361840Y1540423D01*
X1361665Y1543158D01*
X1363073Y1541705D01*
G37*
G36*
G01X1365996Y1540409D02*
X1364749Y1541705D01*
X1366168Y1543170D01*
X1365996Y1540409D01*
G37*
G36*
G01X1365664Y1539004D02*
G03X1364364Y1537654I849J-2119D01*
G01X1362014Y1537704D01*
X1361943Y1538807D01*
X1363911Y1540839D01*
X1365681Y1539011D01*
X1365664Y1539004D01*
G37*
G54D14*
X174685Y637367D03*
X174393Y668511D03*
X526478Y1439952D03*
X1502956Y1439530D03*
X1682882Y618174D03*
Y669109D03*
X1769790Y194789D03*
X1799350D03*
G54D15*
X205159Y1430034D03*
X393067Y1354446D03*
X422833D03*
X453169D03*
X468443Y1379662D03*
X482543Y1353962D03*
X718638Y1429579D03*
X1178470Y1466363D03*
X1369208Y1353946D03*
X1398974D03*
X1429310D03*
X1444043Y1379362D03*
X1459076Y1353946D03*
X1679944Y1463655D03*
X1836248Y269763D03*
Y299056D03*
G54D13*
X159474Y1320753D03*
X183847Y1320778D03*
X208247D03*
X275289Y575702D03*
Y599861D03*
Y624015D03*
Y648169D03*
X278126Y676260D03*
Y700414D03*
X395771Y1242785D03*
X420171D03*
X444493D03*
X468893D03*
X493293D03*
X673093Y1320778D03*
X697466Y1320803D03*
X721866D03*
X1100800Y251488D03*
X1100700Y275788D03*
X1131100Y1357088D03*
X1155500D03*
X1179900D03*
X1371912Y1242785D03*
X1396312D03*
X1420634D03*
X1445034D03*
X1469434D03*
X1577000Y591888D03*
Y616388D03*
Y640888D03*
Y665288D03*
Y689788D03*
Y714288D03*
X1634259Y1354374D03*
X1658632Y1354399D03*
X1683032D03*
%LPD*%
G75*
G36*
G01X58070Y202787D02*
Y206661D01*
X61614D01*
Y202787D01*
X58070D01*
G37*
G36*
G01X304394Y54005D02*
Y65501D01*
X307543D01*
Y54005D01*
X304394D01*
G37*
G36*
G01X302757Y108253D02*
Y109953D01*
X310557D01*
Y108253D01*
X302757D01*
G37*
G36*
G01X306701Y237889D02*
Y249385D01*
X309850D01*
Y237889D01*
X306701D01*
G37*
G36*
G01X436681Y165551D02*
Y204921D01*
X487862D01*
Y165551D01*
X436681D01*
G37*
G36*
G01X738970Y73490D02*
Y84986D01*
X742119D01*
Y73490D01*
X738970D01*
G37*
G36*
G01X741926Y122619D02*
Y130419D01*
X743626D01*
Y122619D01*
X741926D01*
G37*
G36*
G01X881960Y250492D02*
Y261988D01*
X885109D01*
Y250492D01*
X881960D01*
G37*
G36*
G01X963327Y171527D02*
Y174676D01*
X974823D01*
Y171527D01*
X963327D01*
G37*
G36*
G01X1018684Y161114D02*
Y162814D01*
X1026484D01*
Y161114D01*
X1018684D01*
G37*
G36*
G01X1148485Y1615452D02*
Y1616752D01*
X1151485D01*
Y1615452D01*
X1148485D01*
G37*
G36*
G01X1357339Y1531704D02*
Y1534004D01*
X1370489D01*
Y1531704D01*
X1357339D01*
G37*
G36*
G01X1362564Y1544504D02*
Y1545254D01*
X1365264D01*
Y1544504D01*
X1362564D01*
G37*
G36*
G01X1676897Y379850D02*
Y391346D01*
X1680046D01*
Y379850D01*
X1676897D01*
G37*
G36*
G01X1776065Y55289D02*
Y66785D01*
X1779214D01*
Y55289D01*
X1776065D01*
G37*
G36*
G01X1772878Y109377D02*
Y111077D01*
X1780678D01*
Y109377D01*
X1772878D01*
G37*
G54D10*
G01X1523429Y1533014D02*
X1523829Y1533514D01*
G01X1522829Y1532614D02*
X1523429Y1533014D01*
G01X1522629Y1532514D02*
X1522829Y1532614D01*
G01X1522329Y1532414D02*
X1522629Y1532514D01*
G01X1521629Y1532314D02*
X1522329Y1532414D01*
G01X1521529Y1532314D02*
X1521629D01*
G01X1520929Y1532414D02*
X1521529Y1532314D01*
G01X1520629Y1532514D02*
X1520929Y1532414D01*
G01X1520229Y1532714D02*
X1520629Y1532514D01*
G01X1519729Y1533114D02*
X1520229Y1532714D01*
G01X1519429Y1533514D02*
X1519729Y1533114D01*
G01X1519229Y1533914D02*
X1519429Y1533514D01*
G01X1519129Y1534214D02*
X1519229Y1533914D01*
G01X1519029Y1534714D02*
X1519129Y1534214D01*
G01X1519029Y1535014D02*
Y1534714D01*
G01X1519129Y1535614D02*
X1519029Y1535014D01*
G01X1524229Y1534914D02*
X1524129Y1535614D01*
G01X1519029Y1534914D02*
X1524229D01*
G01X1518329Y1558714D02*
Y1548614D01*
G01X1524429Y1558714D02*
Y1548614D01*
G01X1529239Y1551014D02*
G03I-2410J0D01*
G01X1525529Y1536614D02*
X1526629Y1537214D01*
G01X1519229Y1535914D02*
X1519129Y1535614D01*
G01X1519429Y1536314D02*
X1519229Y1535914D01*
G01X1519729Y1536714D02*
X1519429Y1536314D01*
G01X1519829Y1536814D02*
X1519729Y1536714D01*
G01X1520229Y1537114D02*
X1519829Y1536814D01*
G01X1520629Y1537314D02*
X1520229Y1537114D01*
G01X1520929Y1537414D02*
X1520629Y1537314D01*
G01X1521429Y1537514D02*
X1520929Y1537414D01*
G01X1521829Y1537514D02*
X1521429D01*
G01X1522329Y1537414D02*
X1521829Y1537514D01*
G01X1522629Y1537314D02*
X1522329Y1537414D01*
G01X1523029Y1537114D02*
X1522629Y1537314D01*
G01X1523529Y1536714D02*
X1523029Y1537114D01*
G01X1523829Y1536314D02*
X1523529Y1536714D01*
G01X1524029Y1535914D02*
X1523829Y1536314D01*
G01X1524129Y1535614D02*
X1524029Y1535914D01*
G01X1520829Y1553714D02*
X1518329D01*
G01X1520829Y1558714D02*
G02Y1553714I0J-2500D01*
G01X1518329Y1558714D02*
X1520829D01*
G01X1526629Y1537214D02*
Y1532214D01*
G01X1545990Y282500D02*
X1657950D01*
G01X1545990Y276500D02*
X1658110D01*
G01X1658150Y270580D02*
Y324000D01*
X1545990D01*
Y270500D01*
X1658150D01*
Y270580D01*
G01X1545990Y294500D02*
X1658100D01*
G01X1545990Y288500D02*
X1657910D01*
G01X1545990Y306500D02*
X1658020D01*
G01X1545990Y300500D02*
X1658050D01*
G01X1545915Y317000D02*
X1657685D01*
G01X1591800Y323650D02*
Y270750D01*
G01X1631200Y323650D02*
Y270750D01*
G54D11*
G01X610289Y685070D02*
X608789Y686096D01*
X607039Y686779D01*
X605039D01*
X602789Y685754D01*
X601039Y684046D01*
X599789Y681995D01*
X598789Y678579D01*
X598539Y675504D01*
X599039Y672429D01*
X599789Y670379D01*
X601289Y668329D01*
X603039Y666962D01*
X604789Y666279D01*
X606539D01*
X608289Y666962D01*
X609789Y667987D01*
X611039Y669353D01*
G01X617889Y666279D02*
Y686779D01*
X623889D01*
X625889Y685754D01*
X627389Y683362D01*
X627889Y680629D01*
X627389Y677896D01*
X626139Y675845D01*
X623889Y674820D01*
X617889D01*
G01X635489Y686779D02*
Y672087D01*
X636489Y669012D01*
X638489Y666962D01*
X640989Y666279D01*
X643489Y666962D01*
X645489Y669012D01*
X646489Y672087D01*
Y686779D01*
G01X659089Y666279D02*
Y686779D01*
X656089Y682679D01*
G01Y666279D02*
X662089D01*
G01X807810Y1643740D02*
Y1664240D01*
X813810D01*
X815810Y1663215D01*
X817310Y1660823D01*
X817810Y1658090D01*
X817310Y1655357D01*
X816060Y1653306D01*
X813810Y1652281D01*
X807810D01*
G01X830910Y1643740D02*
X829410Y1644082D01*
X827910Y1645448D01*
X826910Y1647840D01*
X826410Y1650573D01*
X826910Y1653306D01*
X827910Y1655698D01*
X829410Y1657065D01*
X830910Y1657406D01*
X832410Y1657065D01*
X833910Y1655698D01*
X834910Y1653306D01*
X835160Y1650573D01*
X834910Y1647840D01*
X833910Y1645448D01*
X832410Y1644082D01*
X830910Y1643740D01*
G01X842760Y1657406D02*
X845760Y1643740D01*
X849010Y1657406D01*
X852260Y1643740D01*
X855260Y1657406D01*
G01X863360Y1652965D02*
X871360D01*
X870610Y1655357D01*
X869360Y1656723D01*
X867610Y1657406D01*
X865860Y1657065D01*
X864360Y1656040D01*
X863360Y1653648D01*
X862860Y1651598D01*
Y1649548D01*
X863360Y1647498D01*
X864610Y1645448D01*
X866110Y1644082D01*
X867860Y1643740D01*
X869610Y1644423D01*
X871360Y1646473D01*
G01X881710Y1643740D02*
Y1657406D01*
G01Y1654674D02*
X882960Y1656040D01*
X884210Y1657065D01*
X885960Y1657406D01*
X887210Y1657065D01*
X888710Y1656040D01*
G01X925410Y1655698D02*
X923660Y1657065D01*
X922160Y1657406D01*
X920160Y1656723D01*
X918660Y1655357D01*
X917660Y1652965D01*
X917410Y1650573D01*
X917660Y1648181D01*
X918660Y1646131D01*
X920160Y1644423D01*
X922160Y1643740D01*
X923910Y1644423D01*
X925410Y1645790D01*
G01X939510Y1643740D02*
X938010Y1644082D01*
X936510Y1645448D01*
X935510Y1647840D01*
X935010Y1650573D01*
X935510Y1653306D01*
X936510Y1655698D01*
X938010Y1657065D01*
X939510Y1657406D01*
X941010Y1657065D01*
X942510Y1655698D01*
X943510Y1653306D01*
X943760Y1650573D01*
X943510Y1647840D01*
X942510Y1645448D01*
X941010Y1644082D01*
X939510Y1643740D01*
G01X953360D02*
Y1657406D01*
G01Y1653990D02*
X954360Y1655698D01*
X955860Y1657065D01*
X957860Y1657406D01*
X959610Y1657065D01*
X961110Y1655698D01*
X961860Y1653306D01*
Y1643740D01*
G01X971460D02*
Y1657406D01*
G01Y1653990D02*
X972460Y1655698D01*
X973960Y1657065D01*
X975960Y1657406D01*
X977710Y1657065D01*
X979210Y1655698D01*
X979960Y1653306D01*
Y1643740D01*
G01X1226857Y684509D02*
X1225357Y685535D01*
X1223607Y686218D01*
X1221607D01*
X1219357Y685193D01*
X1217607Y683485D01*
X1216357Y681434D01*
X1215357Y678018D01*
X1215107Y674943D01*
X1215607Y671868D01*
X1216357Y669818D01*
X1217857Y667768D01*
X1219607Y666401D01*
X1221357Y665718D01*
X1223107D01*
X1224857Y666401D01*
X1226357Y667426D01*
X1227607Y668792D01*
G01X1234457Y665718D02*
Y686218D01*
X1240457D01*
X1242457Y685193D01*
X1243957Y682801D01*
X1244457Y680068D01*
X1243957Y677335D01*
X1242707Y675284D01*
X1240457Y674259D01*
X1234457D01*
G01X1252057Y686218D02*
Y671526D01*
X1253057Y668451D01*
X1255057Y666401D01*
X1257557Y665718D01*
X1260057Y666401D01*
X1262057Y668451D01*
X1263057Y671526D01*
Y686218D01*
G01X1275657D02*
X1273657Y685535D01*
X1272157Y683826D01*
X1271157Y681777D01*
X1270407Y679043D01*
X1270157Y675968D01*
X1270407Y672893D01*
X1271157Y670159D01*
X1272157Y668109D01*
X1273657Y666401D01*
X1275657Y665718D01*
X1277657Y666401D01*
X1279157Y668109D01*
X1280157Y670159D01*
X1280907Y672893D01*
X1281157Y675968D01*
X1280907Y679043D01*
X1280157Y681777D01*
X1279157Y683826D01*
X1277657Y685535D01*
X1275657Y686218D01*
G54D12*
G01X-6350Y-464479D02*
Y-539479D01*
X493650D01*
Y-464479D01*
X-6350D01*
G01X5650Y-529479D02*
Y-534479D01*
G01X4193Y-529479D02*
X7107D01*
G01X12017Y-534479D02*
X9483D01*
Y-529479D01*
X12017D01*
G01X11003Y-531896D02*
X9483D01*
G01X14583Y-529479D02*
Y-534479D01*
X17117D01*
G01X20950Y-534646D02*
X20823Y-534562D01*
Y-534396D01*
X20950Y-534312D01*
X21077Y-534396D01*
Y-534562D01*
X20950Y-534646D01*
G01Y-532396D02*
X20823Y-532312D01*
Y-532146D01*
X20950Y-532062D01*
X21077Y-532146D01*
Y-532312D01*
X20950Y-532396D01*
G01X25733Y-536146D02*
X25100Y-535312D01*
X24783Y-534479D01*
Y-531146D01*
X25100Y-530312D01*
X25733Y-529479D01*
G01X31150D02*
X30643Y-529646D01*
X30263Y-530062D01*
X30010Y-530562D01*
X29820Y-531229D01*
X29757Y-531979D01*
X29820Y-532729D01*
X30010Y-533396D01*
X30263Y-533896D01*
X30643Y-534312D01*
X31150Y-534479D01*
X31657Y-534312D01*
X32037Y-533896D01*
X32290Y-533396D01*
X32480Y-532729D01*
X32543Y-531979D01*
X32480Y-531229D01*
X32290Y-530562D01*
X32037Y-530062D01*
X31657Y-529646D01*
X31150Y-529479D01*
G01X34857Y-533479D02*
X35237Y-534062D01*
X35743Y-534396D01*
X36313Y-534479D01*
X36820Y-534396D01*
X37327Y-533979D01*
X37643Y-533479D01*
X37707Y-532979D01*
X37580Y-532396D01*
X37137Y-531979D01*
X36693Y-531812D01*
X36123D01*
G01X36693D02*
X37073Y-531562D01*
X37390Y-531146D01*
X37517Y-530646D01*
X37390Y-530146D01*
X37073Y-529729D01*
X36503Y-529479D01*
X35933Y-529562D01*
X35363Y-529896D01*
G01X41667Y-536146D02*
X42300Y-535312D01*
X42617Y-534479D01*
Y-531146D01*
X42300Y-530312D01*
X41667Y-529479D01*
G01X45057Y-533479D02*
X45437Y-534062D01*
X45943Y-534396D01*
X46513Y-534479D01*
X47020Y-534396D01*
X47527Y-533979D01*
X47843Y-533479D01*
X47907Y-532979D01*
X47780Y-532396D01*
X47337Y-531979D01*
X46893Y-531812D01*
X46323D01*
G01X46893D02*
X47273Y-531562D01*
X47590Y-531146D01*
X47717Y-530646D01*
X47590Y-530146D01*
X47273Y-529729D01*
X46703Y-529479D01*
X46133Y-529562D01*
X45563Y-529896D01*
G01X50347Y-530312D02*
X50727Y-529812D01*
X51170Y-529562D01*
X51677Y-529479D01*
X52310Y-529646D01*
X52753Y-530062D01*
X52880Y-530562D01*
X52817Y-531062D01*
X52563Y-531479D01*
X51297Y-532312D01*
X50727Y-532896D01*
X50347Y-533729D01*
X50220Y-534479D01*
X52880D01*
G01X56523D02*
X56650Y-533396D01*
X56840Y-532479D01*
X57093Y-531646D01*
X57410Y-530729D01*
X57917Y-529479D01*
X55383D01*
G01X60927Y-532812D02*
X62573D01*
G01X65647Y-530312D02*
X66027Y-529812D01*
X66470Y-529562D01*
X66977Y-529479D01*
X67610Y-529646D01*
X68053Y-530062D01*
X68180Y-530562D01*
X68117Y-531062D01*
X67863Y-531479D01*
X66597Y-532312D01*
X66027Y-532896D01*
X65647Y-533729D01*
X65520Y-534479D01*
X68180D01*
G01X70557Y-533479D02*
X70937Y-534062D01*
X71443Y-534396D01*
X72013Y-534479D01*
X72520Y-534396D01*
X73027Y-533979D01*
X73343Y-533479D01*
X73407Y-532979D01*
X73280Y-532396D01*
X72837Y-531979D01*
X72393Y-531812D01*
X71823D01*
G01X72393D02*
X72773Y-531562D01*
X73090Y-531146D01*
X73217Y-530646D01*
X73090Y-530146D01*
X72773Y-529729D01*
X72203Y-529479D01*
X71633Y-529562D01*
X71063Y-529896D01*
G01X77810Y-534479D02*
Y-529479D01*
X75467Y-533062D01*
X78633D01*
G01X80757Y-533729D02*
X81137Y-534146D01*
X81580Y-534396D01*
X82150Y-534479D01*
X82720Y-534312D01*
X83163Y-533979D01*
X83480Y-533396D01*
X83543Y-532729D01*
X83417Y-532062D01*
X83100Y-531646D01*
X82657Y-531312D01*
X82213Y-531229D01*
X81770Y-531312D01*
X81200Y-531646D01*
X81390Y-529479D01*
X83100D01*
G01X91147Y-534479D02*
Y-529479D01*
X93553D01*
G01X92667Y-531896D02*
X91147D01*
G01X95867Y-534479D02*
X97450Y-529479D01*
X99033Y-534479D01*
G01X98463Y-532729D02*
X96437D01*
G01X101220Y-534479D02*
X103880Y-529479D01*
G01X101220D02*
X103880Y-534479D01*
G01X107650Y-534646D02*
X107523Y-534562D01*
Y-534396D01*
X107650Y-534312D01*
X107777Y-534396D01*
Y-534562D01*
X107650Y-534646D01*
G01Y-532396D02*
X107523Y-532312D01*
Y-532146D01*
X107650Y-532062D01*
X107777Y-532146D01*
Y-532312D01*
X107650Y-532396D01*
G01X112433Y-536146D02*
X111800Y-535312D01*
X111483Y-534479D01*
Y-531146D01*
X111800Y-530312D01*
X112433Y-529479D01*
G01X117850D02*
X117343Y-529646D01*
X116963Y-530062D01*
X116710Y-530562D01*
X116520Y-531229D01*
X116457Y-531979D01*
X116520Y-532729D01*
X116710Y-533396D01*
X116963Y-533896D01*
X117343Y-534312D01*
X117850Y-534479D01*
X118357Y-534312D01*
X118737Y-533896D01*
X118990Y-533396D01*
X119180Y-532729D01*
X119243Y-531979D01*
X119180Y-531229D01*
X118990Y-530562D01*
X118737Y-530062D01*
X118357Y-529646D01*
X117850Y-529479D01*
G01X121557Y-533479D02*
X121937Y-534062D01*
X122443Y-534396D01*
X123013Y-534479D01*
X123520Y-534396D01*
X124027Y-533979D01*
X124343Y-533479D01*
X124407Y-532979D01*
X124280Y-532396D01*
X123837Y-531979D01*
X123393Y-531812D01*
X122823D01*
G01X123393D02*
X123773Y-531562D01*
X124090Y-531146D01*
X124217Y-530646D01*
X124090Y-530146D01*
X123773Y-529729D01*
X123203Y-529479D01*
X122633Y-529562D01*
X122063Y-529896D01*
G01X128367Y-536146D02*
X129000Y-535312D01*
X129317Y-534479D01*
Y-531146D01*
X129000Y-530312D01*
X128367Y-529479D01*
G01X131757Y-533479D02*
X132137Y-534062D01*
X132643Y-534396D01*
X133213Y-534479D01*
X133720Y-534396D01*
X134227Y-533979D01*
X134543Y-533479D01*
X134607Y-532979D01*
X134480Y-532396D01*
X134037Y-531979D01*
X133593Y-531812D01*
X133023D01*
G01X133593D02*
X133973Y-531562D01*
X134290Y-531146D01*
X134417Y-530646D01*
X134290Y-530146D01*
X133973Y-529729D01*
X133403Y-529479D01*
X132833Y-529562D01*
X132263Y-529896D01*
G01X137173Y-533896D02*
X137617Y-534312D01*
X138123Y-534479D01*
X138630Y-534312D01*
X139073Y-533812D01*
X139390Y-533062D01*
X139517Y-532312D01*
Y-531396D01*
X139390Y-530646D01*
X139073Y-529979D01*
X138693Y-529646D01*
X138250Y-529479D01*
X137743Y-529646D01*
X137363Y-529979D01*
X137110Y-530479D01*
X136983Y-531146D01*
X137110Y-531729D01*
X137427Y-532312D01*
X137807Y-532646D01*
X138250Y-532729D01*
X138757Y-532562D01*
X139137Y-532146D01*
X139517Y-531396D01*
G01X143223Y-534479D02*
X143350Y-533396D01*
X143540Y-532479D01*
X143793Y-531646D01*
X144110Y-530729D01*
X144617Y-529479D01*
X142083D01*
G01X147627Y-532812D02*
X149273D01*
G01X152157Y-533479D02*
X152537Y-534062D01*
X153043Y-534396D01*
X153613Y-534479D01*
X154120Y-534396D01*
X154627Y-533979D01*
X154943Y-533479D01*
X155007Y-532979D01*
X154880Y-532396D01*
X154437Y-531979D01*
X153993Y-531812D01*
X153423D01*
G01X153993D02*
X154373Y-531562D01*
X154690Y-531146D01*
X154817Y-530646D01*
X154690Y-530146D01*
X154373Y-529729D01*
X153803Y-529479D01*
X153233Y-529562D01*
X152663Y-529896D01*
G01X157447Y-532396D02*
X157890Y-531812D01*
X158270Y-531479D01*
X158777Y-531312D01*
X159220Y-531479D01*
X159537Y-531812D01*
X159790Y-532312D01*
X159853Y-532896D01*
X159790Y-533396D01*
X159537Y-533896D01*
X159157Y-534312D01*
X158713Y-534479D01*
X158207Y-534312D01*
X157763Y-533812D01*
X157510Y-533062D01*
X157447Y-532229D01*
X157573Y-531146D01*
X157763Y-530562D01*
X158080Y-529979D01*
X158523Y-529562D01*
X158967Y-529479D01*
X159410Y-529646D01*
X159727Y-530062D01*
G01X163750Y-534479D02*
Y-529479D01*
X162990Y-530479D01*
G01Y-534479D02*
X164510D01*
G01X169610D02*
Y-529479D01*
X167267Y-533062D01*
X170433D01*
G01X51583Y1969D02*
G03X53551Y0I1968J-1D01*
G01X319693D01*
G03X321661Y1969I0J1968D01*
G01Y38504D01*
G02X329535Y46378I7874J0D01*
G01X488591D01*
G02X496465Y38504I0J-7874D01*
G01Y22756D01*
G03X498433Y20787I1968J-1D01*
G01X764575D01*
G03X766543Y22756I0J1968D01*
G01Y38504D01*
G02X774417Y46378I7874J0D01*
G01X871260D01*
G03X879134Y54252I0J7874D01*
G01Y131004D01*
G02X887008Y138878I7874J0D01*
G01X1011024D01*
G02X1018898Y131004I0J-7874D01*
G01Y54252D01*
G03X1026772Y46378I7874J0D01*
G01X1518118D01*
G02X1525992Y38504I0J-7874D01*
G01Y1969D01*
G03X1527961Y0I1969J0D01*
G01X1794102D01*
G03X1796071Y1969I0J1969D01*
G01Y38504D01*
G02X1803945Y46378I7874J0D01*
G01X1849606D01*
G03X1857480Y54252I0J7874D01*
G01Y305794D01*
G03X1855174Y311361I-7873J0D01*
G01X1846007Y320528D01*
G02X1843701Y326096I5568J5568D01*
G01Y1593983D01*
G03X1841395Y1599550I-7873J0D01*
G01X1834196Y1606749D01*
G02X1831890Y1612317I5568J5568D01*
G01Y1732244D01*
G03X1824016Y1740118I-7874J0D01*
G01X1091777D01*
G03X1089809Y1738150I0J-1968D01*
G01Y1736654D01*
G02X1087854Y1734921I-1955J236D01*
G01X769705D01*
G02X767750Y1736654I0J1969D01*
G01Y1738150D01*
G03X765782Y1740118I-1968J0D01*
G01X33465D01*
G03X25591Y1732244I0J-7874D01*
G01Y1612317D01*
G02X23284Y1606749I-7875J1D01*
G01X10180Y1593645D01*
G03X7874Y1588077I5568J-5568D01*
G01Y320191D01*
G02X5568Y314623I-7874J0D01*
G01X2306Y311361D01*
G03X0Y305794I5567J-5567D01*
G01Y54252D01*
G03X7874Y46378I7874J0D01*
G01X43709D01*
G02X51583Y38504I0J-7874D01*
G01Y1969D01*
G01X16535Y87795D02*
G02X38583I11024J0D01*
G02X16535I-11024J0D01*
G01X18661Y1420331D02*
G02X58031I19685J0D01*
G02X18661I-19685J0D01*
G01X29685Y631890D02*
G02X51732I11023J0D01*
G02X29685I-11024J0D01*
G01Y1368898D02*
G02X51732I11023J0D01*
G02X29685I-11024J0D01*
G01X62205Y1714961D02*
G02X40157I-11024J0D01*
G02X62205I11024J0D01*
G01X52141Y119148D02*
X56741Y123451D01*
G02X65079Y114538I4169J-4456D01*
G01X60479Y110235D01*
G02X52141Y119148I-4169J4456D01*
G01X98248Y605378D02*
G02X137618I19685J0D01*
G02X98248I-19685J0D01*
G01X197098Y294335D02*
Y260083D01*
G02X157728I-19685J0D01*
G01Y294335D01*
G02X197098I19685J0D01*
G01X196996Y1671142D02*
Y1644764D01*
G02X157626I-19685J0D01*
G01Y1671142D01*
G02X196996I19685J0D01*
G01X188650Y-464479D02*
Y-539479D01*
G01Y-514479D02*
X291650D01*
Y-489479D01*
G01X188650D02*
X291650D01*
G01X247177Y191535D02*
X253476D01*
G02Y178937I0J-6299D01*
G01X247177D01*
G02Y191535I0J6299D01*
G01X269618Y185236D02*
G02X284579I7481J0D01*
G02X269618I-7481J0D01*
G01X291650Y-464479D02*
Y-539479D01*
G01X293650Y-464479D02*
Y-539479D01*
G01X299157Y-524479D02*
Y-519479D01*
X300423D01*
X300930Y-519729D01*
X301310Y-520062D01*
X301627Y-520562D01*
X301880Y-521146D01*
X301943Y-521979D01*
X301880Y-522812D01*
X301627Y-523396D01*
X301310Y-523896D01*
X300930Y-524229D01*
X300423Y-524479D01*
X299157D01*
G01X304067D02*
X305650Y-519479D01*
X307233Y-524479D01*
G01X306663Y-522729D02*
X304637D01*
G01X310750Y-519479D02*
Y-524479D01*
G01X309293Y-519479D02*
X312207D01*
G01X317117Y-524479D02*
X314583D01*
Y-519479D01*
X317117D01*
G01X316103Y-521896D02*
X314583D01*
G01X320950Y-524646D02*
X320823Y-524562D01*
Y-524396D01*
X320950Y-524312D01*
X321077Y-524396D01*
Y-524562D01*
X320950Y-524646D01*
G01Y-522396D02*
X320823Y-522312D01*
Y-522146D01*
X320950Y-522062D01*
X321077Y-522146D01*
Y-522312D01*
X320950Y-522396D01*
G01X299283Y-499479D02*
Y-494479D01*
X300803D01*
X301310Y-494729D01*
X301690Y-495312D01*
X301817Y-495979D01*
X301690Y-496646D01*
X301373Y-497146D01*
X300803Y-497396D01*
X299283D01*
G01X304510Y-499646D02*
X306790Y-494479D01*
G01X309293Y-499479D02*
Y-494479D01*
X312207Y-499479D01*
Y-494479D01*
G01X315850Y-499646D02*
X315723Y-499562D01*
Y-499396D01*
X315850Y-499312D01*
X315977Y-499396D01*
Y-499562D01*
X315850Y-499646D01*
G01Y-497396D02*
X315723Y-497312D01*
Y-497146D01*
X315850Y-497062D01*
X315977Y-497146D01*
Y-497312D01*
X315850Y-497396D01*
G01X293650Y-514479D02*
X493650D01*
G01X293650Y-489479D02*
X493650D01*
G01X299283Y-474479D02*
Y-469479D01*
X300803D01*
X301310Y-469729D01*
X301690Y-470312D01*
X301817Y-470979D01*
X301690Y-471646D01*
X301373Y-472146D01*
X300803Y-472396D01*
X299283D01*
G01X304383Y-474479D02*
Y-469479D01*
X305967D01*
X306473Y-469729D01*
X306790Y-470062D01*
X306917Y-470729D01*
X306790Y-471396D01*
X306410Y-471812D01*
X305967Y-472062D01*
X304383D01*
G01X305967D02*
X306917Y-474479D01*
G01X310750D02*
X310243Y-474396D01*
X309800Y-474062D01*
X309420Y-473562D01*
X309167Y-472979D01*
X309040Y-472312D01*
Y-471646D01*
X309167Y-470979D01*
X309420Y-470396D01*
X309800Y-469896D01*
X310243Y-469562D01*
X310750Y-469479D01*
X311257Y-469562D01*
X311700Y-469896D01*
X312080Y-470396D01*
X312333Y-470979D01*
X312460Y-471646D01*
Y-472312D01*
X312333Y-472979D01*
X312080Y-473562D01*
X311700Y-474062D01*
X311257Y-474396D01*
X310750Y-474479D01*
G01X314583Y-473479D02*
X314900Y-473979D01*
X315280Y-474312D01*
X315723Y-474479D01*
X316230Y-474312D01*
X316610Y-473979D01*
X316990Y-473479D01*
X317117Y-472812D01*
Y-469479D01*
G01X322217Y-474479D02*
X319683D01*
Y-469479D01*
X322217D01*
G01X321203Y-471896D02*
X319683D01*
G01X327443Y-469896D02*
X327063Y-469646D01*
X326620Y-469479D01*
X326113D01*
X325543Y-469729D01*
X325100Y-470146D01*
X324783Y-470646D01*
X324530Y-471479D01*
X324467Y-472229D01*
X324593Y-472979D01*
X324783Y-473479D01*
X325163Y-473979D01*
X325607Y-474312D01*
X326050Y-474479D01*
X326493D01*
X326937Y-474312D01*
X327317Y-474062D01*
X327633Y-473729D01*
G01X331150Y-469479D02*
Y-474479D01*
G01X329693Y-469479D02*
X332607D01*
G01X336250Y-474646D02*
X336123Y-474562D01*
Y-474396D01*
X336250Y-474312D01*
X336377Y-474396D01*
Y-474562D01*
X336250Y-474646D01*
G01Y-472396D02*
X336123Y-472312D01*
Y-472146D01*
X336250Y-472062D01*
X336377Y-472146D01*
Y-472312D01*
X336250Y-472396D01*
G01X300019Y991220D02*
G02X313523I6752J0D01*
G02X300019I-6752J0D01*
G01X316200Y1391831D02*
G02X328799I6299J0D01*
G02X316200I-6299J0D01*
G01X343346Y811122D02*
G02X356850I6752J0D01*
G02X343346I-6752J0D01*
G01X349310Y1171319D02*
G02X362814I6752J0D01*
G02X349310I-6752J0D01*
G01X362598Y87795D02*
G02X384646I11024J0D01*
G02X362598I-11024J0D01*
G01X365287Y191535D02*
X371587D01*
G02Y178937I0J-6299D01*
G01X365287D01*
G02Y191535I0J6299D01*
G01X384647Y1714961D02*
G02X406694I11023J0D01*
G02X384647I-11023J0D01*
G01X387728Y185236D02*
G02X402689I7481J0D01*
G02X387728I-7480J0D01*
G01X408650Y-514479D02*
Y-539479D01*
G01X411283Y-516979D02*
Y-521979D01*
X413817D01*
G01X416890Y-516979D02*
X418410D01*
G01X417650D02*
Y-521979D01*
G01X416890D02*
X418410D01*
G01X423257Y-519312D02*
X423510Y-519062D01*
X423700Y-518646D01*
X423827Y-518062D01*
X423700Y-517562D01*
X423447Y-517229D01*
X423003Y-516979D01*
X421293D01*
Y-521979D01*
X423383D01*
X423827Y-521646D01*
X424080Y-521146D01*
X424207Y-520562D01*
X424080Y-519979D01*
X423700Y-519479D01*
X423257Y-519312D01*
X421293D01*
G01X427850Y-522146D02*
X427723Y-522062D01*
Y-521896D01*
X427850Y-521812D01*
X427977Y-521896D01*
Y-522062D01*
X427850Y-522146D01*
G01Y-519896D02*
X427723Y-519812D01*
Y-519646D01*
X427850Y-519562D01*
X427977Y-519646D01*
Y-519812D01*
X427850Y-519896D01*
G01X447283Y1698268D02*
G02X434803I-6240J0D01*
G02X447283I6240J0D01*
G01X451650Y-514479D02*
Y-539479D01*
G01Y-489479D02*
Y-514479D01*
G01X456663Y-541646D02*
X456770Y-541521D01*
X456850Y-541312D01*
X456903Y-541021D01*
X456850Y-540771D01*
X456743Y-540604D01*
X456557Y-540479D01*
X455837D01*
Y-542979D01*
X456717D01*
X456903Y-542812D01*
X457010Y-542562D01*
X457063Y-542271D01*
X457010Y-541979D01*
X456850Y-541729D01*
X456663Y-541646D01*
X455837D01*
G01X459130Y-542979D02*
Y-541312D01*
G01Y-541604D02*
X459023Y-541437D01*
X458863Y-541354D01*
X458677Y-541312D01*
X458490Y-541396D01*
X458330Y-541562D01*
X458223Y-541812D01*
X458170Y-542146D01*
X458223Y-542479D01*
X458330Y-542729D01*
X458490Y-542896D01*
X458677Y-542979D01*
X458863Y-542937D01*
X459023Y-542812D01*
X459130Y-542646D01*
G01X460450Y-542687D02*
X460583Y-542854D01*
X460770Y-542979D01*
X460930D01*
X461090Y-542896D01*
X461197Y-542771D01*
X461250Y-542604D01*
X461223Y-542354D01*
X461117Y-542229D01*
X460637Y-541979D01*
X460530Y-541687D01*
X460583Y-541479D01*
X460690Y-541354D01*
X460850Y-541312D01*
X461010Y-541354D01*
X461170Y-541479D01*
G01X462650Y-541854D02*
X463503D01*
X463423Y-541562D01*
X463290Y-541396D01*
X463103Y-541312D01*
X462917Y-541354D01*
X462757Y-541479D01*
X462650Y-541771D01*
X462597Y-542021D01*
Y-542271D01*
X462650Y-542521D01*
X462783Y-542771D01*
X462943Y-542937D01*
X463130Y-542979D01*
X463317Y-542896D01*
X463503Y-542646D01*
G01X464770Y-542979D02*
Y-540479D01*
G01Y-541729D02*
X464903Y-541479D01*
X465063Y-541354D01*
X465223Y-541312D01*
X465463Y-541396D01*
X465623Y-541562D01*
X465730Y-541854D01*
Y-542187D01*
X465677Y-542521D01*
X465570Y-542771D01*
X465383Y-542937D01*
X465223Y-542979D01*
X465063Y-542937D01*
X464903Y-542812D01*
X464770Y-542604D01*
G01X467450Y-542979D02*
X467290Y-542937D01*
X467130Y-542771D01*
X467023Y-542479D01*
X466970Y-542146D01*
X467023Y-541812D01*
X467130Y-541521D01*
X467290Y-541354D01*
X467450Y-541312D01*
X467610Y-541354D01*
X467770Y-541521D01*
X467877Y-541812D01*
X467903Y-542146D01*
X467877Y-542479D01*
X467770Y-542771D01*
X467610Y-542937D01*
X467450Y-542979D01*
G01X470130D02*
Y-541312D01*
G01Y-541604D02*
X470023Y-541437D01*
X469863Y-541354D01*
X469677Y-541312D01*
X469490Y-541396D01*
X469330Y-541562D01*
X469223Y-541812D01*
X469170Y-542146D01*
X469223Y-542479D01*
X469330Y-542729D01*
X469490Y-542896D01*
X469677Y-542979D01*
X469863Y-542937D01*
X470023Y-542812D01*
X470130Y-542646D01*
G01X471477Y-542979D02*
Y-541312D01*
G01Y-541646D02*
X471610Y-541479D01*
X471743Y-541354D01*
X471930Y-541312D01*
X472063Y-541354D01*
X472223Y-541479D01*
G01X474530Y-540479D02*
Y-542979D01*
G01Y-542604D02*
X474423Y-542812D01*
X474263Y-542937D01*
X474077Y-542979D01*
X473863Y-542896D01*
X473703Y-542687D01*
X473597Y-542437D01*
X473570Y-542146D01*
X473597Y-541854D01*
X473703Y-541604D01*
X473863Y-541396D01*
X474077Y-541312D01*
X474263Y-541354D01*
X474397Y-541437D01*
X474530Y-541604D01*
G01X477917Y-542979D02*
Y-540479D01*
X478583D01*
X478797Y-540604D01*
X478930Y-540771D01*
X478983Y-541104D01*
X478930Y-541437D01*
X478770Y-541646D01*
X478583Y-541771D01*
X477917D01*
G01X478583D02*
X478983Y-542979D01*
G01X480250Y-541854D02*
X481103D01*
X481023Y-541562D01*
X480890Y-541396D01*
X480703Y-541312D01*
X480517Y-541354D01*
X480357Y-541479D01*
X480250Y-541771D01*
X480197Y-542021D01*
Y-542271D01*
X480250Y-542521D01*
X480383Y-542771D01*
X480543Y-542937D01*
X480730Y-542979D01*
X480917Y-542896D01*
X481103Y-542646D01*
G01X482370Y-541312D02*
X482850Y-542979D01*
X483330Y-541312D01*
G01X485050Y-543062D02*
X484997Y-543021D01*
Y-542937D01*
X485050Y-542896D01*
X485103Y-542937D01*
Y-543021D01*
X485050Y-543062D01*
G01X487250Y-542979D02*
X487437Y-542937D01*
X487650Y-542812D01*
X487783Y-542604D01*
X487837Y-542312D01*
X487783Y-542021D01*
X487623Y-541771D01*
X487383Y-541646D01*
X487117D01*
X486957Y-541562D01*
X486823Y-541354D01*
X486770Y-541062D01*
X486850Y-540771D01*
X487037Y-540562D01*
X487250Y-540479D01*
X487463Y-540562D01*
X487650Y-540771D01*
X487730Y-541062D01*
X487677Y-541354D01*
X487543Y-541562D01*
X487383Y-541646D01*
X487117D01*
X486877Y-541771D01*
X486717Y-542021D01*
X486663Y-542312D01*
X486717Y-542604D01*
X486850Y-542812D01*
X487063Y-542937D01*
X487250Y-542979D01*
G01X489663Y-541646D02*
X489770Y-541521D01*
X489850Y-541312D01*
X489903Y-541021D01*
X489850Y-540771D01*
X489743Y-540604D01*
X489557Y-540479D01*
X488837D01*
Y-542979D01*
X489717D01*
X489903Y-542812D01*
X490010Y-542562D01*
X490063Y-542271D01*
X490010Y-541979D01*
X489850Y-541729D01*
X489663Y-541646D01*
X488837D01*
G01X455550Y-516979D02*
Y-521979D01*
G01X454093Y-516979D02*
X457007D01*
G01X460650Y-521979D02*
X460270Y-521896D01*
X459890Y-521562D01*
X459637Y-520979D01*
X459510Y-520312D01*
X459637Y-519646D01*
X459890Y-519062D01*
X460270Y-518729D01*
X460650Y-518646D01*
X461030Y-518729D01*
X461410Y-519062D01*
X461663Y-519646D01*
X461727Y-520312D01*
X461663Y-520979D01*
X461410Y-521562D01*
X461030Y-521896D01*
X460650Y-521979D01*
G01X465750D02*
X465370Y-521896D01*
X464990Y-521562D01*
X464737Y-520979D01*
X464610Y-520312D01*
X464737Y-519646D01*
X464990Y-519062D01*
X465370Y-518729D01*
X465750Y-518646D01*
X466130Y-518729D01*
X466510Y-519062D01*
X466763Y-519646D01*
X466827Y-520312D01*
X466763Y-520979D01*
X466510Y-521562D01*
X466130Y-521896D01*
X465750Y-521979D01*
G01X470850D02*
Y-516979D01*
G01X475950Y-522146D02*
X475823Y-522062D01*
Y-521896D01*
X475950Y-521812D01*
X476077Y-521896D01*
Y-522062D01*
X475950Y-522146D01*
G01Y-519896D02*
X475823Y-519812D01*
Y-519646D01*
X475950Y-519562D01*
X476077Y-519646D01*
Y-519812D01*
X475950Y-519896D01*
G01X454283Y-496979D02*
Y-491979D01*
X455867D01*
X456373Y-492229D01*
X456690Y-492562D01*
X456817Y-493229D01*
X456690Y-493896D01*
X456310Y-494312D01*
X455867Y-494562D01*
X454283D01*
G01X455867D02*
X456817Y-496979D01*
G01X461917D02*
X459383D01*
Y-491979D01*
X461917D01*
G01X460903Y-494396D02*
X459383D01*
G01X464167Y-491979D02*
X465750Y-496979D01*
X467333Y-491979D01*
G01X470850Y-497146D02*
X470723Y-497062D01*
Y-496896D01*
X470850Y-496812D01*
X470977Y-496896D01*
Y-497062D01*
X470850Y-497146D01*
G01Y-494896D02*
X470723Y-494812D01*
Y-494646D01*
X470850Y-494562D01*
X470977Y-494646D01*
Y-494812D01*
X470850Y-494896D01*
G01X524488Y811122D02*
G02X537992I6752J0D01*
G02X524488I-6752J0D01*
G01X518523Y1171319D02*
G02X532027I6752J0D01*
G02X518523I-6752J0D01*
G01X531177Y1395413D02*
G02X543775I6299J0D01*
G02X531177I-6299J0D01*
G01X567814Y991220D02*
G02X581318I6752J0D01*
G02X567814I-6752J0D01*
G01X650000Y631890D02*
G02X672047I11023J0D01*
G02X650000I-11024J0D01*
G01X723870Y294362D02*
Y260110D01*
G02X684500I-19685J0D01*
G01Y294362D01*
G02X723870I19685J0D01*
G01X696654Y1714961D02*
G02X718701I11023J0D01*
G02X696654I-11024J0D01*
G01X743917Y605413D02*
G02X783287I19685J0D01*
G02X743917I-19685J0D01*
G01X789764Y87795D02*
G02X811811I11023J0D01*
G02X789764I-11023J0D01*
G01X794864Y204724D02*
G02X816517I10827J0D01*
G02X794864I-10826J0D01*
G01X833366Y1420331D02*
G02X849114I7874J0D01*
G02X833366I-7874J0D01*
G01X896260Y175197D02*
G02X904134I3937J0D01*
G02X896260I-3937J0D01*
G01X936673Y311614D02*
X920807D01*
G02X936673I7933J10039D01*
G01X920669Y757874D02*
G02X942717I11024J0D01*
G02X920669I-11024J0D01*
G01Y1072835D02*
G02X942717I11024J0D01*
G02X920669I-11024J0D01*
G01Y1387795D02*
G02X942717I11024J0D01*
G02X920669I-11024J0D01*
G01X940748Y155217D02*
G02X948622I3937J0D01*
G02X940748I-3937J0D01*
G01X1008366Y1420331D02*
G02X1024114I7874J0D01*
G02X1008366I-7874J0D01*
G01X1034843Y87795D02*
G02X1056890I11024J0D01*
G02X1034843I-11023J0D01*
G01X1046832Y204724D02*
G02X1068486I10827J0D01*
G02X1046832I-10827J0D01*
G01X1074390Y605378D02*
G02X1113760I19685J0D01*
G02X1074390I-19685J0D01*
G01X1173240Y294335D02*
Y260083D01*
G02X1133870I-19685J0D01*
G01Y294335D01*
G02X1173240I19685J0D01*
G01X1125512Y1653543D02*
G02X1142047I8267J0D01*
G02X1125512I-8268J0D01*
G01X1144685Y1714961D02*
G02X1166732I11023J0D01*
G02X1144685I-11024J0D01*
G01X1241535Y269488D02*
G02X1253740I6103J0D01*
G02X1241535I-6102J0D01*
G01X1260236Y631890D02*
G02X1282283I11023J0D01*
G02X1260236I-11023J0D01*
G01X1276161Y991220D02*
G02X1289665I6752J0D01*
G02X1276161I-6752J0D01*
G01X1292342Y1391831D02*
G02X1304940I6299J0D01*
G02X1292342I-6299J0D01*
G01X1319488Y811122D02*
G02X1332992I6752J0D01*
G02X1319488I-6752J0D01*
G01X1325452Y1171319D02*
G02X1338956I6752J0D01*
G02X1325452I-6752J0D01*
G01X1399016Y112008D02*
G02X1411220I6102J0D01*
G02X1399016I-6102J0D01*
G01X1422677Y1698268D02*
G02X1410197I-6240J0D01*
G02X1422677I6240J0D01*
G01X1450782Y1714961D02*
G02X1472829I11023J0D01*
G02X1450782I-11024J0D01*
G01X1488583Y87795D02*
G02X1510630I11024J0D01*
G02X1488583I-11023J0D01*
G01X1500629Y811122D02*
G02X1514133I6752J0D01*
G02X1500629I-6752J0D01*
G01X1494665Y1171319D02*
G02X1508169I6752J0D01*
G02X1494665I-6752J0D01*
G01X1507318Y1395413D02*
G02X1519917I6299J0D01*
G02X1507318I-6300J0D01*
G01X1543956Y991220D02*
G02X1557460I6752J0D01*
G02X1543956I-6752J0D01*
G01X1557944Y1534996D02*
X1561585Y1538489D01*
G01X1557760Y1535046D02*
X1561318Y1538459D01*
G01X1557577Y1535098D02*
X1561050Y1538430D01*
G01X1557392Y1535148D02*
X1560782Y1538400D01*
G01X1557208Y1535198D02*
X1560544Y1538399D01*
G01X1557024Y1535250D02*
X1560335Y1538425D01*
G01X1556840Y1535300D02*
X1560125Y1538451D01*
G01X1556665Y1535360D02*
X1559915Y1538477D01*
G01X1556498Y1535426D02*
X1559705Y1538503D01*
G01X1556330Y1535492D02*
X1559511Y1538544D01*
G01X1556163Y1535559D02*
X1559343Y1538609D01*
G01X1555995Y1535625D02*
X1559174Y1538675D01*
G01X1555828Y1535692D02*
X1559006Y1538740D01*
G01X1555660Y1535758D02*
X1558837Y1538806D01*
G01X1555509Y1535840D02*
X1558668Y1538871D01*
G01X1555358Y1535923D02*
X1558515Y1538952D01*
G01X1555207Y1536005D02*
X1558376Y1539046D01*
G01X1555056Y1536088D02*
X1558238Y1539140D01*
G01X1554905Y1536171D02*
X1558099Y1539234D01*
G01X1554754Y1536253D02*
X1557960Y1539328D01*
G01X1554609Y1536341D02*
X1557821Y1539422D01*
G01X1554474Y1536439D02*
X1557687Y1539520D01*
G01X1554340Y1536537D02*
X1557572Y1539637D01*
G01X1554205Y1536634D02*
X1557457Y1539755D01*
G01X1554070Y1536733D02*
X1557343Y1539872D01*
G01X1553936Y1536830D02*
X1557229Y1539989D01*
G01X1553801Y1536929D02*
X1557114Y1540107D01*
G01X1553675Y1537035D02*
X1557000Y1540224D01*
G01X1553556Y1537149D02*
X1556897Y1540353D01*
G01X1553437Y1537261D02*
X1556804Y1540491D01*
G01X1553318Y1537374D02*
X1556712Y1540630D01*
G01X1553199Y1537487D02*
X1556619Y1540768D01*
G01X1553080Y1537600D02*
X1556526Y1540906D01*
G01X1552960Y1537713D02*
X1556434Y1541045D01*
G01X1552853Y1537838D02*
X1556341Y1541183D01*
G01X1552752Y1537967D02*
X1556267Y1541340D01*
G01X1552650Y1538097D02*
X1556197Y1541499D01*
G01X1552549Y1538227D02*
X1556126Y1541658D01*
G01X1552448Y1538357D02*
X1556055Y1541818D01*
G01X1552346Y1538487D02*
X1555984Y1541977D01*
G01X1552245Y1538617D02*
X1555913Y1542136D01*
G01X1552153Y1538756D02*
X1555852Y1542304D01*
G01X1552071Y1538904D02*
X1555805Y1542486D01*
G01X1551988Y1539052D02*
X1555758Y1542670D01*
G01X1551905Y1539200D02*
X1555712Y1542852D01*
G01X1551823Y1539348D02*
X1555666Y1543034D01*
G01X1551740Y1539496D02*
X1555619Y1543217D01*
G01X1551658Y1539644D02*
X1555581Y1543408D01*
G01X1551588Y1539805D02*
X1555565Y1543620D01*
G01X1551523Y1539969D02*
X1555548Y1543831D01*
G01X1551457Y1540133D02*
X1555532Y1544042D01*
G01X1551391Y1540297D02*
X1555516Y1544254D01*
G01X1551325Y1540461D02*
X1555499Y1544465D01*
G01X1551260Y1540626D02*
X1555518Y1544710D01*
G01X1551203Y1540798D02*
X1555544Y1544962D01*
G01X1551152Y1540977D02*
X1555571Y1545215D01*
G01X1551101Y1541155D02*
X1555597Y1545468D01*
G01X1551051Y1541334D02*
X1555624Y1545721D01*
G01X1551000Y1541513D02*
X1555711Y1546032D01*
G01X1550950Y1541692D02*
X1555807Y1546351D01*
G01X1550912Y1541883D02*
X1555904Y1546671D01*
G01X1550875Y1542075D02*
X1556049Y1547038D01*
G01X1550838Y1542266D02*
X1556285Y1547491D01*
G01X1550801Y1542458D02*
X1556598Y1548018D01*
G01X1562613Y1554017D02*
X1550765Y1542651D01*
G01X1562404Y1554042D02*
X1550740Y1542854D01*
G01X1562194Y1554068D02*
X1550716Y1543057D01*
G01X1557944Y1534996D02*
X1561585Y1538489D01*
G01X1557760Y1535046D02*
X1561318Y1538459D01*
G01X1557577Y1535098D02*
X1561050Y1538430D01*
G01X1557392Y1535148D02*
X1560782Y1538400D01*
G01X1557208Y1535198D02*
X1560544Y1538399D01*
G01X1557024Y1535250D02*
X1560335Y1538425D01*
G01X1556840Y1535300D02*
X1560125Y1538451D01*
G01X1556665Y1535360D02*
X1559915Y1538477D01*
G01X1556498Y1535426D02*
X1559705Y1538503D01*
G01X1556330Y1535492D02*
X1559511Y1538544D01*
G01X1556163Y1535559D02*
X1559343Y1538609D01*
G01X1555995Y1535625D02*
X1559174Y1538675D01*
G01X1555828Y1535692D02*
X1559006Y1538740D01*
G01X1555660Y1535758D02*
X1558837Y1538806D01*
G01X1555509Y1535840D02*
X1558668Y1538871D01*
G01X1555358Y1535923D02*
X1558515Y1538952D01*
G01X1555207Y1536005D02*
X1558376Y1539046D01*
G01X1555056Y1536088D02*
X1558238Y1539140D01*
G01X1554905Y1536171D02*
X1558099Y1539234D01*
G01X1554754Y1536253D02*
X1557960Y1539328D01*
G01X1554609Y1536341D02*
X1557821Y1539422D01*
G01X1554474Y1536439D02*
X1557687Y1539520D01*
G01X1554340Y1536537D02*
X1557572Y1539637D01*
G01X1554205Y1536634D02*
X1557457Y1539755D01*
G01X1554070Y1536733D02*
X1557343Y1539872D01*
G01X1553936Y1536830D02*
X1557229Y1539989D01*
G01X1553801Y1536929D02*
X1557114Y1540107D01*
G01X1553675Y1537035D02*
X1557000Y1540224D01*
G01X1553556Y1537149D02*
X1556897Y1540353D01*
G01X1553437Y1537261D02*
X1556804Y1540491D01*
G01X1553318Y1537374D02*
X1556712Y1540630D01*
G01X1553199Y1537487D02*
X1556619Y1540768D01*
G01X1553080Y1537600D02*
X1556526Y1540906D01*
G01X1552960Y1537713D02*
X1556434Y1541045D01*
G01X1552853Y1537838D02*
X1556341Y1541183D01*
G01X1552752Y1537967D02*
X1556267Y1541340D01*
G01X1552650Y1538097D02*
X1556197Y1541499D01*
G01X1552549Y1538227D02*
X1556126Y1541658D01*
G01X1552448Y1538357D02*
X1556055Y1541818D01*
G01X1552346Y1538487D02*
X1555984Y1541977D01*
G01X1552245Y1538617D02*
X1555913Y1542136D01*
G01X1552153Y1538756D02*
X1555852Y1542304D01*
G01X1552071Y1538904D02*
X1555805Y1542486D01*
G01X1551988Y1539052D02*
X1555758Y1542670D01*
G01X1551905Y1539200D02*
X1555712Y1542852D01*
G01X1551823Y1539348D02*
X1555666Y1543034D01*
G01X1551740Y1539496D02*
X1555619Y1543217D01*
G01X1551658Y1539644D02*
X1555581Y1543408D01*
G01X1551588Y1539805D02*
X1555565Y1543620D01*
G01X1551523Y1539969D02*
X1555548Y1543831D01*
G01X1551457Y1540133D02*
X1555532Y1544042D01*
G01X1551391Y1540297D02*
X1555516Y1544254D01*
G01X1551325Y1540461D02*
X1555499Y1544465D01*
G01X1551260Y1540626D02*
X1555518Y1544710D01*
G01X1551203Y1540798D02*
X1555544Y1544962D01*
G01X1551152Y1540977D02*
X1555571Y1545215D01*
G01X1551101Y1541155D02*
X1555597Y1545468D01*
G01X1551051Y1541334D02*
X1555624Y1545721D01*
G01X1551000Y1541513D02*
X1555711Y1546032D01*
G01X1550950Y1541692D02*
X1555807Y1546351D01*
G01X1550912Y1541883D02*
X1555904Y1546671D01*
G01X1550875Y1542075D02*
X1556049Y1547038D01*
G01X1550838Y1542266D02*
X1556285Y1547491D01*
G01X1550801Y1542458D02*
X1556598Y1548018D01*
G01X1562613Y1554017D02*
X1550765Y1542651D01*
G01X1562404Y1554042D02*
X1550740Y1542854D01*
G01X1562194Y1554068D02*
X1550716Y1543057D01*
G01X1561984Y1554095D02*
X1550691Y1543261D01*
G01X1561764Y1554111D02*
X1550665Y1543464D01*
G01X1561536Y1554120D02*
X1550652Y1543678D01*
G01X1561309Y1554129D02*
X1550638Y1543892D01*
G01X1561081Y1554137D02*
X1550624Y1544105D01*
G01X1560854Y1554146D02*
X1550617Y1544327D01*
G01X1560608Y1554137D02*
X1550613Y1544549D01*
G01X1560360Y1554127D02*
X1550618Y1544781D01*
G01X1560111Y1554115D02*
X1550629Y1545019D01*
G01X1559862Y1554104D02*
X1550640Y1545257D01*
G01X1559614Y1554093D02*
X1550651Y1545495D01*
G01X1559337Y1554054D02*
X1550685Y1545754D01*
G01X1559059Y1554015D02*
X1550722Y1546017D01*
G01X1558781Y1553976D02*
X1550759Y1546280D01*
G01X1558504Y1553937D02*
X1550813Y1546559D01*
G01X1558192Y1553865D02*
X1550883Y1546853D01*
G01X1557876Y1553788D02*
X1550953Y1547147D01*
G01X1557558Y1553711D02*
X1551049Y1547467D01*
G01X1557212Y1553607D02*
X1551163Y1547803D01*
G01X1556839Y1553475D02*
X1551281Y1548144D01*
G01X1556464Y1553343D02*
X1551460Y1548542D01*
G01X1556009Y1553134D02*
X1551641Y1548943D01*
G01X1555541Y1552913D02*
X1551924Y1549442D01*
G01X1554913Y1552537D02*
X1552304Y1550034D01*
G01X1561984Y1554095D02*
X1550691Y1543261D01*
G01X1561764Y1554111D02*
X1550665Y1543464D01*
G01X1561536Y1554120D02*
X1550652Y1543678D01*
G01X1561309Y1554129D02*
X1550638Y1543892D01*
G01X1561081Y1554137D02*
X1550624Y1544105D01*
G01X1560854Y1554146D02*
X1550617Y1544327D01*
G01X1560608Y1554137D02*
X1550613Y1544549D01*
G01X1560360Y1554127D02*
X1550618Y1544781D01*
G01X1560111Y1554115D02*
X1550629Y1545019D01*
G01X1559862Y1554104D02*
X1550640Y1545257D01*
G01X1559614Y1554093D02*
X1550651Y1545495D01*
G01X1559337Y1554054D02*
X1550685Y1545754D01*
G01X1559059Y1554015D02*
X1550722Y1546017D01*
G01X1558781Y1553976D02*
X1550759Y1546280D01*
G01X1558504Y1553937D02*
X1550813Y1546559D01*
G01X1558192Y1553865D02*
X1550883Y1546853D01*
G01X1557876Y1553788D02*
X1550953Y1547147D01*
G01X1557558Y1553711D02*
X1551049Y1547467D01*
G01X1557212Y1553607D02*
X1551163Y1547803D01*
G01X1556839Y1553475D02*
X1551281Y1548144D01*
G01X1556464Y1553343D02*
X1551460Y1548542D01*
G01X1556009Y1553134D02*
X1551641Y1548943D01*
G01X1555541Y1552913D02*
X1551924Y1549442D01*
G01X1554913Y1552537D02*
X1552304Y1550034D01*
G01X1571265Y1533006D02*
X1571273Y1533013D01*
G01X1570942Y1532922D02*
X1571137Y1533109D01*
G01X1570619Y1532841D02*
X1571000Y1533206D01*
G01X1570297Y1532758D02*
X1570863Y1533302D01*
G01X1569974Y1532675D02*
X1570727Y1533398D01*
G01X1569651Y1532594D02*
X1570590Y1533495D01*
G01X1569328Y1532510D02*
X1570454Y1533591D01*
G01X1569006Y1532428D02*
X1570318Y1533687D01*
G01X1568682Y1532346D02*
X1570182Y1533783D01*
G01X1568408Y1532309D02*
X1570045Y1533880D01*
G01X1568241Y1532377D02*
X1569909Y1533977D01*
G01X1568073Y1532442D02*
X1569773Y1534072D01*
G01X1567905Y1532510D02*
X1569637Y1534170D01*
G01X1567738Y1532575D02*
X1569500Y1534266D01*
G01X1567570Y1532641D02*
X1569364Y1534363D01*
G01X1567402Y1532708D02*
X1569228Y1534459D01*
G01X1567234Y1532773D02*
X1569091Y1534555D01*
G01X1567066Y1532841D02*
X1568955Y1534653D01*
G01X1566898Y1532906D02*
X1568819Y1534748D01*
G01X1566730Y1532971D02*
X1568683Y1534845D01*
G01X1566561Y1533037D02*
X1568547Y1534942D01*
G01X1566393Y1533103D02*
X1568410Y1535038D01*
G01X1566224Y1533169D02*
X1568274Y1535136D01*
G01X1566056Y1533234D02*
X1568138Y1535231D01*
G01X1565887Y1533299D02*
X1568002Y1535328D01*
G01X1565718Y1533364D02*
X1567866Y1535425D01*
G01X1565549Y1533429D02*
X1567730Y1535521D01*
G01X1565380Y1533495D02*
X1567594Y1535618D01*
G01X1565211Y1533560D02*
X1567458Y1535715D01*
G01X1565041Y1533625D02*
X1567321Y1535811D01*
G01X1564872Y1533689D02*
X1567185Y1535908D01*
G01X1564701Y1533752D02*
X1567049Y1536004D01*
G01X1566913Y1536101D02*
X1564531Y1533817D01*
G01X1564361Y1533881D02*
X1566777Y1536198D01*
G01X1564191Y1533945D02*
X1569264Y1538811D01*
G01X1564020Y1534007D02*
X1569554Y1539317D01*
G01X1563849Y1534071D02*
X1569803Y1539783D01*
G01X1563677Y1534133D02*
X1569950Y1540151D01*
G01X1563505Y1534196D02*
X1570096Y1540518D01*
G01X1563333Y1534257D02*
X1570224Y1540868D01*
G01X1563159Y1534318D02*
X1570301Y1541169D01*
G01X1562985Y1534379D02*
X1570378Y1541471D01*
G01X1562809Y1534436D02*
X1570455Y1541771D01*
G01X1562632Y1534493D02*
X1570524Y1542065D01*
G01X1562449Y1534547D02*
X1570560Y1542327D01*
G01X1562249Y1534581D02*
X1570597Y1542589D01*
G01X1562019Y1534588D02*
X1570633Y1542851D01*
G01X1561789Y1534593D02*
X1570669Y1543112D01*
G01X1561559Y1534601D02*
X1570705Y1543374D01*
G01X1561329Y1534607D02*
X1570714Y1543611D01*
G01X1561098Y1534614D02*
X1570724Y1543847D01*
G01X1560868Y1534620D02*
X1570734Y1544083D01*
G01X1560643Y1534631D02*
X1570744Y1544321D01*
G01X1560428Y1534652D02*
X1570754Y1544558D01*
G01X1560212Y1534672D02*
X1570764Y1544794D01*
G01X1559996Y1534692D02*
X1570760Y1545017D01*
G01X1559781Y1534713D02*
X1570751Y1545237D01*
G01X1559565Y1534733D02*
X1570736Y1545449D01*
G01X1559349Y1534753D02*
X1570715Y1545657D01*
G01X1559145Y1534783D02*
X1570695Y1545864D01*
G01X1570669Y1546066D02*
X1558944Y1534818D01*
G01X1558744Y1534854D02*
X1563198Y1539127D01*
G01X1558544Y1534889D02*
X1562631Y1538810D01*
G01X1558344Y1534924D02*
X1562261Y1538683D01*
G01X1558143Y1534959D02*
X1561890Y1538554D01*
G01X1569651Y1532594D02*
X1569974Y1532675D01*
G01X1571265Y1533006D02*
X1570942Y1532922D01*
G01X1569328Y1532510D02*
X1569651Y1532594D01*
G01X1569006Y1532428D02*
X1569328Y1532510D01*
G01X1570619Y1532841D02*
X1570942Y1532922D01*
G01X1569974Y1532675D02*
X1570297Y1532758D01*
G01D02*
X1570619Y1532841D01*
G01X1568682Y1532346D02*
X1569006Y1532428D01*
G01X1571265Y1533006D02*
X1571273Y1533013D01*
G01X1570942Y1532922D02*
X1571137Y1533109D01*
G01X1570619Y1532841D02*
X1571000Y1533206D01*
G01X1570297Y1532758D02*
X1570863Y1533302D01*
G01X1569974Y1532675D02*
X1570727Y1533398D01*
G01X1569651Y1532594D02*
X1570590Y1533495D01*
G01X1569328Y1532510D02*
X1570454Y1533591D01*
G01X1569006Y1532428D02*
X1570318Y1533687D01*
G01X1568682Y1532346D02*
X1570182Y1533783D01*
G01X1568408Y1532309D02*
X1570045Y1533880D01*
G01X1568241Y1532377D02*
X1569909Y1533977D01*
G01X1568073Y1532442D02*
X1569773Y1534072D01*
G01X1567905Y1532510D02*
X1569637Y1534170D01*
G01X1567738Y1532575D02*
X1569500Y1534266D01*
G01X1567570Y1532641D02*
X1569364Y1534363D01*
G01X1567402Y1532708D02*
X1569228Y1534459D01*
G01X1567234Y1532773D02*
X1569091Y1534555D01*
G01X1567066Y1532841D02*
X1568955Y1534653D01*
G01X1566898Y1532906D02*
X1568819Y1534748D01*
G01X1566730Y1532971D02*
X1568683Y1534845D01*
G01X1566561Y1533037D02*
X1568547Y1534942D01*
G01X1566393Y1533103D02*
X1568410Y1535038D01*
G01X1566224Y1533169D02*
X1568274Y1535136D01*
G01X1566056Y1533234D02*
X1568138Y1535231D01*
G01X1565887Y1533299D02*
X1568002Y1535328D01*
G01X1565718Y1533364D02*
X1567866Y1535425D01*
G01X1565549Y1533429D02*
X1567730Y1535521D01*
G01X1565380Y1533495D02*
X1567594Y1535618D01*
G01X1565211Y1533560D02*
X1567458Y1535715D01*
G01X1565041Y1533625D02*
X1567321Y1535811D01*
G01X1564872Y1533689D02*
X1567185Y1535908D01*
G01X1564701Y1533752D02*
X1567049Y1536004D01*
G01X1566913Y1536101D02*
X1564531Y1533817D01*
G01X1564361Y1533881D02*
X1566777Y1536198D01*
G01X1564191Y1533945D02*
X1569264Y1538811D01*
G01X1564020Y1534007D02*
X1569554Y1539317D01*
G01X1563849Y1534071D02*
X1569803Y1539783D01*
G01X1563677Y1534133D02*
X1569950Y1540151D01*
G01X1563505Y1534196D02*
X1570096Y1540518D01*
G01X1563333Y1534257D02*
X1570224Y1540868D01*
G01X1563159Y1534318D02*
X1570301Y1541169D01*
G01X1562985Y1534379D02*
X1570378Y1541471D01*
G01X1562809Y1534436D02*
X1570455Y1541771D01*
G01X1562632Y1534493D02*
X1570524Y1542065D01*
G01X1562449Y1534547D02*
X1570560Y1542327D01*
G01X1562249Y1534581D02*
X1570597Y1542589D01*
G01X1562019Y1534588D02*
X1570633Y1542851D01*
G01X1561789Y1534593D02*
X1570669Y1543112D01*
G01X1561559Y1534601D02*
X1570705Y1543374D01*
G01X1561329Y1534607D02*
X1570714Y1543611D01*
G01X1561098Y1534614D02*
X1570724Y1543847D01*
G01X1560868Y1534620D02*
X1570734Y1544083D01*
G01X1560643Y1534631D02*
X1570744Y1544321D01*
G01X1560428Y1534652D02*
X1570754Y1544558D01*
G01X1560212Y1534672D02*
X1570764Y1544794D01*
G01X1559996Y1534692D02*
X1570760Y1545017D01*
G01X1559781Y1534713D02*
X1570751Y1545237D01*
G01X1559565Y1534733D02*
X1570736Y1545449D01*
G01X1559349Y1534753D02*
X1570715Y1545657D01*
G01X1559145Y1534783D02*
X1570695Y1545864D01*
G01X1570669Y1546066D02*
X1558944Y1534818D01*
G01X1558744Y1534854D02*
X1563198Y1539127D01*
G01X1558544Y1534889D02*
X1562631Y1538810D01*
G01X1558344Y1534924D02*
X1562261Y1538683D01*
G01X1558143Y1534959D02*
X1561890Y1538554D01*
G01X1569651Y1532594D02*
X1569974Y1532675D01*
G01X1571265Y1533006D02*
X1570942Y1532922D01*
G01X1569328Y1532510D02*
X1569651Y1532594D01*
G01X1569006Y1532428D02*
X1569328Y1532510D01*
G01X1570619Y1532841D02*
X1570942Y1532922D01*
G01X1569974Y1532675D02*
X1570297Y1532758D01*
G01D02*
X1570619Y1532841D01*
G01X1568682Y1532346D02*
X1569006Y1532428D01*
G01X1574172Y1535880D02*
X1577902Y1539458D01*
G01X1574034Y1535975D02*
X1577739Y1539529D01*
G01X1573895Y1536069D02*
X1577591Y1539614D01*
G01X1573756Y1536162D02*
X1577442Y1539699D01*
G01X1573618Y1536257D02*
X1577318Y1539807D01*
G01X1573500Y1536371D02*
X1577209Y1539930D01*
G01X1573397Y1536500D02*
X1577101Y1540052D01*
G01X1573294Y1536628D02*
X1577010Y1540192D01*
G01X1573191Y1536757D02*
X1576940Y1540353D01*
G01X1573088Y1536885D02*
X1576870Y1540513D01*
G01X1572986Y1537014D02*
X1576807Y1540679D01*
G01X1572882Y1537142D02*
X1576774Y1540876D01*
G01X1572803Y1537294D02*
X1576741Y1541072D01*
G01X1572735Y1537455D02*
X1576709Y1541267D01*
G01X1572666Y1537616D02*
X1576701Y1541487D01*
G01X1572598Y1537778D02*
X1576703Y1541716D01*
G01X1572529Y1537939D02*
X1576705Y1541945D01*
G01X1572461Y1538101D02*
X1576707Y1542174D01*
G01X1572392Y1538262D02*
X1576741Y1542434D01*
G01X1572351Y1538450D02*
X1576774Y1542693D01*
G01X1572316Y1538644D02*
X1576808Y1542953D01*
G01X1572282Y1538838D02*
X1576842Y1543213D01*
G01X1572246Y1539031D02*
X1576890Y1543485D01*
G01X1572212Y1539225D02*
X1576938Y1543759D01*
G01X1572177Y1539419D02*
X1576985Y1544032D01*
G01X1572143Y1539613D02*
X1577034Y1544305D01*
G01X1572141Y1539839D02*
X1577082Y1544579D01*
G01X1572139Y1540065D02*
X1577130Y1544852D01*
G01X1572137Y1540290D02*
X1577177Y1545125D01*
G01X1572136Y1540516D02*
X1577225Y1545398D01*
G01X1572134Y1540741D02*
X1577274Y1545671D01*
G01X1572132Y1540967D02*
X1577321Y1545944D01*
G01X1577369Y1546218D02*
X1572140Y1541202D01*
G01X1577417Y1546491D02*
X1572172Y1541459D01*
G01X1577466Y1546764D02*
X1572203Y1541716D01*
G01X1577513Y1547038D02*
X1572234Y1541973D01*
G01X1577561Y1547311D02*
X1572265Y1542231D01*
G01X1577609Y1547584D02*
X1572297Y1542488D01*
G01X1577657Y1547857D02*
X1572328Y1542745D01*
G01X1577705Y1548130D02*
X1572371Y1543013D01*
G01X1570636Y1546262D02*
X1564697Y1540564D01*
G01X1570604Y1546458D02*
X1565058Y1541139D01*
G01X1570570Y1546654D02*
X1565238Y1541538D01*
G01X1570533Y1546845D02*
X1565418Y1541938D01*
G01X1570487Y1547028D02*
X1565506Y1542250D01*
G01X1570442Y1547211D02*
X1565582Y1542549D01*
G01X1570395Y1547394D02*
X1565658Y1542849D01*
G01X1572419Y1543287D02*
X1572371Y1543013D01*
G01X1574172Y1535880D02*
X1577902Y1539458D01*
G01X1574034Y1535975D02*
X1577739Y1539529D01*
G01X1573895Y1536069D02*
X1577591Y1539614D01*
G01X1573756Y1536162D02*
X1577442Y1539699D01*
G01X1573618Y1536257D02*
X1577318Y1539807D01*
G01X1573500Y1536371D02*
X1577209Y1539930D01*
G01X1573397Y1536500D02*
X1577101Y1540052D01*
G01X1573294Y1536628D02*
X1577010Y1540192D01*
G01X1573191Y1536757D02*
X1576940Y1540353D01*
G01X1573088Y1536885D02*
X1576870Y1540513D01*
G01X1572986Y1537014D02*
X1576807Y1540679D01*
G01X1572882Y1537142D02*
X1576774Y1540876D01*
G01X1572803Y1537294D02*
X1576741Y1541072D01*
G01X1572735Y1537455D02*
X1576709Y1541267D01*
G01X1572666Y1537616D02*
X1576701Y1541487D01*
G01X1572598Y1537778D02*
X1576703Y1541716D01*
G01X1572529Y1537939D02*
X1576705Y1541945D01*
G01X1572461Y1538101D02*
X1576707Y1542174D01*
G01X1572392Y1538262D02*
X1576741Y1542434D01*
G01X1572351Y1538450D02*
X1576774Y1542693D01*
G01X1572316Y1538644D02*
X1576808Y1542953D01*
G01X1572282Y1538838D02*
X1576842Y1543213D01*
G01X1572246Y1539031D02*
X1576890Y1543485D01*
G01X1572212Y1539225D02*
X1576938Y1543759D01*
G01X1572177Y1539419D02*
X1576985Y1544032D01*
G01X1572143Y1539613D02*
X1577034Y1544305D01*
G01X1572141Y1539839D02*
X1577082Y1544579D01*
G01X1572139Y1540065D02*
X1577130Y1544852D01*
G01X1572137Y1540290D02*
X1577177Y1545125D01*
G01X1572136Y1540516D02*
X1577225Y1545398D01*
G01X1572134Y1540741D02*
X1577274Y1545671D01*
G01X1572132Y1540967D02*
X1577321Y1545944D01*
G01X1577369Y1546218D02*
X1572140Y1541202D01*
G01X1577417Y1546491D02*
X1572172Y1541459D01*
G01X1577466Y1546764D02*
X1572203Y1541716D01*
G01X1577513Y1547038D02*
X1572234Y1541973D01*
G01X1577561Y1547311D02*
X1572265Y1542231D01*
G01X1577609Y1547584D02*
X1572297Y1542488D01*
G01X1577657Y1547857D02*
X1572328Y1542745D01*
G01X1577705Y1548130D02*
X1572371Y1543013D01*
G01X1570636Y1546262D02*
X1564697Y1540564D01*
G01X1570604Y1546458D02*
X1565058Y1541139D01*
G01X1570570Y1546654D02*
X1565238Y1541538D01*
G01X1570533Y1546845D02*
X1565418Y1541938D01*
G01X1570487Y1547028D02*
X1565506Y1542250D01*
G01X1570442Y1547211D02*
X1565582Y1542549D01*
G01X1570395Y1547394D02*
X1565658Y1542849D01*
G01X1572419Y1543287D02*
X1572371Y1543013D01*
G01X1577753Y1548403D02*
X1572419Y1543287D01*
G01X1577801Y1548677D02*
X1572467Y1543560D01*
G01X1577849Y1548950D02*
X1572515Y1543833D01*
G01X1577897Y1549223D02*
X1572563Y1544107D01*
G01X1577945Y1549497D02*
X1572611Y1544380D01*
G01X1577993Y1549769D02*
X1572659Y1544653D01*
G01X1578041Y1550043D02*
X1572707Y1544926D01*
G01X1578089Y1550316D02*
X1572755Y1545199D01*
G01X1578137Y1550590D02*
X1572802Y1545472D01*
G01X1578184Y1550862D02*
X1572851Y1545746D01*
G01X1578233Y1551135D02*
X1572899Y1546019D01*
G01X1578281Y1551409D02*
X1572946Y1546292D01*
G01X1578328Y1551682D02*
X1572994Y1546566D01*
G01X1578376Y1551956D02*
X1573043Y1546838D01*
G01X1578424Y1552228D02*
X1573091Y1547112D01*
G01X1578309Y1552345D02*
X1573138Y1547385D01*
G01X1578072Y1552345D02*
X1573186Y1547659D01*
G01X1577835Y1552345D02*
X1573234Y1547931D01*
G01X1577598Y1552345D02*
X1573282Y1548204D01*
G01X1577361Y1552345D02*
X1573330Y1548478D01*
G01X1577124Y1552345D02*
X1573378Y1548751D01*
G01X1576888Y1552345D02*
X1573426Y1549025D01*
G01X1576651Y1552345D02*
X1573474Y1549297D01*
G01X1576414Y1552345D02*
X1573522Y1549571D01*
G01X1576177Y1552345D02*
X1573570Y1549844D01*
G01X1575940Y1552345D02*
X1573618Y1550117D01*
G01X1575704Y1552345D02*
X1573666Y1550390D01*
G01X1575466Y1552345D02*
X1573714Y1550664D01*
G01X1575230Y1552345D02*
X1573762Y1550937D01*
G01X1574993Y1552345D02*
X1573810Y1551210D01*
G01X1570349Y1547577D02*
X1565721Y1543137D01*
G01X1570297Y1547754D02*
X1565741Y1543384D01*
G01X1570237Y1547924D02*
X1565761Y1543630D01*
G01X1570178Y1548094D02*
X1565781Y1543877D01*
G01X1570117Y1548264D02*
X1565801Y1544123D01*
G01X1570058Y1548434D02*
X1565805Y1544354D01*
G01X1569998Y1548603D02*
X1565787Y1544564D01*
G01X1569925Y1548761D02*
X1565770Y1544775D01*
G01X1569850Y1548916D02*
X1565752Y1544985D01*
G01X1569775Y1549071D02*
X1565734Y1545196D01*
G01X1569700Y1549227D02*
X1565717Y1545406D01*
G01X1569626Y1549382D02*
X1565686Y1545603D01*
G01X1569550Y1549537D02*
X1565638Y1545785D01*
G01X1569464Y1549682D02*
X1565591Y1545967D01*
G01X1569373Y1549822D02*
X1565544Y1546149D01*
G01X1569282Y1549961D02*
X1565496Y1546330D01*
G01X1569190Y1550101D02*
X1565449Y1546511D01*
G01X1569099Y1550241D02*
X1565399Y1546691D01*
G01X1569007Y1550380D02*
X1565326Y1546848D01*
G01X1568916Y1550519D02*
X1565254Y1547006D01*
G01X1568808Y1550643D02*
X1565181Y1547164D01*
G01X1568698Y1550765D02*
X1565108Y1547321D01*
G01X1568589Y1550887D02*
X1565035Y1547478D01*
G01X1568479Y1551009D02*
X1564963Y1547636D01*
G01X1568369Y1551131D02*
X1564877Y1547781D01*
G01X1568259Y1551252D02*
X1564781Y1547916D01*
G01X1568149Y1551374D02*
X1564685Y1548051D01*
G01X1568029Y1551486D02*
X1564589Y1548186D01*
G01X1567904Y1551594D02*
X1564493Y1548321D01*
G01X1567778Y1551701D02*
X1564397Y1548456D01*
G01X1567654Y1551808D02*
X1564301Y1548592D01*
G01X1567528Y1551914D02*
X1564183Y1548706D01*
G01X1567403Y1552021D02*
X1564064Y1548818D01*
G01X1567270Y1552122D02*
X1563945Y1548932D01*
G01X1567133Y1552217D02*
X1563825Y1549044D01*
G01X1566996Y1552312D02*
X1563707Y1549158D01*
G01X1566859Y1552408D02*
X1563587Y1549270D01*
G01X1566721Y1552504D02*
X1563455Y1549370D01*
G01X1566584Y1552599D02*
X1563311Y1549460D01*
G01X1566437Y1552685D02*
X1563167Y1549548D01*
G01X1566287Y1552769D02*
X1563023Y1549638D01*
G01X1566137Y1552852D02*
X1562879Y1549727D01*
G01X1565987Y1552936D02*
X1562734Y1549815D01*
G01X1565837Y1553019D02*
X1562578Y1549893D01*
G01X1565686Y1553100D02*
X1562405Y1549954D01*
G01X1565521Y1553171D02*
X1562231Y1550014D01*
G01X1565358Y1553241D02*
X1562057Y1550075D01*
G01X1565195Y1553311D02*
X1561884Y1550135D01*
G01X1565031Y1553382D02*
X1561711Y1550197D01*
G01X1564868Y1553452D02*
X1561506Y1550228D01*
G01X1564694Y1553513D02*
X1561294Y1550251D01*
G01X1564516Y1553570D02*
X1561082Y1550275D01*
G01X1564338Y1553626D02*
X1560871Y1550300D01*
G01X1564160Y1553682D02*
X1560658Y1550323D01*
G01X1563982Y1553739D02*
X1560396Y1550299D01*
G01X1563797Y1553789D02*
X1560127Y1550268D01*
G01X1563604Y1553831D02*
X1559857Y1550237D01*
G01X1563410Y1553872D02*
X1559547Y1550166D01*
G01X1563217Y1553914D02*
X1559178Y1550040D01*
G01X1563024Y1553956D02*
X1558810Y1549913D01*
G01X1562824Y1553991D02*
X1558216Y1549571D01*
G01X1573762Y1550937D02*
X1573810Y1551210D01*
G01D02*
X1573858Y1551483D01*
G01X1573714Y1550664D02*
X1573762Y1550937D01*
G01X1573570Y1549844D02*
X1573522Y1549571D01*
G01X1573666Y1550390D02*
X1573714Y1550664D01*
G01X1573618Y1550117D02*
X1573666Y1550390D01*
G01X1573570Y1549844D02*
X1573618Y1550117D01*
G01X1573522Y1549571D02*
X1573474Y1549297D01*
G01X1572659Y1544653D02*
X1572611Y1544380D01*
G01X1572802Y1545472D02*
X1572755Y1545199D01*
G01D02*
X1572707Y1544926D01*
G01X1572946Y1546292D02*
X1572899Y1546019D01*
G01D02*
X1572851Y1545746D01*
G01D02*
X1572802Y1545472D01*
G01X1572707Y1544926D02*
X1572659Y1544653D01*
G01X1573474Y1549297D02*
X1573426Y1549025D01*
G01X1572611Y1544380D02*
X1572563Y1544107D01*
G01D02*
X1572515Y1543833D01*
G01X1573330Y1548478D02*
X1573282Y1548204D01*
G01X1572994Y1546566D02*
X1572946Y1546292D01*
G01X1573282Y1548204D02*
X1573234Y1547931D01*
G01X1573426Y1549025D02*
X1573378Y1548751D01*
G01D02*
X1573330Y1548478D01*
G01X1573234Y1547931D02*
X1573186Y1547659D01*
G01X1573043Y1546838D02*
X1572994Y1546566D01*
G01X1573091Y1547112D02*
X1573043Y1546838D01*
G01X1573186Y1547659D02*
X1573138Y1547385D01*
G01D02*
X1573091Y1547112D01*
G01X1572515Y1543833D02*
X1572467Y1543560D01*
G01D02*
X1572419Y1543287D01*
G01X1577753Y1548403D02*
X1572419Y1543287D01*
G01X1577801Y1548677D02*
X1572467Y1543560D01*
G01X1577849Y1548950D02*
X1572515Y1543833D01*
G01X1577897Y1549223D02*
X1572563Y1544107D01*
G01X1577945Y1549497D02*
X1572611Y1544380D01*
G01X1577993Y1549769D02*
X1572659Y1544653D01*
G01X1578041Y1550043D02*
X1572707Y1544926D01*
G01X1578089Y1550316D02*
X1572755Y1545199D01*
G01X1578137Y1550590D02*
X1572802Y1545472D01*
G01X1578184Y1550862D02*
X1572851Y1545746D01*
G01X1578233Y1551135D02*
X1572899Y1546019D01*
G01X1578281Y1551409D02*
X1572946Y1546292D01*
G01X1578328Y1551682D02*
X1572994Y1546566D01*
G01X1578376Y1551956D02*
X1573043Y1546838D01*
G01X1578424Y1552228D02*
X1573091Y1547112D01*
G01X1578309Y1552345D02*
X1573138Y1547385D01*
G01X1578072Y1552345D02*
X1573186Y1547659D01*
G01X1577835Y1552345D02*
X1573234Y1547931D01*
G01X1577598Y1552345D02*
X1573282Y1548204D01*
G01X1577361Y1552345D02*
X1573330Y1548478D01*
G01X1577124Y1552345D02*
X1573378Y1548751D01*
G01X1576888Y1552345D02*
X1573426Y1549025D01*
G01X1576651Y1552345D02*
X1573474Y1549297D01*
G01X1576414Y1552345D02*
X1573522Y1549571D01*
G01X1576177Y1552345D02*
X1573570Y1549844D01*
G01X1575940Y1552345D02*
X1573618Y1550117D01*
G01X1575704Y1552345D02*
X1573666Y1550390D01*
G01X1575466Y1552345D02*
X1573714Y1550664D01*
G01X1575230Y1552345D02*
X1573762Y1550937D01*
G01X1574993Y1552345D02*
X1573810Y1551210D01*
G01X1570349Y1547577D02*
X1565721Y1543137D01*
G01X1570297Y1547754D02*
X1565741Y1543384D01*
G01X1570237Y1547924D02*
X1565761Y1543630D01*
G01X1570178Y1548094D02*
X1565781Y1543877D01*
G01X1570117Y1548264D02*
X1565801Y1544123D01*
G01X1570058Y1548434D02*
X1565805Y1544354D01*
G01X1569998Y1548603D02*
X1565787Y1544564D01*
G01X1569925Y1548761D02*
X1565770Y1544775D01*
G01X1569850Y1548916D02*
X1565752Y1544985D01*
G01X1569775Y1549071D02*
X1565734Y1545196D01*
G01X1569700Y1549227D02*
X1565717Y1545406D01*
G01X1569626Y1549382D02*
X1565686Y1545603D01*
G01X1569550Y1549537D02*
X1565638Y1545785D01*
G01X1569464Y1549682D02*
X1565591Y1545967D01*
G01X1569373Y1549822D02*
X1565544Y1546149D01*
G01X1569282Y1549961D02*
X1565496Y1546330D01*
G01X1569190Y1550101D02*
X1565449Y1546511D01*
G01X1569099Y1550241D02*
X1565399Y1546691D01*
G01X1569007Y1550380D02*
X1565326Y1546848D01*
G01X1568916Y1550519D02*
X1565254Y1547006D01*
G01X1568808Y1550643D02*
X1565181Y1547164D01*
G01X1568698Y1550765D02*
X1565108Y1547321D01*
G01X1568589Y1550887D02*
X1565035Y1547478D01*
G01X1568479Y1551009D02*
X1564963Y1547636D01*
G01X1568369Y1551131D02*
X1564877Y1547781D01*
G01X1568259Y1551252D02*
X1564781Y1547916D01*
G01X1568149Y1551374D02*
X1564685Y1548051D01*
G01X1568029Y1551486D02*
X1564589Y1548186D01*
G01X1567904Y1551594D02*
X1564493Y1548321D01*
G01X1567778Y1551701D02*
X1564397Y1548456D01*
G01X1567654Y1551808D02*
X1564301Y1548592D01*
G01X1567528Y1551914D02*
X1564183Y1548706D01*
G01X1567403Y1552021D02*
X1564064Y1548818D01*
G01X1567270Y1552122D02*
X1563945Y1548932D01*
G01X1567133Y1552217D02*
X1563825Y1549044D01*
G01X1566996Y1552312D02*
X1563707Y1549158D01*
G01X1566859Y1552408D02*
X1563587Y1549270D01*
G01X1566721Y1552504D02*
X1563455Y1549370D01*
G01X1566584Y1552599D02*
X1563311Y1549460D01*
G01X1566437Y1552685D02*
X1563167Y1549548D01*
G01X1566287Y1552769D02*
X1563023Y1549638D01*
G01X1566137Y1552852D02*
X1562879Y1549727D01*
G01X1565987Y1552936D02*
X1562734Y1549815D01*
G01X1565837Y1553019D02*
X1562578Y1549893D01*
G01X1565686Y1553100D02*
X1562405Y1549954D01*
G01X1565521Y1553171D02*
X1562231Y1550014D01*
G01X1565358Y1553241D02*
X1562057Y1550075D01*
G01X1565195Y1553311D02*
X1561884Y1550135D01*
G01X1565031Y1553382D02*
X1561711Y1550197D01*
G01X1564868Y1553452D02*
X1561506Y1550228D01*
G01X1564694Y1553513D02*
X1561294Y1550251D01*
G01X1564516Y1553570D02*
X1561082Y1550275D01*
G01X1564338Y1553626D02*
X1560871Y1550300D01*
G01X1564160Y1553682D02*
X1560658Y1550323D01*
G01X1563982Y1553739D02*
X1560396Y1550299D01*
G01X1563797Y1553789D02*
X1560127Y1550268D01*
G01X1563604Y1553831D02*
X1559857Y1550237D01*
G01X1563410Y1553872D02*
X1559547Y1550166D01*
G01X1563217Y1553914D02*
X1559178Y1550040D01*
G01X1563024Y1553956D02*
X1558810Y1549913D01*
G01X1562824Y1553991D02*
X1558216Y1549571D01*
G01X1573762Y1550937D02*
X1573810Y1551210D01*
G01D02*
X1573858Y1551483D01*
G01X1573714Y1550664D02*
X1573762Y1550937D01*
G01X1573570Y1549844D02*
X1573522Y1549571D01*
G01X1573666Y1550390D02*
X1573714Y1550664D01*
G01X1573618Y1550117D02*
X1573666Y1550390D01*
G01X1573570Y1549844D02*
X1573618Y1550117D01*
G01X1573522Y1549571D02*
X1573474Y1549297D01*
G01X1572659Y1544653D02*
X1572611Y1544380D01*
G01X1572802Y1545472D02*
X1572755Y1545199D01*
G01D02*
X1572707Y1544926D01*
G01X1572946Y1546292D02*
X1572899Y1546019D01*
G01D02*
X1572851Y1545746D01*
G01D02*
X1572802Y1545472D01*
G01X1572707Y1544926D02*
X1572659Y1544653D01*
G01X1573474Y1549297D02*
X1573426Y1549025D01*
G01X1572611Y1544380D02*
X1572563Y1544107D01*
G01D02*
X1572515Y1543833D01*
G01X1573330Y1548478D02*
X1573282Y1548204D01*
G01X1572994Y1546566D02*
X1572946Y1546292D01*
G01X1573282Y1548204D02*
X1573234Y1547931D01*
G01X1573426Y1549025D02*
X1573378Y1548751D01*
G01D02*
X1573330Y1548478D01*
G01X1573234Y1547931D02*
X1573186Y1547659D01*
G01X1573043Y1546838D02*
X1572994Y1546566D01*
G01X1573091Y1547112D02*
X1573043Y1546838D01*
G01X1573186Y1547659D02*
X1573138Y1547385D01*
G01D02*
X1573091Y1547112D01*
G01X1572515Y1543833D02*
X1572467Y1543560D01*
G01D02*
X1572419Y1543287D01*
G01X1574756Y1552345D02*
X1573858Y1551483D01*
G01X1574519Y1552345D02*
X1573906Y1551756D01*
G01X1574282Y1552345D02*
X1573954Y1552030D01*
G01X1574046Y1552345D02*
X1574001Y1552303D01*
G01X1574282Y1552345D02*
X1574046D01*
G01X1573858Y1551483D02*
X1573906Y1551756D01*
G01D02*
X1573954Y1552030D01*
G01X1574009Y1552345D02*
X1574001Y1552303D01*
G01X1574046Y1552345D02*
X1574009D01*
G01X1573954Y1552030D02*
X1574001Y1552303D01*
G01X1574756Y1552345D02*
X1573858Y1551483D01*
G01X1574519Y1552345D02*
X1573906Y1551756D01*
G01X1574282Y1552345D02*
X1573954Y1552030D01*
G01X1574046Y1552345D02*
X1574001Y1552303D01*
G01X1574282Y1552345D02*
X1574046D01*
G01X1573858Y1551483D02*
X1573906Y1551756D01*
G01D02*
X1573954Y1552030D01*
G01X1574009Y1552345D02*
X1574001Y1552303D01*
G01X1574046Y1552345D02*
X1574009D01*
G01X1573954Y1552030D02*
X1574001Y1552303D01*
G01X1590469Y1536290D02*
X1593782Y1539469D01*
G01X1590345Y1536398D02*
X1593672Y1539590D01*
G01X1590221Y1536506D02*
X1593586Y1539734D01*
G01X1590101Y1536619D02*
X1593499Y1539879D01*
G01X1589991Y1536741D02*
X1593446Y1540054D01*
G01X1589882Y1536863D02*
X1593394Y1540232D01*
G01X1589774Y1536986D02*
X1593372Y1540438D01*
G01X1589680Y1537124D02*
X1593357Y1540651D01*
G01X1589586Y1537261D02*
X1593377Y1540897D01*
G01X1589492Y1537398D02*
X1593413Y1541159D01*
G01X1589412Y1537548D02*
X1593538Y1541506D01*
G01X1589334Y1537701D02*
X1593664Y1541854D01*
G01X1589257Y1537854D02*
X1598346Y1546572D01*
G01X1589190Y1538017D02*
X1598146Y1546608D01*
G01X1589131Y1538187D02*
X1597945Y1546642D01*
G01X1589071Y1538357D02*
X1597733Y1546667D01*
G01X1589020Y1538535D02*
X1597508Y1546678D01*
G01X1588979Y1538723D02*
X1597284Y1546690D01*
G01X1585577Y1535460D02*
X1585696Y1535574D01*
G01X1585340Y1535460D02*
X1585745Y1535848D01*
G01X1588939Y1538912D02*
X1597059Y1546702D01*
G01X1585103Y1535460D02*
X1585792Y1536121D01*
G01X1588904Y1539106D02*
X1596835Y1546714D01*
G01X1588886Y1539315D02*
X1596587Y1546703D01*
G01X1584866Y1535460D02*
X1585840Y1536394D01*
G01X1588867Y1539525D02*
X1596334Y1546688D01*
G01X1584630Y1535460D02*
X1585888Y1536667D01*
G01X1584392Y1535460D02*
X1585937Y1536941D01*
G01X1588853Y1539739D02*
X1596081Y1546672D01*
G01X1588859Y1539971D02*
X1595827Y1546656D01*
G01X1584156Y1535460D02*
X1585985Y1537214D01*
G01X1588864Y1540204D02*
X1595574Y1546641D01*
G01X1583919Y1535460D02*
X1586032Y1537487D01*
G01X1583682Y1535460D02*
X1586080Y1537760D01*
G01X1588876Y1540442D02*
X1595310Y1546614D01*
G01X1588908Y1540701D02*
X1595012Y1546556D01*
G01X1583446Y1535460D02*
X1586128Y1538034D01*
G01X1588942Y1540960D02*
X1594714Y1546498D01*
G01X1583208Y1535460D02*
X1586177Y1538308D01*
G01X1582972Y1535460D02*
X1586225Y1538580D01*
G01X1588994Y1541237D02*
X1594417Y1546439D01*
G01X1589081Y1541548D02*
X1594119Y1546381D01*
G01X1582735Y1535460D02*
X1586272Y1538853D01*
G01X1582498Y1535460D02*
X1586320Y1539127D01*
G01X1589168Y1541858D02*
X1593764Y1546267D01*
G01X1589256Y1542170D02*
X1593389Y1546135D01*
G01X1582261Y1535460D02*
X1586369Y1539400D01*
G01X1589365Y1542502D02*
X1593015Y1546003D01*
G01X1582024Y1535460D02*
X1586417Y1539673D01*
G01X1581788Y1535460D02*
X1586465Y1539947D01*
G01X1589603Y1542957D02*
X1592564Y1545797D01*
G01X1581551Y1535460D02*
X1586512Y1540220D01*
G01X1581313Y1535460D02*
X1586560Y1540493D01*
G01X1581271Y1535646D02*
X1586609Y1540767D01*
G01X1581319Y1535920D02*
X1586657Y1541040D01*
G01X1581366Y1536192D02*
X1586705Y1541313D01*
G01X1581415Y1536466D02*
X1586752Y1541586D01*
G01X1580911Y1536209D02*
X1586801Y1541860D01*
G01X1580306Y1535856D02*
X1586849Y1542132D01*
G01X1579836Y1535633D02*
X1586897Y1542406D01*
G01X1579449Y1535488D02*
X1586945Y1542680D01*
G01X1579116Y1535396D02*
X1586992Y1542953D01*
G01X1578782Y1535304D02*
X1587041Y1543226D01*
G01X1578459Y1535221D02*
X1587089Y1543500D01*
G01X1578197Y1535197D02*
X1587137Y1543773D01*
G01X1577935Y1535172D02*
X1587185Y1544046D01*
G01X1577673Y1535149D02*
X1587233Y1544319D01*
G01X1577411Y1535125D02*
X1587281Y1544592D01*
G01X1577161Y1535111D02*
X1587329Y1544866D01*
G01X1576945Y1535132D02*
X1587377Y1545139D01*
G01X1576729Y1535152D02*
X1587425Y1545412D01*
G01X1576513Y1535171D02*
X1587473Y1545685D01*
G01X1587521Y1545959D02*
X1576297Y1535193D01*
G01X1581695Y1540597D02*
X1587569Y1546232D01*
G01X1576081Y1535212D02*
X1580763Y1539704D01*
G01X1581956Y1541074D02*
X1587617Y1546505D01*
G01X1575865Y1535231D02*
X1580302Y1539488D01*
G01X1575666Y1535267D02*
X1579978Y1539405D01*
G01X1582134Y1541473D02*
X1587665Y1546779D01*
G01X1575489Y1535326D02*
X1579666Y1539332D01*
G01X1582255Y1541816D02*
X1587713Y1547053D01*
G01X1587761Y1547325D02*
X1582367Y1542151D01*
G01X1575313Y1535384D02*
X1579411Y1539315D01*
G01X1575137Y1535442D02*
X1579157Y1539298D01*
G01X1587809Y1547598D02*
X1582432Y1542440D01*
G01X1574960Y1535499D02*
X1578918Y1539296D01*
G01X1587857Y1547872D02*
X1582498Y1542731D01*
G01X1574783Y1535558D02*
X1578696Y1539311D01*
G01X1587905Y1548145D02*
X1582563Y1543021D01*
G01X1574607Y1535616D02*
X1578475Y1539327D01*
G01X1574450Y1535693D02*
X1578274Y1539360D01*
G01X1574311Y1535787D02*
X1578088Y1539409D01*
G01X1586752Y1541586D02*
X1586801Y1541860D01*
G01X1585340Y1535460D02*
X1585577D01*
G01X1584392D02*
X1584630D01*
G01D02*
X1584866D01*
G01X1583919D02*
X1584156D01*
G01D02*
X1584392D01*
G01X1585103D02*
X1585340D01*
G01X1584866D02*
X1585103D01*
G01X1583682D02*
X1583919D01*
G01X1581551D02*
X1581788D01*
G01X1583446D02*
X1583682D01*
G01X1582024D02*
X1582261D01*
G01D02*
X1582498D01*
G01X1581788D02*
X1582024D01*
G01X1583208D02*
X1583446D01*
G01X1581313D02*
X1581551D01*
G01X1582972D02*
X1583208D01*
G01X1582735D02*
X1582972D01*
G01X1582498D02*
X1582735D01*
G01X1581415Y1536466D02*
X1581366Y1536192D01*
G01X1581319Y1535920D02*
X1581271Y1535646D01*
G01X1581366Y1536192D02*
X1581319Y1535920D01*
G01X1581239Y1535460D02*
X1581313D01*
G01X1581271Y1535646D02*
X1581239Y1535460D01*
G01X1585840Y1536394D02*
X1585792Y1536121D01*
G01D02*
X1585745Y1535848D01*
G01X1585888Y1536667D02*
X1585840Y1536394D01*
G01X1585745Y1535848D02*
X1585696Y1535574D01*
G01X1585676Y1535460D02*
X1585696Y1535574D01*
G01X1585577Y1535460D02*
X1585676D01*
G01X1586080Y1537760D02*
X1586032Y1537487D01*
G01D02*
X1585985Y1537214D01*
G01D02*
X1585937Y1536941D01*
G01D02*
X1585888Y1536667D01*
G01X1586128Y1538034D02*
X1586080Y1537760D01*
G01X1586849Y1542132D02*
X1586897Y1542406D01*
G01X1586657Y1541040D02*
X1586705Y1541313D01*
G01D02*
X1586752Y1541586D01*
G01X1586801Y1541860D02*
X1586849Y1542132D01*
G01X1586897Y1542406D02*
X1586945Y1542680D01*
G01D02*
X1586992Y1542953D01*
G01D02*
X1587041Y1543226D01*
G01X1586272Y1538853D02*
X1586225Y1538580D01*
G01X1586369Y1539400D02*
X1586320Y1539127D01*
G01D02*
X1586272Y1538853D01*
G01X1586177Y1538308D02*
X1586128Y1538034D01*
G01X1586225Y1538580D02*
X1586177Y1538308D01*
G01X1586417Y1539673D02*
X1586369Y1539400D01*
G01X1586560Y1540493D02*
X1586512Y1540220D01*
G01X1586560Y1540493D02*
X1586609Y1540767D01*
G01X1586465Y1539947D02*
X1586417Y1539673D01*
G01X1586512Y1540220D02*
X1586465Y1539947D01*
G01X1586609Y1540767D02*
X1586657Y1541040D01*
G01X1590469Y1536290D02*
X1593782Y1539469D01*
G01X1590345Y1536398D02*
X1593672Y1539590D01*
G01X1590221Y1536506D02*
X1593586Y1539734D01*
G01X1590101Y1536619D02*
X1593499Y1539879D01*
G01X1589991Y1536741D02*
X1593446Y1540054D01*
G01X1589882Y1536863D02*
X1593394Y1540232D01*
G01X1589774Y1536986D02*
X1593372Y1540438D01*
G01X1589680Y1537124D02*
X1593357Y1540651D01*
G01X1589586Y1537261D02*
X1593377Y1540897D01*
G01X1589492Y1537398D02*
X1593413Y1541159D01*
G01X1589412Y1537548D02*
X1593538Y1541506D01*
G01X1589334Y1537701D02*
X1593664Y1541854D01*
G01X1589257Y1537854D02*
X1598346Y1546572D01*
G01X1589190Y1538017D02*
X1598146Y1546608D01*
G01X1589131Y1538187D02*
X1597945Y1546642D01*
G01X1589071Y1538357D02*
X1597733Y1546667D01*
G01X1589020Y1538535D02*
X1597508Y1546678D01*
G01X1588979Y1538723D02*
X1597284Y1546690D01*
G01X1585577Y1535460D02*
X1585696Y1535574D01*
G01X1585340Y1535460D02*
X1585745Y1535848D01*
G01X1588939Y1538912D02*
X1597059Y1546702D01*
G01X1585103Y1535460D02*
X1585792Y1536121D01*
G01X1588904Y1539106D02*
X1596835Y1546714D01*
G01X1588886Y1539315D02*
X1596587Y1546703D01*
G01X1584866Y1535460D02*
X1585840Y1536394D01*
G01X1588867Y1539525D02*
X1596334Y1546688D01*
G01X1584630Y1535460D02*
X1585888Y1536667D01*
G01X1584392Y1535460D02*
X1585937Y1536941D01*
G01X1588853Y1539739D02*
X1596081Y1546672D01*
G01X1588859Y1539971D02*
X1595827Y1546656D01*
G01X1584156Y1535460D02*
X1585985Y1537214D01*
G01X1588864Y1540204D02*
X1595574Y1546641D01*
G01X1583919Y1535460D02*
X1586032Y1537487D01*
G01X1583682Y1535460D02*
X1586080Y1537760D01*
G01X1588876Y1540442D02*
X1595310Y1546614D01*
G01X1588908Y1540701D02*
X1595012Y1546556D01*
G01X1583446Y1535460D02*
X1586128Y1538034D01*
G01X1588942Y1540960D02*
X1594714Y1546498D01*
G01X1583208Y1535460D02*
X1586177Y1538308D01*
G01X1582972Y1535460D02*
X1586225Y1538580D01*
G01X1588994Y1541237D02*
X1594417Y1546439D01*
G01X1589081Y1541548D02*
X1594119Y1546381D01*
G01X1582735Y1535460D02*
X1586272Y1538853D01*
G01X1582498Y1535460D02*
X1586320Y1539127D01*
G01X1589168Y1541858D02*
X1593764Y1546267D01*
G01X1589256Y1542170D02*
X1593389Y1546135D01*
G01X1582261Y1535460D02*
X1586369Y1539400D01*
G01X1589365Y1542502D02*
X1593015Y1546003D01*
G01X1582024Y1535460D02*
X1586417Y1539673D01*
G01X1581788Y1535460D02*
X1586465Y1539947D01*
G01X1589603Y1542957D02*
X1592564Y1545797D01*
G01X1581551Y1535460D02*
X1586512Y1540220D01*
G01X1581313Y1535460D02*
X1586560Y1540493D01*
G01X1581271Y1535646D02*
X1586609Y1540767D01*
G01X1581319Y1535920D02*
X1586657Y1541040D01*
G01X1581366Y1536192D02*
X1586705Y1541313D01*
G01X1581415Y1536466D02*
X1586752Y1541586D01*
G01X1580911Y1536209D02*
X1586801Y1541860D01*
G01X1580306Y1535856D02*
X1586849Y1542132D01*
G01X1579836Y1535633D02*
X1586897Y1542406D01*
G01X1579449Y1535488D02*
X1586945Y1542680D01*
G01X1579116Y1535396D02*
X1586992Y1542953D01*
G01X1578782Y1535304D02*
X1587041Y1543226D01*
G01X1578459Y1535221D02*
X1587089Y1543500D01*
G01X1578197Y1535197D02*
X1587137Y1543773D01*
G01X1577935Y1535172D02*
X1587185Y1544046D01*
G01X1577673Y1535149D02*
X1587233Y1544319D01*
G01X1577411Y1535125D02*
X1587281Y1544592D01*
G01X1577161Y1535111D02*
X1587329Y1544866D01*
G01X1576945Y1535132D02*
X1587377Y1545139D01*
G01X1576729Y1535152D02*
X1587425Y1545412D01*
G01X1576513Y1535171D02*
X1587473Y1545685D01*
G01X1587521Y1545959D02*
X1576297Y1535193D01*
G01X1581695Y1540597D02*
X1587569Y1546232D01*
G01X1576081Y1535212D02*
X1580763Y1539704D01*
G01X1581956Y1541074D02*
X1587617Y1546505D01*
G01X1575865Y1535231D02*
X1580302Y1539488D01*
G01X1575666Y1535267D02*
X1579978Y1539405D01*
G01X1582134Y1541473D02*
X1587665Y1546779D01*
G01X1575489Y1535326D02*
X1579666Y1539332D01*
G01X1582255Y1541816D02*
X1587713Y1547053D01*
G01X1587761Y1547325D02*
X1582367Y1542151D01*
G01X1575313Y1535384D02*
X1579411Y1539315D01*
G01X1575137Y1535442D02*
X1579157Y1539298D01*
G01X1587809Y1547598D02*
X1582432Y1542440D01*
G01X1574960Y1535499D02*
X1578918Y1539296D01*
G01X1587857Y1547872D02*
X1582498Y1542731D01*
G01X1574783Y1535558D02*
X1578696Y1539311D01*
G01X1587905Y1548145D02*
X1582563Y1543021D01*
G01X1574607Y1535616D02*
X1578475Y1539327D01*
G01X1574450Y1535693D02*
X1578274Y1539360D01*
G01X1574311Y1535787D02*
X1578088Y1539409D01*
G01X1586752Y1541586D02*
X1586801Y1541860D01*
G01X1585340Y1535460D02*
X1585577D01*
G01X1584392D02*
X1584630D01*
G01D02*
X1584866D01*
G01X1583919D02*
X1584156D01*
G01D02*
X1584392D01*
G01X1585103D02*
X1585340D01*
G01X1584866D02*
X1585103D01*
G01X1583682D02*
X1583919D01*
G01X1581551D02*
X1581788D01*
G01X1583446D02*
X1583682D01*
G01X1582024D02*
X1582261D01*
G01D02*
X1582498D01*
G01X1581788D02*
X1582024D01*
G01X1583208D02*
X1583446D01*
G01X1581313D02*
X1581551D01*
G01X1582972D02*
X1583208D01*
G01X1582735D02*
X1582972D01*
G01X1582498D02*
X1582735D01*
G01X1581415Y1536466D02*
X1581366Y1536192D01*
G01X1581319Y1535920D02*
X1581271Y1535646D01*
G01X1581366Y1536192D02*
X1581319Y1535920D01*
G01X1581239Y1535460D02*
X1581313D01*
G01X1581271Y1535646D02*
X1581239Y1535460D01*
G01X1585840Y1536394D02*
X1585792Y1536121D01*
G01D02*
X1585745Y1535848D01*
G01X1585888Y1536667D02*
X1585840Y1536394D01*
G01X1585745Y1535848D02*
X1585696Y1535574D01*
G01X1585676Y1535460D02*
X1585696Y1535574D01*
G01X1585577Y1535460D02*
X1585676D01*
G01X1586080Y1537760D02*
X1586032Y1537487D01*
G01D02*
X1585985Y1537214D01*
G01D02*
X1585937Y1536941D01*
G01D02*
X1585888Y1536667D01*
G01X1586128Y1538034D02*
X1586080Y1537760D01*
G01X1586849Y1542132D02*
X1586897Y1542406D01*
G01X1586657Y1541040D02*
X1586705Y1541313D01*
G01D02*
X1586752Y1541586D01*
G01X1586801Y1541860D02*
X1586849Y1542132D01*
G01X1586897Y1542406D02*
X1586945Y1542680D01*
G01D02*
X1586992Y1542953D01*
G01D02*
X1587041Y1543226D01*
G01X1586272Y1538853D02*
X1586225Y1538580D01*
G01X1586369Y1539400D02*
X1586320Y1539127D01*
G01D02*
X1586272Y1538853D01*
G01X1586177Y1538308D02*
X1586128Y1538034D01*
G01X1586225Y1538580D02*
X1586177Y1538308D01*
G01X1586417Y1539673D02*
X1586369Y1539400D01*
G01X1586560Y1540493D02*
X1586512Y1540220D01*
G01X1586560Y1540493D02*
X1586609Y1540767D01*
G01X1586465Y1539947D02*
X1586417Y1539673D01*
G01X1586512Y1540220D02*
X1586465Y1539947D01*
G01X1586609Y1540767D02*
X1586657Y1541040D01*
G01X1589841Y1543413D02*
X1592012Y1545495D01*
G01X1587953Y1548418D02*
X1582616Y1543299D01*
G01X1588001Y1548691D02*
X1582664Y1543572D01*
G01X1588049Y1548965D02*
X1582712Y1543845D01*
G01X1588097Y1549238D02*
X1582760Y1544119D01*
G01X1588145Y1549512D02*
X1582808Y1544391D01*
G01X1588193Y1549784D02*
X1582856Y1544664D01*
G01X1588241Y1550058D02*
X1582904Y1544938D01*
G01X1588289Y1550331D02*
X1582952Y1545211D01*
G01X1588337Y1550605D02*
X1582999Y1545484D01*
G01X1588385Y1550877D02*
X1583047Y1545757D01*
G01X1588434Y1551151D02*
X1583095Y1546030D01*
G01X1588482Y1551425D02*
X1583143Y1546304D01*
G01X1588529Y1551698D02*
X1583191Y1546576D01*
G01X1588577Y1551971D02*
X1583239Y1546849D01*
G01X1588625Y1552244D02*
X1583287Y1547123D01*
G01X1588493Y1552345D02*
X1583334Y1547396D01*
G01X1588257Y1552345D02*
X1583383Y1547669D01*
G01X1588020Y1552345D02*
X1583430Y1547942D01*
G01X1587783Y1552345D02*
X1583478Y1548215D01*
G01X1587546Y1552345D02*
X1583526Y1548489D01*
G01X1587309Y1552345D02*
X1583574Y1548762D01*
G01X1587072Y1552345D02*
X1583622Y1549034D01*
G01X1586836Y1552345D02*
X1583669Y1549308D01*
G01X1586598Y1552345D02*
X1583718Y1549581D01*
G01X1586362Y1552345D02*
X1583765Y1549854D01*
G01X1586125Y1552345D02*
X1583813Y1550127D01*
G01X1585888Y1552345D02*
X1583861Y1550400D01*
G01X1585651Y1552345D02*
X1583909Y1550674D01*
G01X1585414Y1552345D02*
X1583957Y1550947D01*
G01X1585178Y1552345D02*
X1584004Y1551219D01*
G01X1583383Y1547669D02*
X1583334Y1547396D01*
G01X1587617Y1546505D02*
X1587665Y1546779D01*
G01X1587569Y1546232D02*
X1587617Y1546505D01*
G01X1587137Y1543773D02*
X1587185Y1544046D01*
G01X1587233Y1544319D02*
X1587281Y1544592D01*
G01X1587185Y1544046D02*
X1587233Y1544319D01*
G01X1587521Y1545959D02*
X1587473Y1545685D01*
G01X1587329Y1544866D02*
X1587377Y1545139D01*
G01X1587473Y1545685D02*
X1587425Y1545412D01*
G01X1587377Y1545139D02*
X1587425Y1545412D01*
G01X1577034Y1544305D02*
X1577082Y1544579D01*
G01X1576890Y1543485D02*
X1576938Y1543759D01*
G01X1577082Y1544579D02*
X1577130Y1544852D01*
G01X1576842Y1543213D02*
X1576890Y1543485D01*
G01X1576985Y1544032D02*
X1577034Y1544305D01*
G01X1577225Y1545398D02*
X1577274Y1545671D01*
G01X1577177Y1545125D02*
X1577225Y1545398D01*
G01X1577130Y1544852D02*
X1577177Y1545125D01*
G01X1587281Y1544592D02*
X1587329Y1544866D01*
G01X1587521Y1545959D02*
X1587569Y1546232D01*
G01X1577321Y1545944D02*
X1577369Y1546218D01*
G01D02*
X1577417Y1546491D01*
G01X1587953Y1548418D02*
X1588001Y1548691D01*
G01X1587905Y1548145D02*
X1587953Y1548418D01*
G01X1588097Y1549238D02*
X1588145Y1549512D01*
G01X1588049Y1548965D02*
X1588097Y1549238D01*
G01X1587713Y1547053D02*
X1587761Y1547325D01*
G01X1587809Y1547598D02*
X1587857Y1547872D01*
G01D02*
X1587905Y1548145D01*
G01X1587761Y1547325D02*
X1587809Y1547598D01*
G01X1588001Y1548691D02*
X1588049Y1548965D01*
G01X1588434Y1551151D02*
X1588482Y1551425D01*
G01X1588145Y1549512D02*
X1588193Y1549784D01*
G01X1588241Y1550058D02*
X1588289Y1550331D01*
G01X1588193Y1549784D02*
X1588241Y1550058D01*
G01X1588385Y1550877D02*
X1588434Y1551151D01*
G01X1588337Y1550605D02*
X1588385Y1550877D01*
G01X1588289Y1550331D02*
X1588337Y1550605D01*
G01X1577705Y1548130D02*
X1577753Y1548403D01*
G01X1577417Y1546491D02*
X1577466Y1546764D01*
G01X1577801Y1548677D02*
X1577849Y1548950D01*
G01X1577657Y1547857D02*
X1577705Y1548130D01*
G01X1577753Y1548403D02*
X1577801Y1548677D01*
G01X1577609Y1547584D02*
X1577657Y1547857D01*
G01X1577466Y1546764D02*
X1577513Y1547038D01*
G01X1577561Y1547311D02*
X1577609Y1547584D01*
G01X1577849Y1548950D02*
X1577897Y1549223D01*
G01X1577513Y1547038D02*
X1577561Y1547311D01*
G01X1578233Y1551135D02*
X1578281Y1551409D01*
G01X1578184Y1550862D02*
X1578233Y1551135D01*
G01X1577993Y1549769D02*
X1578041Y1550043D01*
G01X1577897Y1549223D02*
X1577945Y1549497D01*
G01D02*
X1577993Y1549769D01*
G01X1578089Y1550316D02*
X1578137Y1550590D01*
G01D02*
X1578184Y1550862D01*
G01X1578041Y1550043D02*
X1578089Y1550316D01*
G01X1576938Y1543759D02*
X1576985Y1544032D01*
G01X1587089Y1543500D02*
X1587137Y1543773D01*
G01X1582712Y1543845D02*
X1582664Y1543572D01*
G01X1587713Y1547053D02*
X1587665Y1546779D01*
G01X1582664Y1543572D02*
X1582616Y1543299D01*
G01X1582760Y1544119D02*
X1582712Y1543845D01*
G01X1587041Y1543226D02*
X1587089Y1543500D01*
G01X1583191Y1546576D02*
X1583143Y1546304D01*
G01X1582808Y1544391D02*
X1582760Y1544119D01*
G01X1583861Y1550400D02*
X1583909Y1550674D01*
G01X1577321Y1545944D02*
X1577274Y1545671D01*
G01X1583957Y1550947D02*
X1584004Y1551219D01*
G01D02*
X1584053Y1551493D01*
G01X1583909Y1550674D02*
X1583957Y1550947D01*
G01X1583813Y1550127D02*
X1583861Y1550400D01*
G01X1583143Y1546304D02*
X1583095Y1546030D01*
G01X1583287Y1547123D02*
X1583239Y1546849D01*
G01X1583095Y1546030D02*
X1583047Y1545757D01*
G01X1583239Y1546849D02*
X1583191Y1546576D01*
G01X1582904Y1544938D02*
X1582856Y1544664D01*
G01D02*
X1582808Y1544391D01*
G01X1583047Y1545757D02*
X1582999Y1545484D01*
G01X1582952Y1545211D02*
X1582904Y1544938D01*
G01X1582999Y1545484D02*
X1582952Y1545211D01*
G01X1583765Y1549854D02*
X1583813Y1550127D01*
G01X1583622Y1549034D02*
X1583574Y1548762D01*
G01X1583669Y1549308D02*
X1583622Y1549034D01*
G01X1583718Y1549581D02*
X1583765Y1549854D01*
G01X1583718Y1549581D02*
X1583669Y1549308D01*
G01X1583526Y1548489D02*
X1583478Y1548215D01*
G01X1583334Y1547396D02*
X1583287Y1547123D01*
G01X1583430Y1547942D02*
X1583383Y1547669D01*
G01X1583478Y1548215D02*
X1583430Y1547942D01*
G01X1583574Y1548762D02*
X1583526Y1548489D01*
G01X1589841Y1543413D02*
X1592012Y1545495D01*
G01X1587953Y1548418D02*
X1582616Y1543299D01*
G01X1588001Y1548691D02*
X1582664Y1543572D01*
G01X1588049Y1548965D02*
X1582712Y1543845D01*
G01X1588097Y1549238D02*
X1582760Y1544119D01*
G01X1588145Y1549512D02*
X1582808Y1544391D01*
G01X1588193Y1549784D02*
X1582856Y1544664D01*
G01X1588241Y1550058D02*
X1582904Y1544938D01*
G01X1588289Y1550331D02*
X1582952Y1545211D01*
G01X1588337Y1550605D02*
X1582999Y1545484D01*
G01X1588385Y1550877D02*
X1583047Y1545757D01*
G01X1588434Y1551151D02*
X1583095Y1546030D01*
G01X1588482Y1551425D02*
X1583143Y1546304D01*
G01X1588529Y1551698D02*
X1583191Y1546576D01*
G01X1588577Y1551971D02*
X1583239Y1546849D01*
G01X1588625Y1552244D02*
X1583287Y1547123D01*
G01X1588493Y1552345D02*
X1583334Y1547396D01*
G01X1588257Y1552345D02*
X1583383Y1547669D01*
G01X1588020Y1552345D02*
X1583430Y1547942D01*
G01X1587783Y1552345D02*
X1583478Y1548215D01*
G01X1587546Y1552345D02*
X1583526Y1548489D01*
G01X1587309Y1552345D02*
X1583574Y1548762D01*
G01X1587072Y1552345D02*
X1583622Y1549034D01*
G01X1586836Y1552345D02*
X1583669Y1549308D01*
G01X1586598Y1552345D02*
X1583718Y1549581D01*
G01X1586362Y1552345D02*
X1583765Y1549854D01*
G01X1586125Y1552345D02*
X1583813Y1550127D01*
G01X1585888Y1552345D02*
X1583861Y1550400D01*
G01X1585651Y1552345D02*
X1583909Y1550674D01*
G01X1585414Y1552345D02*
X1583957Y1550947D01*
G01X1585178Y1552345D02*
X1584004Y1551219D01*
G01X1583383Y1547669D02*
X1583334Y1547396D01*
G01X1587617Y1546505D02*
X1587665Y1546779D01*
G01X1587569Y1546232D02*
X1587617Y1546505D01*
G01X1587137Y1543773D02*
X1587185Y1544046D01*
G01X1587233Y1544319D02*
X1587281Y1544592D01*
G01X1587185Y1544046D02*
X1587233Y1544319D01*
G01X1587521Y1545959D02*
X1587473Y1545685D01*
G01X1587329Y1544866D02*
X1587377Y1545139D01*
G01X1587473Y1545685D02*
X1587425Y1545412D01*
G01X1587377Y1545139D02*
X1587425Y1545412D01*
G01X1577034Y1544305D02*
X1577082Y1544579D01*
G01X1576890Y1543485D02*
X1576938Y1543759D01*
G01X1577082Y1544579D02*
X1577130Y1544852D01*
G01X1576842Y1543213D02*
X1576890Y1543485D01*
G01X1576985Y1544032D02*
X1577034Y1544305D01*
G01X1577225Y1545398D02*
X1577274Y1545671D01*
G01X1577177Y1545125D02*
X1577225Y1545398D01*
G01X1577130Y1544852D02*
X1577177Y1545125D01*
G01X1587281Y1544592D02*
X1587329Y1544866D01*
G01X1587521Y1545959D02*
X1587569Y1546232D01*
G01X1577321Y1545944D02*
X1577369Y1546218D01*
G01D02*
X1577417Y1546491D01*
G01X1587953Y1548418D02*
X1588001Y1548691D01*
G01X1587905Y1548145D02*
X1587953Y1548418D01*
G01X1588097Y1549238D02*
X1588145Y1549512D01*
G01X1588049Y1548965D02*
X1588097Y1549238D01*
G01X1587713Y1547053D02*
X1587761Y1547325D01*
G01X1587809Y1547598D02*
X1587857Y1547872D01*
G01D02*
X1587905Y1548145D01*
G01X1587761Y1547325D02*
X1587809Y1547598D01*
G01X1588001Y1548691D02*
X1588049Y1548965D01*
G01X1588434Y1551151D02*
X1588482Y1551425D01*
G01X1588145Y1549512D02*
X1588193Y1549784D01*
G01X1588241Y1550058D02*
X1588289Y1550331D01*
G01X1588193Y1549784D02*
X1588241Y1550058D01*
G01X1588385Y1550877D02*
X1588434Y1551151D01*
G01X1588337Y1550605D02*
X1588385Y1550877D01*
G01X1588289Y1550331D02*
X1588337Y1550605D01*
G01X1577705Y1548130D02*
X1577753Y1548403D01*
G01X1577417Y1546491D02*
X1577466Y1546764D01*
G01X1577801Y1548677D02*
X1577849Y1548950D01*
G01X1577657Y1547857D02*
X1577705Y1548130D01*
G01X1577753Y1548403D02*
X1577801Y1548677D01*
G01X1577609Y1547584D02*
X1577657Y1547857D01*
G01X1577466Y1546764D02*
X1577513Y1547038D01*
G01X1577561Y1547311D02*
X1577609Y1547584D01*
G01X1577849Y1548950D02*
X1577897Y1549223D01*
G01X1577513Y1547038D02*
X1577561Y1547311D01*
G01X1578233Y1551135D02*
X1578281Y1551409D01*
G01X1578184Y1550862D02*
X1578233Y1551135D01*
G01X1577993Y1549769D02*
X1578041Y1550043D01*
G01X1577897Y1549223D02*
X1577945Y1549497D01*
G01D02*
X1577993Y1549769D01*
G01X1578089Y1550316D02*
X1578137Y1550590D01*
G01D02*
X1578184Y1550862D01*
G01X1578041Y1550043D02*
X1578089Y1550316D01*
G01X1576938Y1543759D02*
X1576985Y1544032D01*
G01X1587089Y1543500D02*
X1587137Y1543773D01*
G01X1582712Y1543845D02*
X1582664Y1543572D01*
G01X1587713Y1547053D02*
X1587665Y1546779D01*
G01X1582664Y1543572D02*
X1582616Y1543299D01*
G01X1582760Y1544119D02*
X1582712Y1543845D01*
G01X1587041Y1543226D02*
X1587089Y1543500D01*
G01X1583191Y1546576D02*
X1583143Y1546304D01*
G01X1582808Y1544391D02*
X1582760Y1544119D01*
G01X1583861Y1550400D02*
X1583909Y1550674D01*
G01X1577321Y1545944D02*
X1577274Y1545671D01*
G01X1583957Y1550947D02*
X1584004Y1551219D01*
G01D02*
X1584053Y1551493D01*
G01X1583909Y1550674D02*
X1583957Y1550947D01*
G01X1583813Y1550127D02*
X1583861Y1550400D01*
G01X1583143Y1546304D02*
X1583095Y1546030D01*
G01X1583287Y1547123D02*
X1583239Y1546849D01*
G01X1583095Y1546030D02*
X1583047Y1545757D01*
G01X1583239Y1546849D02*
X1583191Y1546576D01*
G01X1582904Y1544938D02*
X1582856Y1544664D01*
G01D02*
X1582808Y1544391D01*
G01X1583047Y1545757D02*
X1582999Y1545484D01*
G01X1582952Y1545211D02*
X1582904Y1544938D01*
G01X1582999Y1545484D02*
X1582952Y1545211D01*
G01X1583765Y1549854D02*
X1583813Y1550127D01*
G01X1583622Y1549034D02*
X1583574Y1548762D01*
G01X1583669Y1549308D02*
X1583622Y1549034D01*
G01X1583718Y1549581D02*
X1583765Y1549854D01*
G01X1583718Y1549581D02*
X1583669Y1549308D01*
G01X1583526Y1548489D02*
X1583478Y1548215D01*
G01X1583334Y1547396D02*
X1583287Y1547123D01*
G01X1583430Y1547942D02*
X1583383Y1547669D01*
G01X1583478Y1548215D02*
X1583430Y1547942D01*
G01X1583574Y1548762D02*
X1583526Y1548489D01*
G01X1584941Y1552345D02*
X1584053Y1551493D01*
G01X1584704Y1552345D02*
X1584101Y1551766D01*
G01X1584467Y1552345D02*
X1584148Y1552039D01*
G01X1584230Y1552345D02*
X1584196Y1552312D01*
G01X1587072Y1552345D02*
X1586836D01*
G01X1587309D02*
X1587072D01*
G01X1586598D02*
X1586362D01*
G01D02*
X1586125D01*
G01X1588257D02*
X1588020D01*
G01X1587546D02*
X1587309D01*
G01X1588020D02*
X1587783D01*
G01D02*
X1587546D01*
G01X1585178D02*
X1584941D01*
G01D02*
X1584704D01*
G01D02*
X1584467D01*
G01D02*
X1584230D01*
G01X1585888D02*
X1585651D01*
G01X1585414D02*
X1585178D01*
G01X1588493D02*
X1588257D01*
G01X1585651D02*
X1585414D01*
G01X1586125D02*
X1585888D01*
G01X1588643D02*
X1588493D01*
G01X1588625Y1552244D02*
X1588643Y1552345D01*
G01X1588482Y1551425D02*
X1588529Y1551698D01*
G01D02*
X1588577Y1551971D01*
G01D02*
X1588625Y1552244D01*
G01X1586836Y1552345D02*
X1586598D01*
G01X1577361D02*
X1577124D01*
G01D02*
X1576888D01*
G01X1576414D02*
X1576177D01*
G01X1576888D02*
X1576651D01*
G01D02*
X1576414D01*
G01X1578309D02*
X1578072D01*
G01D02*
X1577835D01*
G01X1577598D02*
X1577361D01*
G01X1577835D02*
X1577598D01*
G01X1578445D02*
X1578309D01*
G01X1578424Y1552228D02*
X1578445Y1552345D01*
G01X1574519D02*
X1574282D01*
G01X1576177D02*
X1575940D01*
G01X1574756D02*
X1574519D01*
G01X1575940D02*
X1575704D01*
G01D02*
X1575466D01*
G01D02*
X1575230D01*
G01X1574993D02*
X1574756D01*
G01X1575230D02*
X1574993D01*
G01X1578376Y1551956D02*
X1578424Y1552228D01*
G01X1578328Y1551682D02*
X1578376Y1551956D01*
G01X1578281Y1551409D02*
X1578328Y1551682D01*
G01X1584148Y1552039D02*
X1584196Y1552312D01*
G01X1584053Y1551493D02*
X1584101Y1551766D01*
G01X1584202Y1552345D02*
X1584196Y1552312D01*
G01X1584230Y1552345D02*
X1584202D01*
G01X1584101Y1551766D02*
X1584148Y1552039D01*
G01X1584941Y1552345D02*
X1584053Y1551493D01*
G01X1584704Y1552345D02*
X1584101Y1551766D01*
G01X1584467Y1552345D02*
X1584148Y1552039D01*
G01X1584230Y1552345D02*
X1584196Y1552312D01*
G01X1587072Y1552345D02*
X1586836D01*
G01X1587309D02*
X1587072D01*
G01X1586598D02*
X1586362D01*
G01D02*
X1586125D01*
G01X1588257D02*
X1588020D01*
G01X1587546D02*
X1587309D01*
G01X1588020D02*
X1587783D01*
G01D02*
X1587546D01*
G01X1585178D02*
X1584941D01*
G01D02*
X1584704D01*
G01D02*
X1584467D01*
G01D02*
X1584230D01*
G01X1585888D02*
X1585651D01*
G01X1585414D02*
X1585178D01*
G01X1588493D02*
X1588257D01*
G01X1585651D02*
X1585414D01*
G01X1586125D02*
X1585888D01*
G01X1588643D02*
X1588493D01*
G01X1588625Y1552244D02*
X1588643Y1552345D01*
G01X1588482Y1551425D02*
X1588529Y1551698D01*
G01D02*
X1588577Y1551971D01*
G01D02*
X1588625Y1552244D01*
G01X1586836Y1552345D02*
X1586598D01*
G01X1577361D02*
X1577124D01*
G01D02*
X1576888D01*
G01X1576414D02*
X1576177D01*
G01X1576888D02*
X1576651D01*
G01D02*
X1576414D01*
G01X1578309D02*
X1578072D01*
G01D02*
X1577835D01*
G01X1577598D02*
X1577361D01*
G01X1577835D02*
X1577598D01*
G01X1578445D02*
X1578309D01*
G01X1578424Y1552228D02*
X1578445Y1552345D01*
G01X1574519D02*
X1574282D01*
G01X1576177D02*
X1575940D01*
G01X1574756D02*
X1574519D01*
G01X1575940D02*
X1575704D01*
G01D02*
X1575466D01*
G01D02*
X1575230D01*
G01X1574993D02*
X1574756D01*
G01X1575230D02*
X1574993D01*
G01X1578376Y1551956D02*
X1578424Y1552228D01*
G01X1578328Y1551682D02*
X1578376Y1551956D01*
G01X1578281Y1551409D02*
X1578328Y1551682D01*
G01X1584148Y1552039D02*
X1584196Y1552312D01*
G01X1584053Y1551493D02*
X1584101Y1551766D01*
G01X1584202Y1552345D02*
X1584196Y1552312D01*
G01X1584230Y1552345D02*
X1584202D01*
G01X1584101Y1551766D02*
X1584148Y1552039D01*
G01X1606658Y1535460D02*
X1610423Y1539073D01*
G01X1606421Y1535460D02*
X1610472Y1539346D01*
G01X1606183Y1535460D02*
X1610521Y1539620D01*
G01X1605946Y1535460D02*
X1610568Y1539894D01*
G01X1605710Y1535460D02*
X1610616Y1540167D01*
G01X1605473Y1535460D02*
X1610665Y1540440D01*
G01X1605374Y1535591D02*
X1610713Y1540714D01*
G01X1605421Y1535865D02*
X1610761Y1540987D01*
G01X1605470Y1536138D02*
X1610808Y1541260D01*
G01X1605517Y1536411D02*
X1610857Y1541533D01*
G01X1605565Y1536685D02*
X1610905Y1541807D01*
G01X1605614Y1536959D02*
X1610952Y1542080D01*
G01X1605661Y1537231D02*
X1611001Y1542353D01*
G01X1605709Y1537504D02*
X1611050Y1542627D01*
G01X1605757Y1537778D02*
X1611097Y1542900D01*
G01X1605806Y1538051D02*
X1611145Y1543174D01*
G01X1605852Y1538324D02*
X1611194Y1543447D01*
G01X1611241Y1543720D02*
X1605901Y1538597D01*
G01X1602394Y1535460D02*
X1602527Y1535586D01*
G01X1611289Y1543993D02*
X1605950Y1538870D01*
G01X1611337Y1544267D02*
X1605997Y1539144D01*
G01X1602156Y1535460D02*
X1602574Y1535860D01*
G01X1611386Y1544540D02*
X1606045Y1539417D01*
G01X1601920Y1535460D02*
X1602622Y1536133D01*
G01X1601684Y1535460D02*
X1602670Y1536406D01*
G01X1611440Y1544820D02*
X1606094Y1539690D01*
G01X1601446Y1535460D02*
X1602716Y1536679D01*
G01X1611506Y1545110D02*
X1606141Y1539964D01*
G01X1611571Y1545399D02*
X1606189Y1540237D01*
G01X1601209Y1535460D02*
X1602765Y1536953D01*
G01X1611634Y1545687D02*
X1606238Y1540510D01*
G01X1600972Y1535460D02*
X1602814Y1537226D01*
G01X1600736Y1535460D02*
X1602860Y1537498D01*
G01X1611752Y1546027D02*
X1606285Y1540783D01*
G01X1600499Y1535460D02*
X1602909Y1537772D01*
G01X1611872Y1546370D02*
X1606332Y1541056D01*
G01X1612062Y1546779D02*
X1606381Y1541330D01*
G01X1600262Y1535460D02*
X1602958Y1538045D01*
G01X1612376Y1547308D02*
X1606429Y1541603D01*
G01X1600026Y1535460D02*
X1603004Y1538318D01*
G01X1599789Y1535460D02*
X1603053Y1538591D01*
G01X1617671Y1552615D02*
X1606476Y1541875D01*
G01X1617454Y1552635D02*
X1606525Y1542149D01*
G01X1599551Y1535460D02*
X1603100Y1538864D01*
G01X1599314Y1535460D02*
X1603148Y1539138D01*
G01X1617239Y1552654D02*
X1606573Y1542423D01*
G01X1617023Y1552675D02*
X1606620Y1542695D01*
G01X1599077Y1535460D02*
X1603197Y1539411D01*
G01X1598841Y1535460D02*
X1603244Y1539684D01*
G01X1616806Y1552694D02*
X1606669Y1542969D01*
G01X1598604Y1535460D02*
X1603292Y1539958D01*
G01X1598367Y1535460D02*
X1603340Y1540231D01*
G01X1598131Y1535460D02*
X1603388Y1540503D01*
G01X1598097Y1535655D02*
X1603435Y1540777D01*
G01X1598146Y1535929D02*
X1603484Y1541050D01*
G01X1598194Y1536203D02*
X1603532Y1541323D01*
G01X1598243Y1536476D02*
X1603579Y1541596D01*
G01X1597696Y1536179D02*
X1603628Y1541869D01*
G01X1597099Y1535834D02*
X1603675Y1542143D01*
G01X1596625Y1535606D02*
X1603723Y1542416D01*
G01X1596244Y1535468D02*
X1603772Y1542689D01*
G01X1595907Y1535372D02*
X1603819Y1542962D01*
G01X1595570Y1535277D02*
X1603867Y1543235D01*
G01X1595263Y1535209D02*
X1603915Y1543508D01*
G01X1595000Y1535185D02*
X1603963Y1543782D01*
G01X1594736Y1535157D02*
X1604010Y1544054D01*
G01X1594473Y1535133D02*
X1604059Y1544328D01*
G01X1594209Y1535106D02*
X1604107Y1544602D01*
G01X1593982Y1535115D02*
X1604154Y1544874D01*
G01X1593754Y1535125D02*
X1604203Y1545147D01*
G01X1604251Y1545421D02*
X1593533Y1535140D01*
G01X1593322Y1535166D02*
X1597880Y1539537D01*
G01X1604298Y1545694D02*
X1598965Y1540577D01*
G01X1593112Y1535190D02*
X1597359Y1539264D01*
G01X1604347Y1545967D02*
X1599012Y1540850D01*
G01X1592912Y1535225D02*
X1596977Y1539125D01*
G01X1604394Y1546240D02*
X1599060Y1541123D01*
G01X1604442Y1546513D02*
X1599108Y1541397D01*
G01X1592717Y1535266D02*
X1596603Y1538994D01*
G01X1592522Y1535305D02*
X1596332Y1538961D01*
G01X1604489Y1546787D02*
X1599156Y1541670D01*
G01X1592339Y1535358D02*
X1596061Y1538927D01*
G01X1604510Y1547033D02*
X1599204Y1541943D01*
G01X1592159Y1535412D02*
X1595790Y1538894D01*
G01X1604530Y1547279D02*
X1599252Y1542216D01*
G01X1591978Y1535467D02*
X1595529Y1538872D01*
G01X1604550Y1547526D02*
X1599300Y1542490D01*
G01X1604569Y1547772D02*
X1599190Y1542612D01*
G01X1591810Y1535532D02*
X1595309Y1538888D01*
G01X1591644Y1535600D02*
X1595089Y1538904D01*
G01X1604590Y1548018D02*
X1599050Y1542703D01*
G01X1604583Y1548239D02*
X1598898Y1542785D01*
G01X1591478Y1535667D02*
X1594879Y1538929D01*
G01X1591323Y1535746D02*
X1594692Y1538978D01*
G01X1604556Y1548440D02*
X1598742Y1542864D01*
G01X1604529Y1548641D02*
X1598578Y1542933D01*
G01X1591171Y1535827D02*
X1594506Y1539027D01*
G01X1604501Y1548842D02*
X1598406Y1542995D01*
G01X1591019Y1535909D02*
X1594335Y1539090D01*
G01X1590876Y1535999D02*
X1594182Y1539170D01*
G01X1604473Y1549042D02*
X1598227Y1543050D01*
G01X1590738Y1536093D02*
X1594029Y1539251D01*
G01X1590600Y1536188D02*
X1593902Y1539357D01*
G01X1594727Y1542874D02*
X1598546Y1546538D01*
G01X1605806Y1538051D02*
X1605757Y1537778D01*
G01X1605852Y1538324D02*
X1605806Y1538051D01*
G01X1605901Y1538597D02*
X1605852Y1538324D01*
G01X1605901Y1538597D02*
X1605950Y1538870D01*
G01X1605757Y1537778D02*
X1605709Y1537504D01*
G01D02*
X1605661Y1537231D01*
G01X1605470Y1536138D02*
X1605421Y1535865D01*
G01X1605710Y1535460D02*
X1605946D01*
G01X1605350D02*
X1605473D01*
G01X1605374Y1535591D02*
X1605350Y1535460D01*
G01X1605421Y1535865D02*
X1605374Y1535591D01*
G01X1605661Y1537231D02*
X1605614Y1536959D01*
G01D02*
X1605565Y1536685D01*
G01D02*
X1605517Y1536411D01*
G01D02*
X1605470Y1536138D01*
G01X1605473Y1535460D02*
X1605710D01*
G01X1606658D02*
X1606894D01*
G01X1606421D02*
X1606658D01*
G01X1606183D02*
X1606421D01*
G01X1605946D02*
X1606183D01*
G01X1606332Y1541056D02*
X1606285Y1540783D01*
G01X1606189Y1540237D02*
X1606141Y1539964D01*
G01X1606094Y1539690D02*
X1606045Y1539417D01*
G01X1606285Y1540783D02*
X1606238Y1540510D01*
G01D02*
X1606189Y1540237D01*
G01X1606141Y1539964D02*
X1606094Y1539690D01*
G01X1606045Y1539417D02*
X1605997Y1539144D01*
G01D02*
X1605950Y1538870D01*
G01X1606381Y1541330D02*
X1606332Y1541056D01*
G01X1606476Y1541875D02*
X1606429Y1541603D01*
G01D02*
X1606381Y1541330D01*
G01X1606573Y1542423D02*
X1606525Y1542149D01*
G01X1606669Y1542969D02*
X1606620Y1542695D01*
G01D02*
X1606573Y1542423D01*
G01X1606525Y1542149D02*
X1606476Y1541875D01*
G01X1606716Y1543242D02*
X1606669Y1542969D01*
G01X1599012Y1540850D02*
X1598965Y1540577D01*
G01X1599252Y1542216D02*
X1599204Y1541943D01*
G01X1599300Y1542490D02*
X1599252Y1542216D01*
G01X1603579Y1541596D02*
X1603628Y1541869D01*
G01X1599156Y1541670D02*
X1599108Y1541397D01*
G01D02*
X1599060Y1541123D01*
G01X1599204Y1541943D02*
X1599156Y1541670D01*
G01X1599060Y1541123D02*
X1599012Y1540850D01*
G01X1603388Y1540503D02*
X1603435Y1540777D01*
G01X1600262Y1535460D02*
X1600499D01*
G01X1600736D02*
X1600972D01*
G01D02*
X1601209D01*
G01X1600499D02*
X1600736D01*
G01X1601920D02*
X1602156D01*
G01D02*
X1602394D01*
G01X1601446D02*
X1601684D01*
G01D02*
X1601920D01*
G01X1600026D02*
X1600262D01*
G01X1601209D02*
X1601446D01*
G01X1599789D02*
X1600026D01*
G01X1598604D02*
X1598841D01*
G01X1598367D02*
X1598604D01*
G01X1598063D02*
X1598131D01*
G01X1598097Y1535655D02*
X1598063Y1535460D01*
G01X1598131D02*
X1598367D01*
G01X1598146Y1535929D02*
X1598097Y1535655D01*
G01X1599551Y1535460D02*
X1599789D01*
G01X1599077D02*
X1599314D01*
G01X1598841D02*
X1599077D01*
G01X1599314D02*
X1599551D01*
G01X1598243Y1536476D02*
X1598194Y1536203D01*
G01D02*
X1598146Y1535929D01*
G01X1603197Y1539411D02*
X1603244Y1539684D01*
G01X1603484Y1541050D02*
X1603532Y1541323D01*
G01D02*
X1603579Y1541596D01*
G01X1603340Y1540231D02*
X1603388Y1540503D01*
G01X1603435Y1540777D02*
X1603484Y1541050D01*
G01X1603675Y1542143D02*
X1603723Y1542416D01*
G01X1603628Y1541869D02*
X1603675Y1542143D01*
G01X1603004Y1538318D02*
X1603053Y1538591D01*
G01X1602814Y1537226D02*
X1602860Y1537498D01*
G01X1602958Y1538045D02*
X1603004Y1538318D01*
G01X1602909Y1537772D02*
X1602958Y1538045D01*
G01X1602860Y1537498D02*
X1602909Y1537772D01*
G01X1603148Y1539138D02*
X1603197Y1539411D01*
G01X1603244Y1539684D02*
X1603292Y1539958D01*
G01D02*
X1603340Y1540231D01*
G01X1603100Y1538864D02*
X1603148Y1539138D01*
G01X1603053Y1538591D02*
X1603100Y1538864D01*
G01X1603772Y1542689D02*
X1603819Y1542962D01*
G01D02*
X1603867Y1543235D01*
G01X1603723Y1542416D02*
X1603772Y1542689D01*
G01X1602765Y1536953D02*
X1602814Y1537226D01*
G01X1602504Y1535460D02*
X1602527Y1535586D01*
G01X1602394Y1535460D02*
X1602504D01*
G01X1602527Y1535586D02*
X1602574Y1535860D01*
G01X1602670Y1536406D02*
X1602716Y1536679D01*
G01D02*
X1602765Y1536953D01*
G01X1602574Y1535860D02*
X1602622Y1536133D01*
G01D02*
X1602670Y1536406D01*
G01X1606658Y1535460D02*
X1610423Y1539073D01*
G01X1606421Y1535460D02*
X1610472Y1539346D01*
G01X1606183Y1535460D02*
X1610521Y1539620D01*
G01X1605946Y1535460D02*
X1610568Y1539894D01*
G01X1605710Y1535460D02*
X1610616Y1540167D01*
G01X1605473Y1535460D02*
X1610665Y1540440D01*
G01X1605374Y1535591D02*
X1610713Y1540714D01*
G01X1605421Y1535865D02*
X1610761Y1540987D01*
G01X1605470Y1536138D02*
X1610808Y1541260D01*
G01X1605517Y1536411D02*
X1610857Y1541533D01*
G01X1605565Y1536685D02*
X1610905Y1541807D01*
G01X1605614Y1536959D02*
X1610952Y1542080D01*
G01X1605661Y1537231D02*
X1611001Y1542353D01*
G01X1605709Y1537504D02*
X1611050Y1542627D01*
G01X1605757Y1537778D02*
X1611097Y1542900D01*
G01X1605806Y1538051D02*
X1611145Y1543174D01*
G01X1605852Y1538324D02*
X1611194Y1543447D01*
G01X1611241Y1543720D02*
X1605901Y1538597D01*
G01X1602394Y1535460D02*
X1602527Y1535586D01*
G01X1611289Y1543993D02*
X1605950Y1538870D01*
G01X1611337Y1544267D02*
X1605997Y1539144D01*
G01X1602156Y1535460D02*
X1602574Y1535860D01*
G01X1611386Y1544540D02*
X1606045Y1539417D01*
G01X1601920Y1535460D02*
X1602622Y1536133D01*
G01X1601684Y1535460D02*
X1602670Y1536406D01*
G01X1611440Y1544820D02*
X1606094Y1539690D01*
G01X1601446Y1535460D02*
X1602716Y1536679D01*
G01X1611506Y1545110D02*
X1606141Y1539964D01*
G01X1611571Y1545399D02*
X1606189Y1540237D01*
G01X1601209Y1535460D02*
X1602765Y1536953D01*
G01X1611634Y1545687D02*
X1606238Y1540510D01*
G01X1600972Y1535460D02*
X1602814Y1537226D01*
G01X1600736Y1535460D02*
X1602860Y1537498D01*
G01X1611752Y1546027D02*
X1606285Y1540783D01*
G01X1600499Y1535460D02*
X1602909Y1537772D01*
G01X1611872Y1546370D02*
X1606332Y1541056D01*
G01X1612062Y1546779D02*
X1606381Y1541330D01*
G01X1600262Y1535460D02*
X1602958Y1538045D01*
G01X1612376Y1547308D02*
X1606429Y1541603D01*
G01X1600026Y1535460D02*
X1603004Y1538318D01*
G01X1599789Y1535460D02*
X1603053Y1538591D01*
G01X1617671Y1552615D02*
X1606476Y1541875D01*
G01X1617454Y1552635D02*
X1606525Y1542149D01*
G01X1599551Y1535460D02*
X1603100Y1538864D01*
G01X1599314Y1535460D02*
X1603148Y1539138D01*
G01X1617239Y1552654D02*
X1606573Y1542423D01*
G01X1617023Y1552675D02*
X1606620Y1542695D01*
G01X1599077Y1535460D02*
X1603197Y1539411D01*
G01X1598841Y1535460D02*
X1603244Y1539684D01*
G01X1616806Y1552694D02*
X1606669Y1542969D01*
G01X1598604Y1535460D02*
X1603292Y1539958D01*
G01X1598367Y1535460D02*
X1603340Y1540231D01*
G01X1598131Y1535460D02*
X1603388Y1540503D01*
G01X1598097Y1535655D02*
X1603435Y1540777D01*
G01X1598146Y1535929D02*
X1603484Y1541050D01*
G01X1598194Y1536203D02*
X1603532Y1541323D01*
G01X1598243Y1536476D02*
X1603579Y1541596D01*
G01X1597696Y1536179D02*
X1603628Y1541869D01*
G01X1597099Y1535834D02*
X1603675Y1542143D01*
G01X1596625Y1535606D02*
X1603723Y1542416D01*
G01X1596244Y1535468D02*
X1603772Y1542689D01*
G01X1595907Y1535372D02*
X1603819Y1542962D01*
G01X1595570Y1535277D02*
X1603867Y1543235D01*
G01X1595263Y1535209D02*
X1603915Y1543508D01*
G01X1595000Y1535185D02*
X1603963Y1543782D01*
G01X1594736Y1535157D02*
X1604010Y1544054D01*
G01X1594473Y1535133D02*
X1604059Y1544328D01*
G01X1594209Y1535106D02*
X1604107Y1544602D01*
G01X1593982Y1535115D02*
X1604154Y1544874D01*
G01X1593754Y1535125D02*
X1604203Y1545147D01*
G01X1604251Y1545421D02*
X1593533Y1535140D01*
G01X1593322Y1535166D02*
X1597880Y1539537D01*
G01X1604298Y1545694D02*
X1598965Y1540577D01*
G01X1593112Y1535190D02*
X1597359Y1539264D01*
G01X1604347Y1545967D02*
X1599012Y1540850D01*
G01X1592912Y1535225D02*
X1596977Y1539125D01*
G01X1604394Y1546240D02*
X1599060Y1541123D01*
G01X1604442Y1546513D02*
X1599108Y1541397D01*
G01X1592717Y1535266D02*
X1596603Y1538994D01*
G01X1592522Y1535305D02*
X1596332Y1538961D01*
G01X1604489Y1546787D02*
X1599156Y1541670D01*
G01X1592339Y1535358D02*
X1596061Y1538927D01*
G01X1604510Y1547033D02*
X1599204Y1541943D01*
G01X1592159Y1535412D02*
X1595790Y1538894D01*
G01X1604530Y1547279D02*
X1599252Y1542216D01*
G01X1591978Y1535467D02*
X1595529Y1538872D01*
G01X1604550Y1547526D02*
X1599300Y1542490D01*
G01X1604569Y1547772D02*
X1599190Y1542612D01*
G01X1591810Y1535532D02*
X1595309Y1538888D01*
G01X1591644Y1535600D02*
X1595089Y1538904D01*
G01X1604590Y1548018D02*
X1599050Y1542703D01*
G01X1604583Y1548239D02*
X1598898Y1542785D01*
G01X1591478Y1535667D02*
X1594879Y1538929D01*
G01X1591323Y1535746D02*
X1594692Y1538978D01*
G01X1604556Y1548440D02*
X1598742Y1542864D01*
G01X1604529Y1548641D02*
X1598578Y1542933D01*
G01X1591171Y1535827D02*
X1594506Y1539027D01*
G01X1604501Y1548842D02*
X1598406Y1542995D01*
G01X1591019Y1535909D02*
X1594335Y1539090D01*
G01X1590876Y1535999D02*
X1594182Y1539170D01*
G01X1604473Y1549042D02*
X1598227Y1543050D01*
G01X1590738Y1536093D02*
X1594029Y1539251D01*
G01X1590600Y1536188D02*
X1593902Y1539357D01*
G01X1594727Y1542874D02*
X1598546Y1546538D01*
G01X1605806Y1538051D02*
X1605757Y1537778D01*
G01X1605852Y1538324D02*
X1605806Y1538051D01*
G01X1605901Y1538597D02*
X1605852Y1538324D01*
G01X1605901Y1538597D02*
X1605950Y1538870D01*
G01X1605757Y1537778D02*
X1605709Y1537504D01*
G01D02*
X1605661Y1537231D01*
G01X1605470Y1536138D02*
X1605421Y1535865D01*
G01X1605710Y1535460D02*
X1605946D01*
G01X1605350D02*
X1605473D01*
G01X1605374Y1535591D02*
X1605350Y1535460D01*
G01X1605421Y1535865D02*
X1605374Y1535591D01*
G01X1605661Y1537231D02*
X1605614Y1536959D01*
G01D02*
X1605565Y1536685D01*
G01D02*
X1605517Y1536411D01*
G01D02*
X1605470Y1536138D01*
G01X1605473Y1535460D02*
X1605710D01*
G01X1606658D02*
X1606894D01*
G01X1606421D02*
X1606658D01*
G01X1606183D02*
X1606421D01*
G01X1605946D02*
X1606183D01*
G01X1606332Y1541056D02*
X1606285Y1540783D01*
G01X1606189Y1540237D02*
X1606141Y1539964D01*
G01X1606094Y1539690D02*
X1606045Y1539417D01*
G01X1606285Y1540783D02*
X1606238Y1540510D01*
G01D02*
X1606189Y1540237D01*
G01X1606141Y1539964D02*
X1606094Y1539690D01*
G01X1606045Y1539417D02*
X1605997Y1539144D01*
G01D02*
X1605950Y1538870D01*
G01X1606381Y1541330D02*
X1606332Y1541056D01*
G01X1606476Y1541875D02*
X1606429Y1541603D01*
G01D02*
X1606381Y1541330D01*
G01X1606573Y1542423D02*
X1606525Y1542149D01*
G01X1606669Y1542969D02*
X1606620Y1542695D01*
G01D02*
X1606573Y1542423D01*
G01X1606525Y1542149D02*
X1606476Y1541875D01*
G01X1606716Y1543242D02*
X1606669Y1542969D01*
G01X1599012Y1540850D02*
X1598965Y1540577D01*
G01X1599252Y1542216D02*
X1599204Y1541943D01*
G01X1599300Y1542490D02*
X1599252Y1542216D01*
G01X1603579Y1541596D02*
X1603628Y1541869D01*
G01X1599156Y1541670D02*
X1599108Y1541397D01*
G01D02*
X1599060Y1541123D01*
G01X1599204Y1541943D02*
X1599156Y1541670D01*
G01X1599060Y1541123D02*
X1599012Y1540850D01*
G01X1603388Y1540503D02*
X1603435Y1540777D01*
G01X1600262Y1535460D02*
X1600499D01*
G01X1600736D02*
X1600972D01*
G01D02*
X1601209D01*
G01X1600499D02*
X1600736D01*
G01X1601920D02*
X1602156D01*
G01D02*
X1602394D01*
G01X1601446D02*
X1601684D01*
G01D02*
X1601920D01*
G01X1600026D02*
X1600262D01*
G01X1601209D02*
X1601446D01*
G01X1599789D02*
X1600026D01*
G01X1598604D02*
X1598841D01*
G01X1598367D02*
X1598604D01*
G01X1598063D02*
X1598131D01*
G01X1598097Y1535655D02*
X1598063Y1535460D01*
G01X1598131D02*
X1598367D01*
G01X1598146Y1535929D02*
X1598097Y1535655D01*
G01X1599551Y1535460D02*
X1599789D01*
G01X1599077D02*
X1599314D01*
G01X1598841D02*
X1599077D01*
G01X1599314D02*
X1599551D01*
G01X1598243Y1536476D02*
X1598194Y1536203D01*
G01D02*
X1598146Y1535929D01*
G01X1603197Y1539411D02*
X1603244Y1539684D01*
G01X1603484Y1541050D02*
X1603532Y1541323D01*
G01D02*
X1603579Y1541596D01*
G01X1603340Y1540231D02*
X1603388Y1540503D01*
G01X1603435Y1540777D02*
X1603484Y1541050D01*
G01X1603675Y1542143D02*
X1603723Y1542416D01*
G01X1603628Y1541869D02*
X1603675Y1542143D01*
G01X1603004Y1538318D02*
X1603053Y1538591D01*
G01X1602814Y1537226D02*
X1602860Y1537498D01*
G01X1602958Y1538045D02*
X1603004Y1538318D01*
G01X1602909Y1537772D02*
X1602958Y1538045D01*
G01X1602860Y1537498D02*
X1602909Y1537772D01*
G01X1603148Y1539138D02*
X1603197Y1539411D01*
G01X1603244Y1539684D02*
X1603292Y1539958D01*
G01D02*
X1603340Y1540231D01*
G01X1603100Y1538864D02*
X1603148Y1539138D01*
G01X1603053Y1538591D02*
X1603100Y1538864D01*
G01X1603772Y1542689D02*
X1603819Y1542962D01*
G01D02*
X1603867Y1543235D01*
G01X1603723Y1542416D02*
X1603772Y1542689D01*
G01X1602765Y1536953D02*
X1602814Y1537226D01*
G01X1602504Y1535460D02*
X1602527Y1535586D01*
G01X1602394Y1535460D02*
X1602504D01*
G01X1602527Y1535586D02*
X1602574Y1535860D01*
G01X1602670Y1536406D02*
X1602716Y1536679D01*
G01D02*
X1602765Y1536953D01*
G01X1602574Y1535860D02*
X1602622Y1536133D01*
G01D02*
X1602670Y1536406D01*
G01X1616552Y1552677D02*
X1606716Y1543242D01*
G01X1616291Y1552654D02*
X1606764Y1543515D01*
G01X1604446Y1549243D02*
X1598037Y1543096D01*
G01X1604390Y1549419D02*
X1597842Y1543137D01*
G01X1604325Y1549581D02*
X1597638Y1543167D01*
G01X1604257Y1549744D02*
X1597429Y1543194D01*
G01X1604189Y1549907D02*
X1597211Y1543212D01*
G01X1604123Y1550070D02*
X1596989Y1543227D01*
G01X1599764Y1546115D02*
X1596762Y1543236D01*
G01X1604057Y1550233D02*
X1599969Y1546312D01*
G01X1599605Y1546190D02*
X1596530Y1543241D01*
G01X1603974Y1550381D02*
X1600016Y1546585D01*
G01X1603872Y1550511D02*
X1600063Y1546858D01*
G01X1599446Y1546264D02*
X1596290Y1543237D01*
G01X1599275Y1546329D02*
X1596018Y1543203D01*
G01X1603772Y1550641D02*
X1600089Y1547109D01*
G01X1603670Y1550771D02*
X1600103Y1547350D01*
G01X1595745Y1543169D02*
X1599097Y1546385D01*
G01X1595473Y1543135D02*
X1598919Y1546441D01*
G01X1603568Y1550901D02*
X1600082Y1547556D01*
G01X1595192Y1543093D02*
X1598740Y1546497D01*
G01X1603468Y1551031D02*
X1600052Y1547755D01*
G01X1603365Y1551162D02*
X1599994Y1547927D01*
G01X1603233Y1551261D02*
X1599933Y1548095D01*
G01X1603102Y1551362D02*
X1599842Y1548235D01*
G01X1602969Y1551462D02*
X1599750Y1548374D01*
G01X1602836Y1551562D02*
X1599634Y1548490D01*
G01X1602703Y1551662D02*
X1599511Y1548599D01*
G01X1602571Y1551762D02*
X1599376Y1548697D01*
G01X1602429Y1551852D02*
X1599223Y1548777D01*
G01X1602266Y1551924D02*
X1599069Y1548857D01*
G01X1602103Y1551996D02*
X1598886Y1548909D01*
G01X1601942Y1552068D02*
X1598701Y1548958D01*
G01X1601780Y1552139D02*
X1598502Y1548995D01*
G01X1601618Y1552211D02*
X1598283Y1549012D01*
G01X1601456Y1552283D02*
X1598064Y1549029D01*
G01X1601275Y1552336D02*
X1597826Y1549027D01*
G01X1601083Y1552380D02*
X1597583Y1549023D01*
G01X1600892Y1552424D02*
X1597341Y1549018D01*
G01X1600701Y1552468D02*
X1597088Y1549002D01*
G01X1600510Y1552512D02*
X1596834Y1548985D01*
G01X1600318Y1552555D02*
X1596572Y1548962D01*
G01X1600127Y1552599D02*
X1596299Y1548926D01*
G01X1599906Y1552614D02*
X1596022Y1548888D01*
G01X1599686Y1552629D02*
X1595723Y1548828D01*
G01X1599464Y1552644D02*
X1595415Y1548760D01*
G01X1599243Y1552660D02*
X1595082Y1548668D01*
G01X1599022Y1552675D02*
X1594726Y1548553D01*
G01X1598801Y1552689D02*
X1594347Y1548416D01*
G01X1598569Y1552695D02*
X1593925Y1548239D01*
G01X1598325Y1552688D02*
X1593469Y1548029D01*
G01X1598081Y1552681D02*
X1593179Y1547978D01*
G01X1597838Y1552675D02*
X1593116Y1548145D01*
G01X1597586Y1552661D02*
X1593053Y1548312D01*
G01X1597325Y1552637D02*
X1592990Y1548479D01*
G01X1597064Y1552614D02*
X1592928Y1548646D01*
G01X1596804Y1552591D02*
X1592865Y1548813D01*
G01X1596520Y1552547D02*
X1592802Y1548980D01*
G01X1596236Y1552502D02*
X1592739Y1549147D01*
G01X1595952Y1552456D02*
X1592676Y1549314D01*
G01X1595640Y1552384D02*
X1592613Y1549480D01*
G01X1595326Y1552311D02*
X1592551Y1549647D01*
G01X1594998Y1552223D02*
X1592488Y1549815D01*
G01X1594648Y1552114D02*
X1592425Y1549982D01*
G01X1594289Y1551996D02*
X1592362Y1550148D01*
G01X1593894Y1551845D02*
X1592299Y1550315D01*
G01X1593485Y1551680D02*
X1592236Y1550483D01*
G01X1593041Y1551482D02*
X1592174Y1550649D01*
G01X1592570Y1551256D02*
X1592111Y1550816D01*
G01X1592073Y1551007D02*
X1592048Y1550983D01*
G01X1606813Y1543788D02*
X1606764Y1543515D01*
G01D02*
X1606716Y1543242D01*
G01X1604251Y1545421D02*
X1604203Y1545147D01*
G01X1604394Y1546240D02*
X1604347Y1545967D01*
G01X1604442Y1546513D02*
X1604394Y1546240D01*
G01X1604298Y1545694D02*
X1604251Y1545421D01*
G01X1604347Y1545967D02*
X1604298Y1545694D01*
G01X1592236Y1550483D02*
X1592174Y1550649D01*
G01X1592236Y1550483D02*
X1592299Y1550315D01*
G01X1592174Y1550649D02*
X1592111Y1550816D01*
G01D02*
X1592048Y1550983D01*
G01X1592299Y1550315D02*
X1592362Y1550148D01*
G01X1592488Y1549815D02*
X1592551Y1549647D01*
G01X1592425Y1549982D02*
X1592488Y1549815D01*
G01X1592362Y1550148D02*
X1592425Y1549982D01*
G01X1592551Y1549647D02*
X1592613Y1549480D01*
G01X1593116Y1548145D02*
X1593179Y1547978D01*
G01X1592802Y1548980D02*
X1592865Y1548813D01*
G01X1592739Y1549147D02*
X1592802Y1548980D01*
G01X1592676Y1549314D02*
X1592739Y1549147D01*
G01X1592865Y1548813D02*
X1592928Y1548646D01*
G01X1593053Y1548312D02*
X1593116Y1548145D01*
G01X1592613Y1549480D02*
X1592676Y1549314D01*
G01X1592928Y1548646D02*
X1592990Y1548479D01*
G01D02*
X1593053Y1548312D01*
G01X1604059Y1544328D02*
X1604107Y1544602D01*
G01X1604010Y1544054D02*
X1604059Y1544328D01*
G01X1604107Y1544602D02*
X1604154Y1544874D01*
G01X1604203Y1545147D02*
X1604154Y1544874D01*
G01X1603915Y1543508D02*
X1603963Y1543782D01*
G01X1603867Y1543235D02*
X1603915Y1543508D01*
G01X1603963Y1543782D02*
X1604010Y1544054D01*
G01X1600016Y1546585D02*
X1599969Y1546312D01*
G01X1600063Y1546858D02*
X1600016Y1546585D01*
G01X1616552Y1552677D02*
X1606716Y1543242D01*
G01X1616291Y1552654D02*
X1606764Y1543515D01*
G01X1604446Y1549243D02*
X1598037Y1543096D01*
G01X1604390Y1549419D02*
X1597842Y1543137D01*
G01X1604325Y1549581D02*
X1597638Y1543167D01*
G01X1604257Y1549744D02*
X1597429Y1543194D01*
G01X1604189Y1549907D02*
X1597211Y1543212D01*
G01X1604123Y1550070D02*
X1596989Y1543227D01*
G01X1599764Y1546115D02*
X1596762Y1543236D01*
G01X1604057Y1550233D02*
X1599969Y1546312D01*
G01X1599605Y1546190D02*
X1596530Y1543241D01*
G01X1603974Y1550381D02*
X1600016Y1546585D01*
G01X1603872Y1550511D02*
X1600063Y1546858D01*
G01X1599446Y1546264D02*
X1596290Y1543237D01*
G01X1599275Y1546329D02*
X1596018Y1543203D01*
G01X1603772Y1550641D02*
X1600089Y1547109D01*
G01X1603670Y1550771D02*
X1600103Y1547350D01*
G01X1595745Y1543169D02*
X1599097Y1546385D01*
G01X1595473Y1543135D02*
X1598919Y1546441D01*
G01X1603568Y1550901D02*
X1600082Y1547556D01*
G01X1595192Y1543093D02*
X1598740Y1546497D01*
G01X1603468Y1551031D02*
X1600052Y1547755D01*
G01X1603365Y1551162D02*
X1599994Y1547927D01*
G01X1603233Y1551261D02*
X1599933Y1548095D01*
G01X1603102Y1551362D02*
X1599842Y1548235D01*
G01X1602969Y1551462D02*
X1599750Y1548374D01*
G01X1602836Y1551562D02*
X1599634Y1548490D01*
G01X1602703Y1551662D02*
X1599511Y1548599D01*
G01X1602571Y1551762D02*
X1599376Y1548697D01*
G01X1602429Y1551852D02*
X1599223Y1548777D01*
G01X1602266Y1551924D02*
X1599069Y1548857D01*
G01X1602103Y1551996D02*
X1598886Y1548909D01*
G01X1601942Y1552068D02*
X1598701Y1548958D01*
G01X1601780Y1552139D02*
X1598502Y1548995D01*
G01X1601618Y1552211D02*
X1598283Y1549012D01*
G01X1601456Y1552283D02*
X1598064Y1549029D01*
G01X1601275Y1552336D02*
X1597826Y1549027D01*
G01X1601083Y1552380D02*
X1597583Y1549023D01*
G01X1600892Y1552424D02*
X1597341Y1549018D01*
G01X1600701Y1552468D02*
X1597088Y1549002D01*
G01X1600510Y1552512D02*
X1596834Y1548985D01*
G01X1600318Y1552555D02*
X1596572Y1548962D01*
G01X1600127Y1552599D02*
X1596299Y1548926D01*
G01X1599906Y1552614D02*
X1596022Y1548888D01*
G01X1599686Y1552629D02*
X1595723Y1548828D01*
G01X1599464Y1552644D02*
X1595415Y1548760D01*
G01X1599243Y1552660D02*
X1595082Y1548668D01*
G01X1599022Y1552675D02*
X1594726Y1548553D01*
G01X1598801Y1552689D02*
X1594347Y1548416D01*
G01X1598569Y1552695D02*
X1593925Y1548239D01*
G01X1598325Y1552688D02*
X1593469Y1548029D01*
G01X1598081Y1552681D02*
X1593179Y1547978D01*
G01X1597838Y1552675D02*
X1593116Y1548145D01*
G01X1597586Y1552661D02*
X1593053Y1548312D01*
G01X1597325Y1552637D02*
X1592990Y1548479D01*
G01X1597064Y1552614D02*
X1592928Y1548646D01*
G01X1596804Y1552591D02*
X1592865Y1548813D01*
G01X1596520Y1552547D02*
X1592802Y1548980D01*
G01X1596236Y1552502D02*
X1592739Y1549147D01*
G01X1595952Y1552456D02*
X1592676Y1549314D01*
G01X1595640Y1552384D02*
X1592613Y1549480D01*
G01X1595326Y1552311D02*
X1592551Y1549647D01*
G01X1594998Y1552223D02*
X1592488Y1549815D01*
G01X1594648Y1552114D02*
X1592425Y1549982D01*
G01X1594289Y1551996D02*
X1592362Y1550148D01*
G01X1593894Y1551845D02*
X1592299Y1550315D01*
G01X1593485Y1551680D02*
X1592236Y1550483D01*
G01X1593041Y1551482D02*
X1592174Y1550649D01*
G01X1592570Y1551256D02*
X1592111Y1550816D01*
G01X1592073Y1551007D02*
X1592048Y1550983D01*
G01X1606813Y1543788D02*
X1606764Y1543515D01*
G01D02*
X1606716Y1543242D01*
G01X1604251Y1545421D02*
X1604203Y1545147D01*
G01X1604394Y1546240D02*
X1604347Y1545967D01*
G01X1604442Y1546513D02*
X1604394Y1546240D01*
G01X1604298Y1545694D02*
X1604251Y1545421D01*
G01X1604347Y1545967D02*
X1604298Y1545694D01*
G01X1592236Y1550483D02*
X1592174Y1550649D01*
G01X1592236Y1550483D02*
X1592299Y1550315D01*
G01X1592174Y1550649D02*
X1592111Y1550816D01*
G01D02*
X1592048Y1550983D01*
G01X1592299Y1550315D02*
X1592362Y1550148D01*
G01X1592488Y1549815D02*
X1592551Y1549647D01*
G01X1592425Y1549982D02*
X1592488Y1549815D01*
G01X1592362Y1550148D02*
X1592425Y1549982D01*
G01X1592551Y1549647D02*
X1592613Y1549480D01*
G01X1593116Y1548145D02*
X1593179Y1547978D01*
G01X1592802Y1548980D02*
X1592865Y1548813D01*
G01X1592739Y1549147D02*
X1592802Y1548980D01*
G01X1592676Y1549314D02*
X1592739Y1549147D01*
G01X1592865Y1548813D02*
X1592928Y1548646D01*
G01X1593053Y1548312D02*
X1593116Y1548145D01*
G01X1592613Y1549480D02*
X1592676Y1549314D01*
G01X1592928Y1548646D02*
X1592990Y1548479D01*
G01D02*
X1593053Y1548312D01*
G01X1604059Y1544328D02*
X1604107Y1544602D01*
G01X1604010Y1544054D02*
X1604059Y1544328D01*
G01X1604107Y1544602D02*
X1604154Y1544874D01*
G01X1604203Y1545147D02*
X1604154Y1544874D01*
G01X1603915Y1543508D02*
X1603963Y1543782D01*
G01X1603867Y1543235D02*
X1603915Y1543508D01*
G01X1603963Y1543782D02*
X1604010Y1544054D01*
G01X1600016Y1546585D02*
X1599969Y1546312D01*
G01X1600063Y1546858D02*
X1600016Y1546585D01*
G01X1609737Y1535460D02*
X1609799Y1535521D01*
G01X1609500Y1535460D02*
X1609847Y1535794D01*
G01X1609262Y1535460D02*
X1609894Y1536066D01*
G01X1609026Y1535460D02*
X1609943Y1536340D01*
G01X1608789Y1535460D02*
X1609992Y1536614D01*
G01X1608551Y1535460D02*
X1610039Y1536887D01*
G01X1608315Y1535460D02*
X1610087Y1537160D01*
G01X1608078Y1535460D02*
X1610136Y1537433D01*
G01X1607841Y1535460D02*
X1610184Y1537707D01*
G01X1607605Y1535460D02*
X1610232Y1537980D01*
G01X1607369Y1535460D02*
X1610279Y1538253D01*
G01X1607130Y1535460D02*
X1610328Y1538527D01*
G01X1606894Y1535460D02*
X1610376Y1538801D01*
G01X1609992Y1536614D02*
X1609943Y1536340D01*
G01X1610232Y1537980D02*
X1610279Y1538253D01*
G01X1610087Y1537160D02*
X1610039Y1536887D01*
G01X1609943Y1536340D02*
X1609894Y1536066D01*
G01X1610039Y1536887D02*
X1609992Y1536614D01*
G01X1610472Y1539346D02*
X1610521Y1539620D01*
G01X1610184Y1537707D02*
X1610136Y1537433D01*
G01X1610423Y1539073D02*
X1610472Y1539346D01*
G01X1610616Y1540167D02*
X1610665Y1540440D01*
G01X1610568Y1539894D02*
X1610616Y1540167D01*
G01X1610521Y1539620D02*
X1610568Y1539894D01*
G01X1610279Y1538253D02*
X1610328Y1538527D01*
G01X1610232Y1537980D02*
X1610184Y1537707D01*
G01X1610376Y1538801D02*
X1610423Y1539073D01*
G01X1610328Y1538527D02*
X1610376Y1538801D01*
G01X1610905Y1541807D02*
X1610952Y1542080D01*
G01X1610136Y1537433D02*
X1610087Y1537160D01*
G01X1610952Y1542080D02*
X1611001Y1542353D01*
G01X1611050Y1542627D02*
X1611097Y1542900D01*
G01X1611001Y1542353D02*
X1611050Y1542627D01*
G01X1610808Y1541260D02*
X1610857Y1541533D01*
G01X1610713Y1540714D02*
X1610761Y1540987D01*
G01X1610665Y1540440D02*
X1610713Y1540714D01*
G01X1610857Y1541533D02*
X1610905Y1541807D01*
G01X1610761Y1540987D02*
X1610808Y1541260D01*
G01X1611097Y1542900D02*
X1611145Y1543174D01*
G01X1609500Y1535460D02*
X1609737D01*
G01X1609026D02*
X1609262D01*
G01D02*
X1609500D01*
G01X1608789D02*
X1609026D01*
G01X1608551D02*
X1608789D01*
G01X1608315D02*
X1608551D01*
G01X1607605D02*
X1607841D01*
G01X1608078D02*
X1608315D01*
G01X1607369D02*
X1607605D01*
G01X1607841D02*
X1608078D01*
G01X1607130D02*
X1607369D01*
G01X1606894D02*
X1607130D01*
G01X1609847Y1535794D02*
X1609799Y1535521D01*
G01X1609894Y1536066D02*
X1609847Y1535794D01*
G01X1609788Y1535460D02*
X1609799Y1535521D01*
G01X1609737Y1535460D02*
X1609788D01*
G01X1609737D02*
X1609799Y1535521D01*
G01X1609500Y1535460D02*
X1609847Y1535794D01*
G01X1609262Y1535460D02*
X1609894Y1536066D01*
G01X1609026Y1535460D02*
X1609943Y1536340D01*
G01X1608789Y1535460D02*
X1609992Y1536614D01*
G01X1608551Y1535460D02*
X1610039Y1536887D01*
G01X1608315Y1535460D02*
X1610087Y1537160D01*
G01X1608078Y1535460D02*
X1610136Y1537433D01*
G01X1607841Y1535460D02*
X1610184Y1537707D01*
G01X1607605Y1535460D02*
X1610232Y1537980D01*
G01X1607369Y1535460D02*
X1610279Y1538253D01*
G01X1607130Y1535460D02*
X1610328Y1538527D01*
G01X1606894Y1535460D02*
X1610376Y1538801D01*
G01X1609992Y1536614D02*
X1609943Y1536340D01*
G01X1610232Y1537980D02*
X1610279Y1538253D01*
G01X1610087Y1537160D02*
X1610039Y1536887D01*
G01X1609943Y1536340D02*
X1609894Y1536066D01*
G01X1610039Y1536887D02*
X1609992Y1536614D01*
G01X1610472Y1539346D02*
X1610521Y1539620D01*
G01X1610184Y1537707D02*
X1610136Y1537433D01*
G01X1610423Y1539073D02*
X1610472Y1539346D01*
G01X1610616Y1540167D02*
X1610665Y1540440D01*
G01X1610568Y1539894D02*
X1610616Y1540167D01*
G01X1610521Y1539620D02*
X1610568Y1539894D01*
G01X1610279Y1538253D02*
X1610328Y1538527D01*
G01X1610232Y1537980D02*
X1610184Y1537707D01*
G01X1610376Y1538801D02*
X1610423Y1539073D01*
G01X1610328Y1538527D02*
X1610376Y1538801D01*
G01X1610905Y1541807D02*
X1610952Y1542080D01*
G01X1610136Y1537433D02*
X1610087Y1537160D01*
G01X1610952Y1542080D02*
X1611001Y1542353D01*
G01X1611050Y1542627D02*
X1611097Y1542900D01*
G01X1611001Y1542353D02*
X1611050Y1542627D01*
G01X1610808Y1541260D02*
X1610857Y1541533D01*
G01X1610713Y1540714D02*
X1610761Y1540987D01*
G01X1610665Y1540440D02*
X1610713Y1540714D01*
G01X1610857Y1541533D02*
X1610905Y1541807D01*
G01X1610761Y1540987D02*
X1610808Y1541260D01*
G01X1611097Y1542900D02*
X1611145Y1543174D01*
G01X1609500Y1535460D02*
X1609737D01*
G01X1609026D02*
X1609262D01*
G01D02*
X1609500D01*
G01X1608789D02*
X1609026D01*
G01X1608551D02*
X1608789D01*
G01X1608315D02*
X1608551D01*
G01X1607605D02*
X1607841D01*
G01X1608078D02*
X1608315D01*
G01X1607369D02*
X1607605D01*
G01X1607841D02*
X1608078D01*
G01X1607130D02*
X1607369D01*
G01X1606894D02*
X1607130D01*
G01X1609847Y1535794D02*
X1609799Y1535521D01*
G01X1609894Y1536066D02*
X1609847Y1535794D01*
G01X1609788Y1535460D02*
X1609799Y1535521D01*
G01X1609737Y1535460D02*
X1609788D01*
G01X1618103Y1552575D02*
X1613647Y1548300D01*
G01X1617887Y1552595D02*
X1613185Y1548084D01*
G01X1616028Y1552629D02*
X1606813Y1543788D01*
G01X1615767Y1552605D02*
X1606860Y1544061D01*
G01X1615504Y1552581D02*
X1606908Y1544335D01*
G01X1615173Y1552491D02*
X1606956Y1544608D01*
G01X1614841Y1552399D02*
X1607004Y1544881D01*
G01X1614508Y1552306D02*
X1607051Y1545154D01*
G01X1614107Y1552149D02*
X1607100Y1545428D01*
G01X1613636Y1551926D02*
X1607148Y1545701D01*
G01X1612987Y1551529D02*
X1607195Y1545974D01*
G01X1612580Y1551366D02*
X1607244Y1546247D01*
G01X1612629Y1551640D02*
X1607293Y1546521D01*
G01X1612676Y1551913D02*
X1607339Y1546794D01*
G01X1612724Y1552186D02*
X1607388Y1547067D01*
G01X1612653Y1552345D02*
X1607437Y1547340D01*
G01X1612416Y1552345D02*
X1607483Y1547613D01*
G01X1612178Y1552345D02*
X1607531Y1547887D01*
G01X1611942Y1552345D02*
X1607580Y1548160D01*
G01X1611706Y1552345D02*
X1607628Y1548433D01*
G01X1611469Y1552345D02*
X1607675Y1548706D01*
G01X1611232Y1552345D02*
X1607724Y1548980D01*
G01X1610996Y1552345D02*
X1607772Y1549253D01*
G01X1610758Y1552345D02*
X1607819Y1549526D01*
G01X1610521Y1552345D02*
X1607868Y1549799D01*
G01X1610285Y1552345D02*
X1607915Y1550072D01*
G01X1610047Y1552345D02*
X1607963Y1550346D01*
G01X1609810Y1552345D02*
X1608012Y1550618D01*
G01X1609574Y1552345D02*
X1608059Y1550892D01*
G01X1609337Y1552345D02*
X1608107Y1551166D01*
G01X1611194Y1543447D02*
X1611145Y1543174D01*
G01X1611241Y1543720D02*
X1611194Y1543447D01*
G01X1611289Y1543993D02*
X1611241Y1543720D01*
G01X1611337Y1544267D02*
X1611289Y1543993D01*
G01X1607244Y1546247D02*
X1607195Y1545974D01*
G01X1611386Y1544540D02*
X1611337Y1544267D01*
G01X1607195Y1545974D02*
X1607148Y1545701D01*
G01X1607724Y1548980D02*
X1607772Y1549253D01*
G01D02*
X1607819Y1549526D01*
G01X1607868Y1549799D02*
X1607915Y1550072D01*
G01X1607628Y1548433D02*
X1607580Y1548160D01*
G01D02*
X1607531Y1547887D01*
G01X1607675Y1548706D02*
X1607724Y1548980D01*
G01X1607628Y1548433D02*
X1607675Y1548706D01*
G01X1607915Y1550072D02*
X1607963Y1550346D01*
G01X1607819Y1549526D02*
X1607868Y1549799D01*
G01X1608012Y1550618D02*
X1608059Y1550892D01*
G01X1607963Y1550346D02*
X1608012Y1550618D01*
G01X1608059Y1550892D02*
X1608107Y1551166D01*
G01D02*
X1608155Y1551438D01*
G01X1607531Y1547887D02*
X1607483Y1547613D01*
G01X1606908Y1544335D02*
X1606860Y1544061D01*
G01X1606956Y1544608D02*
X1606908Y1544335D01*
G01X1606860Y1544061D02*
X1606813Y1543788D01*
G01X1607483Y1547613D02*
X1607437Y1547340D01*
G01X1607293Y1546521D02*
X1607244Y1546247D01*
G01X1607339Y1546794D02*
X1607293Y1546521D01*
G01X1607388Y1547067D02*
X1607339Y1546794D01*
G01X1607437Y1547340D02*
X1607388Y1547067D01*
G01X1607148Y1545701D02*
X1607100Y1545428D01*
G01X1607051Y1545154D02*
X1607004Y1544881D01*
G01X1607100Y1545428D02*
X1607051Y1545154D01*
G01X1607004Y1544881D02*
X1606956Y1544608D01*
G01X1618103Y1552575D02*
X1613647Y1548300D01*
G01X1617887Y1552595D02*
X1613185Y1548084D01*
G01X1616028Y1552629D02*
X1606813Y1543788D01*
G01X1615767Y1552605D02*
X1606860Y1544061D01*
G01X1615504Y1552581D02*
X1606908Y1544335D01*
G01X1615173Y1552491D02*
X1606956Y1544608D01*
G01X1614841Y1552399D02*
X1607004Y1544881D01*
G01X1614508Y1552306D02*
X1607051Y1545154D01*
G01X1614107Y1552149D02*
X1607100Y1545428D01*
G01X1613636Y1551926D02*
X1607148Y1545701D01*
G01X1612987Y1551529D02*
X1607195Y1545974D01*
G01X1612580Y1551366D02*
X1607244Y1546247D01*
G01X1612629Y1551640D02*
X1607293Y1546521D01*
G01X1612676Y1551913D02*
X1607339Y1546794D01*
G01X1612724Y1552186D02*
X1607388Y1547067D01*
G01X1612653Y1552345D02*
X1607437Y1547340D01*
G01X1612416Y1552345D02*
X1607483Y1547613D01*
G01X1612178Y1552345D02*
X1607531Y1547887D01*
G01X1611942Y1552345D02*
X1607580Y1548160D01*
G01X1611706Y1552345D02*
X1607628Y1548433D01*
G01X1611469Y1552345D02*
X1607675Y1548706D01*
G01X1611232Y1552345D02*
X1607724Y1548980D01*
G01X1610996Y1552345D02*
X1607772Y1549253D01*
G01X1610758Y1552345D02*
X1607819Y1549526D01*
G01X1610521Y1552345D02*
X1607868Y1549799D01*
G01X1610285Y1552345D02*
X1607915Y1550072D01*
G01X1610047Y1552345D02*
X1607963Y1550346D01*
G01X1609810Y1552345D02*
X1608012Y1550618D01*
G01X1609574Y1552345D02*
X1608059Y1550892D01*
G01X1609337Y1552345D02*
X1608107Y1551166D01*
G01X1611194Y1543447D02*
X1611145Y1543174D01*
G01X1611241Y1543720D02*
X1611194Y1543447D01*
G01X1611289Y1543993D02*
X1611241Y1543720D01*
G01X1611337Y1544267D02*
X1611289Y1543993D01*
G01X1607244Y1546247D02*
X1607195Y1545974D01*
G01X1611386Y1544540D02*
X1611337Y1544267D01*
G01X1607195Y1545974D02*
X1607148Y1545701D01*
G01X1607724Y1548980D02*
X1607772Y1549253D01*
G01D02*
X1607819Y1549526D01*
G01X1607868Y1549799D02*
X1607915Y1550072D01*
G01X1607628Y1548433D02*
X1607580Y1548160D01*
G01D02*
X1607531Y1547887D01*
G01X1607675Y1548706D02*
X1607724Y1548980D01*
G01X1607628Y1548433D02*
X1607675Y1548706D01*
G01X1607915Y1550072D02*
X1607963Y1550346D01*
G01X1607819Y1549526D02*
X1607868Y1549799D01*
G01X1608012Y1550618D02*
X1608059Y1550892D01*
G01X1607963Y1550346D02*
X1608012Y1550618D01*
G01X1608059Y1550892D02*
X1608107Y1551166D01*
G01D02*
X1608155Y1551438D01*
G01X1607531Y1547887D02*
X1607483Y1547613D01*
G01X1606908Y1544335D02*
X1606860Y1544061D01*
G01X1606956Y1544608D02*
X1606908Y1544335D01*
G01X1606860Y1544061D02*
X1606813Y1543788D01*
G01X1607483Y1547613D02*
X1607437Y1547340D01*
G01X1607293Y1546521D02*
X1607244Y1546247D01*
G01X1607339Y1546794D02*
X1607293Y1546521D01*
G01X1607388Y1547067D02*
X1607339Y1546794D01*
G01X1607437Y1547340D02*
X1607388Y1547067D01*
G01X1607148Y1545701D02*
X1607100Y1545428D01*
G01X1607051Y1545154D02*
X1607004Y1544881D01*
G01X1607100Y1545428D02*
X1607051Y1545154D01*
G01X1607004Y1544881D02*
X1606956Y1544608D01*
G01X1619920Y1535460D02*
X1619996Y1535532D01*
G01X1619684Y1535460D02*
X1620045Y1535806D01*
G01X1619448Y1535460D02*
X1620093Y1536079D01*
G01X1619210Y1535460D02*
X1620140Y1536352D01*
G01X1618974Y1535460D02*
X1620189Y1536625D01*
G01X1618738Y1535460D02*
X1620236Y1536898D01*
G01X1618500Y1535460D02*
X1620284Y1537172D01*
G01X1618263Y1535460D02*
X1620333Y1537446D01*
G01X1618027Y1535460D02*
X1620380Y1537718D01*
G01X1617789Y1535460D02*
X1620428Y1537991D01*
G01X1617552Y1535460D02*
X1620476Y1538265D01*
G01X1617316Y1535460D02*
X1620524Y1538538D01*
G01X1617079Y1535460D02*
X1620571Y1538811D01*
G01X1616841Y1535460D02*
X1620620Y1539084D01*
G01X1616605Y1535460D02*
X1620668Y1539357D01*
G01X1616368Y1535460D02*
X1620715Y1539631D01*
G01X1616131Y1535460D02*
X1620764Y1539903D01*
G01X1615895Y1535460D02*
X1620811Y1540177D01*
G01X1615657Y1535460D02*
X1620859Y1540450D01*
G01X1615566Y1535600D02*
X1620908Y1540724D01*
G01X1615615Y1535873D02*
X1620955Y1540996D01*
G01X1615663Y1536146D02*
X1621003Y1541269D01*
G01X1615710Y1536420D02*
X1621051Y1541542D01*
G01X1615759Y1536693D02*
X1621099Y1541816D01*
G01X1615807Y1536966D02*
X1621146Y1542089D01*
G01X1615854Y1537239D02*
X1621195Y1542362D01*
G01X1615903Y1537513D02*
X1621243Y1542636D01*
G01X1615952Y1537787D02*
X1621290Y1542909D01*
G01X1615999Y1538059D02*
X1621339Y1543182D01*
G01X1616047Y1538333D02*
X1621386Y1543455D01*
G01X1616095Y1538606D02*
X1621434Y1543728D01*
G01X1616143Y1538880D02*
X1621483Y1544002D01*
G01X1616190Y1539153D02*
X1621530Y1544275D01*
G01X1616239Y1539426D02*
X1621578Y1544547D01*
G01X1616288Y1539699D02*
X1621627Y1544821D01*
G01X1616335Y1539972D02*
X1621667Y1545088D01*
G01X1616383Y1540246D02*
X1621698Y1545345D01*
G01X1616432Y1540519D02*
X1621730Y1545601D01*
G01X1616479Y1540792D02*
X1621761Y1545859D01*
G01X1616527Y1541066D02*
X1621792Y1546117D01*
G01X1616576Y1541339D02*
X1621825Y1546374D01*
G01X1616623Y1541612D02*
X1621854Y1546631D01*
G01X1616670Y1541886D02*
X1621860Y1546863D01*
G01X1621857Y1547088D02*
X1616719Y1542159D01*
G01X1616768Y1542432D02*
X1621856Y1547314D01*
G01X1616816Y1542705D02*
X1621854Y1547539D01*
G01X1616863Y1542979D02*
X1621852Y1547765D01*
G01X1617316Y1535460D02*
X1617552D01*
G01X1618027D02*
X1618263D01*
G01X1617789D02*
X1618027D01*
G01X1617552D02*
X1617789D01*
G01X1618263D02*
X1618500D01*
G01D02*
X1618738D01*
G01D02*
X1618974D01*
G01X1615615Y1535873D02*
X1615566Y1535600D01*
G01X1615663Y1536146D02*
X1615615Y1535873D01*
G01X1615657Y1535460D02*
X1615895D01*
G01D02*
X1616131D01*
G01X1615710Y1536420D02*
X1615663Y1536146D01*
G01X1615542Y1535460D02*
X1615657D01*
G01X1615566Y1535600D02*
X1615542Y1535460D01*
G01X1615807Y1536966D02*
X1615759Y1536693D01*
G01D02*
X1615710Y1536420D01*
G01X1617079Y1535460D02*
X1617316D01*
G01X1616131D02*
X1616368D01*
G01X1616841D02*
X1617079D01*
G01X1616368D02*
X1616605D01*
G01D02*
X1616841D01*
G01X1615854Y1537239D02*
X1615807Y1536966D01*
G01X1616190Y1539153D02*
X1616143Y1538880D01*
G01X1616623Y1541612D02*
X1616576Y1541339D01*
G01D02*
X1616527Y1541066D01*
G01X1616432Y1540519D02*
X1616383Y1540246D01*
G01X1616479Y1540792D02*
X1616432Y1540519D01*
G01X1616527Y1541066D02*
X1616479Y1540792D01*
G01X1616095Y1538606D02*
X1616047Y1538333D01*
G01D02*
X1615999Y1538059D01*
G01X1616383Y1540246D02*
X1616335Y1539972D01*
G01X1615999Y1538059D02*
X1615952Y1537787D01*
G01D02*
X1615903Y1537513D01*
G01X1616335Y1539972D02*
X1616288Y1539699D01*
G01D02*
X1616239Y1539426D01*
G01X1615903Y1537513D02*
X1615854Y1537239D01*
G01X1616143Y1538880D02*
X1616095Y1538606D01*
G01X1616239Y1539426D02*
X1616190Y1539153D01*
G01X1616670Y1541886D02*
X1616623Y1541612D01*
G01X1616912Y1543252D02*
X1616863Y1542979D01*
G01X1616768Y1542432D02*
X1616719Y1542159D01*
G01X1616863Y1542979D02*
X1616816Y1542705D01*
G01X1620189Y1536625D02*
X1620140Y1536352D01*
G01X1620093Y1536079D02*
X1620045Y1535806D01*
G01X1620715Y1539631D02*
X1620668Y1539357D01*
G01X1620140Y1536352D02*
X1620093Y1536079D01*
G01X1620764Y1539903D02*
X1620715Y1539631D01*
G01X1620859Y1540450D02*
X1620811Y1540177D01*
G01X1620045Y1535806D02*
X1619996Y1535532D01*
G01X1620908Y1540724D02*
X1620859Y1540450D01*
G01X1620811Y1540177D02*
X1620764Y1539903D01*
G01X1619984Y1535460D02*
X1619996Y1535532D01*
G01X1619920Y1535460D02*
X1619984D01*
G01X1620428Y1537991D02*
X1620380Y1537718D01*
G01X1620524Y1538538D02*
X1620476Y1538265D01*
G01D02*
X1620428Y1537991D01*
G01X1620571Y1538811D02*
X1620524Y1538538D01*
G01X1620620Y1539084D02*
X1620571Y1538811D01*
G01X1620284Y1537172D02*
X1620236Y1536898D01*
G01X1620668Y1539357D02*
X1620620Y1539084D01*
G01X1620236Y1536898D02*
X1620189Y1536625D01*
G01X1620333Y1537446D02*
X1620284Y1537172D01*
G01X1620380Y1537718D02*
X1620333Y1537446D01*
G01X1621243Y1542636D02*
X1621195Y1542362D01*
G01X1621339Y1543182D02*
X1621290Y1542909D01*
G01X1620955Y1540996D02*
X1620908Y1540724D01*
G01X1619210Y1535460D02*
X1619448D01*
G01X1618974D02*
X1619210D01*
G01X1619448D02*
X1619684D01*
G01X1621099Y1541816D02*
X1621051Y1541542D01*
G01X1621146Y1542089D02*
X1621099Y1541816D01*
G01X1621051Y1541542D02*
X1621003Y1541269D01*
G01D02*
X1620955Y1540996D01*
G01X1619684Y1535460D02*
X1619920D01*
G01X1621290Y1542909D02*
X1621243Y1542636D01*
G01X1621195Y1542362D02*
X1621146Y1542089D01*
G01X1616670Y1541886D02*
X1616719Y1542159D01*
G01X1616816Y1542705D02*
X1616768Y1542432D01*
G01X1619920Y1535460D02*
X1619996Y1535532D01*
G01X1619684Y1535460D02*
X1620045Y1535806D01*
G01X1619448Y1535460D02*
X1620093Y1536079D01*
G01X1619210Y1535460D02*
X1620140Y1536352D01*
G01X1618974Y1535460D02*
X1620189Y1536625D01*
G01X1618738Y1535460D02*
X1620236Y1536898D01*
G01X1618500Y1535460D02*
X1620284Y1537172D01*
G01X1618263Y1535460D02*
X1620333Y1537446D01*
G01X1618027Y1535460D02*
X1620380Y1537718D01*
G01X1617789Y1535460D02*
X1620428Y1537991D01*
G01X1617552Y1535460D02*
X1620476Y1538265D01*
G01X1617316Y1535460D02*
X1620524Y1538538D01*
G01X1617079Y1535460D02*
X1620571Y1538811D01*
G01X1616841Y1535460D02*
X1620620Y1539084D01*
G01X1616605Y1535460D02*
X1620668Y1539357D01*
G01X1616368Y1535460D02*
X1620715Y1539631D01*
G01X1616131Y1535460D02*
X1620764Y1539903D01*
G01X1615895Y1535460D02*
X1620811Y1540177D01*
G01X1615657Y1535460D02*
X1620859Y1540450D01*
G01X1615566Y1535600D02*
X1620908Y1540724D01*
G01X1615615Y1535873D02*
X1620955Y1540996D01*
G01X1615663Y1536146D02*
X1621003Y1541269D01*
G01X1615710Y1536420D02*
X1621051Y1541542D01*
G01X1615759Y1536693D02*
X1621099Y1541816D01*
G01X1615807Y1536966D02*
X1621146Y1542089D01*
G01X1615854Y1537239D02*
X1621195Y1542362D01*
G01X1615903Y1537513D02*
X1621243Y1542636D01*
G01X1615952Y1537787D02*
X1621290Y1542909D01*
G01X1615999Y1538059D02*
X1621339Y1543182D01*
G01X1616047Y1538333D02*
X1621386Y1543455D01*
G01X1616095Y1538606D02*
X1621434Y1543728D01*
G01X1616143Y1538880D02*
X1621483Y1544002D01*
G01X1616190Y1539153D02*
X1621530Y1544275D01*
G01X1616239Y1539426D02*
X1621578Y1544547D01*
G01X1616288Y1539699D02*
X1621627Y1544821D01*
G01X1616335Y1539972D02*
X1621667Y1545088D01*
G01X1616383Y1540246D02*
X1621698Y1545345D01*
G01X1616432Y1540519D02*
X1621730Y1545601D01*
G01X1616479Y1540792D02*
X1621761Y1545859D01*
G01X1616527Y1541066D02*
X1621792Y1546117D01*
G01X1616576Y1541339D02*
X1621825Y1546374D01*
G01X1616623Y1541612D02*
X1621854Y1546631D01*
G01X1616670Y1541886D02*
X1621860Y1546863D01*
G01X1621857Y1547088D02*
X1616719Y1542159D01*
G01X1616768Y1542432D02*
X1621856Y1547314D01*
G01X1616816Y1542705D02*
X1621854Y1547539D01*
G01X1616863Y1542979D02*
X1621852Y1547765D01*
G01X1617316Y1535460D02*
X1617552D01*
G01X1618027D02*
X1618263D01*
G01X1617789D02*
X1618027D01*
G01X1617552D02*
X1617789D01*
G01X1618263D02*
X1618500D01*
G01D02*
X1618738D01*
G01D02*
X1618974D01*
G01X1615615Y1535873D02*
X1615566Y1535600D01*
G01X1615663Y1536146D02*
X1615615Y1535873D01*
G01X1615657Y1535460D02*
X1615895D01*
G01D02*
X1616131D01*
G01X1615710Y1536420D02*
X1615663Y1536146D01*
G01X1615542Y1535460D02*
X1615657D01*
G01X1615566Y1535600D02*
X1615542Y1535460D01*
G01X1615807Y1536966D02*
X1615759Y1536693D01*
G01D02*
X1615710Y1536420D01*
G01X1617079Y1535460D02*
X1617316D01*
G01X1616131D02*
X1616368D01*
G01X1616841D02*
X1617079D01*
G01X1616368D02*
X1616605D01*
G01D02*
X1616841D01*
G01X1615854Y1537239D02*
X1615807Y1536966D01*
G01X1616190Y1539153D02*
X1616143Y1538880D01*
G01X1616623Y1541612D02*
X1616576Y1541339D01*
G01D02*
X1616527Y1541066D01*
G01X1616432Y1540519D02*
X1616383Y1540246D01*
G01X1616479Y1540792D02*
X1616432Y1540519D01*
G01X1616527Y1541066D02*
X1616479Y1540792D01*
G01X1616095Y1538606D02*
X1616047Y1538333D01*
G01D02*
X1615999Y1538059D01*
G01X1616383Y1540246D02*
X1616335Y1539972D01*
G01X1615999Y1538059D02*
X1615952Y1537787D01*
G01D02*
X1615903Y1537513D01*
G01X1616335Y1539972D02*
X1616288Y1539699D01*
G01D02*
X1616239Y1539426D01*
G01X1615903Y1537513D02*
X1615854Y1537239D01*
G01X1616143Y1538880D02*
X1616095Y1538606D01*
G01X1616239Y1539426D02*
X1616190Y1539153D01*
G01X1616670Y1541886D02*
X1616623Y1541612D01*
G01X1616912Y1543252D02*
X1616863Y1542979D01*
G01X1616768Y1542432D02*
X1616719Y1542159D01*
G01X1616863Y1542979D02*
X1616816Y1542705D01*
G01X1620189Y1536625D02*
X1620140Y1536352D01*
G01X1620093Y1536079D02*
X1620045Y1535806D01*
G01X1620715Y1539631D02*
X1620668Y1539357D01*
G01X1620140Y1536352D02*
X1620093Y1536079D01*
G01X1620764Y1539903D02*
X1620715Y1539631D01*
G01X1620859Y1540450D02*
X1620811Y1540177D01*
G01X1620045Y1535806D02*
X1619996Y1535532D01*
G01X1620908Y1540724D02*
X1620859Y1540450D01*
G01X1620811Y1540177D02*
X1620764Y1539903D01*
G01X1619984Y1535460D02*
X1619996Y1535532D01*
G01X1619920Y1535460D02*
X1619984D01*
G01X1620428Y1537991D02*
X1620380Y1537718D01*
G01X1620524Y1538538D02*
X1620476Y1538265D01*
G01D02*
X1620428Y1537991D01*
G01X1620571Y1538811D02*
X1620524Y1538538D01*
G01X1620620Y1539084D02*
X1620571Y1538811D01*
G01X1620284Y1537172D02*
X1620236Y1536898D01*
G01X1620668Y1539357D02*
X1620620Y1539084D01*
G01X1620236Y1536898D02*
X1620189Y1536625D01*
G01X1620333Y1537446D02*
X1620284Y1537172D01*
G01X1620380Y1537718D02*
X1620333Y1537446D01*
G01X1621243Y1542636D02*
X1621195Y1542362D01*
G01X1621339Y1543182D02*
X1621290Y1542909D01*
G01X1620955Y1540996D02*
X1620908Y1540724D01*
G01X1619210Y1535460D02*
X1619448D01*
G01X1618974D02*
X1619210D01*
G01X1619448D02*
X1619684D01*
G01X1621099Y1541816D02*
X1621051Y1541542D01*
G01X1621146Y1542089D02*
X1621099Y1541816D01*
G01X1621051Y1541542D02*
X1621003Y1541269D01*
G01D02*
X1620955Y1540996D01*
G01X1619684Y1535460D02*
X1619920D01*
G01X1621290Y1542909D02*
X1621243Y1542636D01*
G01X1621195Y1542362D02*
X1621146Y1542089D01*
G01X1616670Y1541886D02*
X1616719Y1542159D01*
G01X1616816Y1542705D02*
X1616768Y1542432D01*
G01X1616912Y1543252D02*
X1621852Y1547990D01*
G01X1616959Y1543525D02*
X1621846Y1548212D01*
G01X1617007Y1543798D02*
X1621811Y1548406D01*
G01X1617056Y1544072D02*
X1621776Y1548600D01*
G01X1621740Y1548794D02*
X1617105Y1544345D01*
G01X1621707Y1548987D02*
X1617151Y1544617D01*
G01X1621671Y1549181D02*
X1617183Y1544876D01*
G01X1621637Y1549375D02*
X1617218Y1545136D01*
G01X1621591Y1549560D02*
X1617251Y1545396D01*
G01X1621523Y1549721D02*
X1617282Y1545652D01*
G01X1621456Y1549883D02*
X1617284Y1545881D01*
G01X1621386Y1550044D02*
X1617286Y1546111D01*
G01X1621317Y1550206D02*
X1617289Y1546340D01*
G01X1621249Y1550367D02*
X1617278Y1546557D01*
G01X1621182Y1550528D02*
X1617246Y1546753D01*
G01X1621098Y1550677D02*
X1617213Y1546949D01*
G01X1620994Y1550805D02*
X1617180Y1547145D01*
G01X1620891Y1550933D02*
X1617114Y1547309D01*
G01X1620788Y1551061D02*
X1617045Y1547469D01*
G01X1620685Y1551190D02*
X1616974Y1547629D01*
G01X1620582Y1551318D02*
X1616879Y1547767D01*
G01X1620479Y1551446D02*
X1616771Y1547889D01*
G01X1620360Y1551558D02*
X1616662Y1548012D01*
G01X1620220Y1551652D02*
X1616535Y1548117D01*
G01X1620080Y1551745D02*
X1616386Y1548201D01*
G01X1619942Y1551840D02*
X1616239Y1548287D01*
G01X1619804Y1551933D02*
X1616072Y1548354D01*
G01X1619665Y1552028D02*
X1615887Y1548403D01*
G01X1619526Y1552122D02*
X1615699Y1548452D01*
G01X1619364Y1552194D02*
X1615496Y1548483D01*
G01X1619189Y1552253D02*
X1615275Y1548498D01*
G01X1619012Y1552311D02*
X1615054Y1548513D01*
G01X1618835Y1552369D02*
X1614811Y1548508D01*
G01X1618659Y1552427D02*
X1614556Y1548490D01*
G01X1618483Y1552485D02*
X1614300Y1548471D01*
G01X1618306Y1552543D02*
X1613984Y1548396D01*
G01X1617105Y1544345D02*
X1617056Y1544072D01*
G01X1621530Y1544275D02*
X1621483Y1544002D01*
G01X1621578Y1544547D02*
X1621530Y1544275D01*
G01X1617056Y1544072D02*
X1617007Y1543798D01*
G01X1621434Y1543728D02*
X1621386Y1543455D01*
G01D02*
X1621339Y1543182D01*
G01X1621483Y1544002D02*
X1621434Y1543728D01*
G01X1616959Y1543525D02*
X1616912Y1543252D01*
G01X1621627Y1544821D02*
X1621578Y1544547D01*
G01X1617007Y1543798D02*
X1616959Y1543525D01*
G01X1616912Y1543252D02*
X1621852Y1547990D01*
G01X1616959Y1543525D02*
X1621846Y1548212D01*
G01X1617007Y1543798D02*
X1621811Y1548406D01*
G01X1617056Y1544072D02*
X1621776Y1548600D01*
G01X1621740Y1548794D02*
X1617105Y1544345D01*
G01X1621707Y1548987D02*
X1617151Y1544617D01*
G01X1621671Y1549181D02*
X1617183Y1544876D01*
G01X1621637Y1549375D02*
X1617218Y1545136D01*
G01X1621591Y1549560D02*
X1617251Y1545396D01*
G01X1621523Y1549721D02*
X1617282Y1545652D01*
G01X1621456Y1549883D02*
X1617284Y1545881D01*
G01X1621386Y1550044D02*
X1617286Y1546111D01*
G01X1621317Y1550206D02*
X1617289Y1546340D01*
G01X1621249Y1550367D02*
X1617278Y1546557D01*
G01X1621182Y1550528D02*
X1617246Y1546753D01*
G01X1621098Y1550677D02*
X1617213Y1546949D01*
G01X1620994Y1550805D02*
X1617180Y1547145D01*
G01X1620891Y1550933D02*
X1617114Y1547309D01*
G01X1620788Y1551061D02*
X1617045Y1547469D01*
G01X1620685Y1551190D02*
X1616974Y1547629D01*
G01X1620582Y1551318D02*
X1616879Y1547767D01*
G01X1620479Y1551446D02*
X1616771Y1547889D01*
G01X1620360Y1551558D02*
X1616662Y1548012D01*
G01X1620220Y1551652D02*
X1616535Y1548117D01*
G01X1620080Y1551745D02*
X1616386Y1548201D01*
G01X1619942Y1551840D02*
X1616239Y1548287D01*
G01X1619804Y1551933D02*
X1616072Y1548354D01*
G01X1619665Y1552028D02*
X1615887Y1548403D01*
G01X1619526Y1552122D02*
X1615699Y1548452D01*
G01X1619364Y1552194D02*
X1615496Y1548483D01*
G01X1619189Y1552253D02*
X1615275Y1548498D01*
G01X1619012Y1552311D02*
X1615054Y1548513D01*
G01X1618835Y1552369D02*
X1614811Y1548508D01*
G01X1618659Y1552427D02*
X1614556Y1548490D01*
G01X1618483Y1552485D02*
X1614300Y1548471D01*
G01X1618306Y1552543D02*
X1613984Y1548396D01*
G01X1617105Y1544345D02*
X1617056Y1544072D01*
G01X1621530Y1544275D02*
X1621483Y1544002D01*
G01X1621578Y1544547D02*
X1621530Y1544275D01*
G01X1617056Y1544072D02*
X1617007Y1543798D01*
G01X1621434Y1543728D02*
X1621386Y1543455D01*
G01D02*
X1621339Y1543182D01*
G01X1621483Y1544002D02*
X1621434Y1543728D01*
G01X1616959Y1543525D02*
X1616912Y1543252D01*
G01X1621627Y1544821D02*
X1621578Y1544547D01*
G01X1617007Y1543798D02*
X1616959Y1543525D01*
G01X1609099Y1552345D02*
X1608155Y1551438D01*
G01X1608863Y1552345D02*
X1608203Y1551712D01*
G01X1608626Y1552345D02*
X1608250Y1551985D01*
G01X1608389Y1552345D02*
X1608299Y1552258D01*
G01X1612752Y1552345D02*
X1612653D01*
G01X1612724Y1552186D02*
X1612752Y1552345D01*
G01X1612676Y1551913D02*
X1612724Y1552186D01*
G01X1612580Y1551366D02*
X1612629Y1551640D01*
G01D02*
X1612676Y1551913D01*
G01X1612178Y1552345D02*
X1611942D01*
G01D02*
X1611706D01*
G01X1612653D02*
X1612416D01*
G01D02*
X1612178D01*
G01X1611706D02*
X1611469D01*
G01X1610047D02*
X1609810D01*
G01X1608863D02*
X1608626D01*
G01X1609337D02*
X1609099D01*
G01X1611469D02*
X1611232D01*
G01X1609574D02*
X1609337D01*
G01X1609810D02*
X1609574D01*
G01X1609099D02*
X1608863D01*
G01X1610758D02*
X1610521D01*
G01X1610996D02*
X1610758D01*
G01X1610285D02*
X1610047D01*
G01X1611232D02*
X1610996D01*
G01X1608626D02*
X1608389D01*
G01X1610521D02*
X1610285D01*
G01X1608314D02*
X1608299Y1552258D01*
G01X1608389Y1552345D02*
X1608314D01*
G01X1608250Y1551985D02*
X1608299Y1552258D01*
G01X1608203Y1551712D02*
X1608250Y1551985D01*
G01X1608155Y1551438D02*
X1608203Y1551712D01*
G01X1609099Y1552345D02*
X1608155Y1551438D01*
G01X1608863Y1552345D02*
X1608203Y1551712D01*
G01X1608626Y1552345D02*
X1608250Y1551985D01*
G01X1608389Y1552345D02*
X1608299Y1552258D01*
G01X1612752Y1552345D02*
X1612653D01*
G01X1612724Y1552186D02*
X1612752Y1552345D01*
G01X1612676Y1551913D02*
X1612724Y1552186D01*
G01X1612580Y1551366D02*
X1612629Y1551640D01*
G01D02*
X1612676Y1551913D01*
G01X1612178Y1552345D02*
X1611942D01*
G01D02*
X1611706D01*
G01X1612653D02*
X1612416D01*
G01D02*
X1612178D01*
G01X1611706D02*
X1611469D01*
G01X1610047D02*
X1609810D01*
G01X1608863D02*
X1608626D01*
G01X1609337D02*
X1609099D01*
G01X1611469D02*
X1611232D01*
G01X1609574D02*
X1609337D01*
G01X1609810D02*
X1609574D01*
G01X1609099D02*
X1608863D01*
G01X1610758D02*
X1610521D01*
G01X1610996D02*
X1610758D01*
G01X1610285D02*
X1610047D01*
G01X1611232D02*
X1610996D01*
G01X1608626D02*
X1608389D01*
G01X1610521D02*
X1610285D01*
G01X1608314D02*
X1608299Y1552258D01*
G01X1608389Y1552345D02*
X1608314D01*
G01X1608250Y1551985D02*
X1608299Y1552258D01*
G01X1608203Y1551712D02*
X1608250Y1551985D01*
G01X1608155Y1551438D02*
X1608203Y1551712D01*
G01X1639240Y1535589D02*
X1642695Y1538902D01*
G01X1639073Y1535656D02*
X1642478Y1538921D01*
G01X1638917Y1535733D02*
X1642292Y1538970D01*
G01X1638764Y1535814D02*
X1642106Y1539018D01*
G01X1638612Y1535895D02*
X1641928Y1539077D01*
G01X1638467Y1535983D02*
X1641776Y1539157D01*
G01X1638330Y1536077D02*
X1641623Y1539237D01*
G01X1638190Y1536172D02*
X1641490Y1539338D01*
G01X1638057Y1536272D02*
X1641371Y1539450D01*
G01X1637934Y1536379D02*
X1641254Y1539566D01*
G01X1637809Y1536487D02*
X1641167Y1539709D01*
G01X1637687Y1536598D02*
X1641082Y1539854D01*
G01X1637577Y1536720D02*
X1641022Y1540025D01*
G01X1637469Y1536842D02*
X1640971Y1540202D01*
G01X1637359Y1536965D02*
X1640942Y1540401D01*
G01X1637264Y1537100D02*
X1640926Y1540614D01*
G01X1637169Y1537237D02*
X1640938Y1540853D01*
G01X1637075Y1537374D02*
X1640964Y1541104D01*
G01X1636992Y1537522D02*
X1641082Y1541445D01*
G01X1636915Y1537675D02*
X1641208Y1541793D01*
G01X1636838Y1537828D02*
X1641870Y1542656D01*
G01X1636767Y1537988D02*
X1645748Y1546602D01*
G01X1636708Y1538158D02*
X1645547Y1546637D01*
G01X1636648Y1538328D02*
X1645338Y1546665D01*
G01X1636594Y1538503D02*
X1645114Y1546676D01*
G01X1636553Y1538691D02*
X1644889Y1546688D01*
G01X1636514Y1538879D02*
X1644665Y1546700D01*
G01X1636476Y1539070D02*
X1644442Y1546712D01*
G01X1636457Y1539280D02*
X1644197Y1546706D01*
G01X1636438Y1539489D02*
X1643945Y1546690D01*
G01X1632462Y1535903D02*
X1632955Y1536375D01*
G01X1643691Y1546675D02*
X1636420Y1539699D01*
G01X1631978Y1535665D02*
X1633059Y1536703D01*
G01X1636426Y1539932D02*
X1643438Y1546658D01*
G01X1636431Y1540164D02*
X1643184Y1546643D01*
G01X1631592Y1535522D02*
X1633164Y1537030D01*
G01X1636438Y1540398D02*
X1642928Y1546624D01*
G01X1631220Y1535392D02*
X1633267Y1537357D01*
G01X1630912Y1535323D02*
X1633371Y1537683D01*
G01X1636470Y1540657D02*
X1642631Y1546566D01*
G01X1630603Y1535255D02*
X1633476Y1538010D01*
G01X1636504Y1540916D02*
X1642332Y1546507D01*
G01X1630295Y1535187D02*
X1633580Y1538338D01*
G01X1636548Y1541186D02*
X1642034Y1546448D01*
G01X1630037Y1535166D02*
X1633683Y1538664D01*
G01X1636634Y1541496D02*
X1641737Y1546390D01*
G01X1629779Y1535147D02*
X1633787Y1538991D01*
G01X1636721Y1541806D02*
X1641394Y1546289D01*
G01X1629522Y1535128D02*
X1633891Y1539318D01*
G01X1636809Y1542117D02*
X1641019Y1546157D01*
G01X1636896Y1542428D02*
X1640645Y1546024D01*
G01X1629264Y1535106D02*
X1633995Y1539646D01*
G01X1637131Y1542881D02*
X1640222Y1545847D01*
G01X1629050Y1535128D02*
X1634099Y1539972D01*
G01X1628835Y1535149D02*
X1634203Y1540299D01*
G01X1628620Y1535171D02*
X1634307Y1540626D01*
G01X1628406Y1535193D02*
X1633454Y1540035D01*
G01X1628212Y1535233D02*
X1632862Y1539694D01*
G01X1628037Y1535293D02*
X1632449Y1539525D01*
G01X1627862Y1535351D02*
X1632095Y1539413D01*
G01X1627685Y1535411D02*
X1631825Y1539381D01*
G01X1627512Y1535469D02*
X1631559Y1539353D01*
G01X1627363Y1535553D02*
X1631335Y1539365D01*
G01X1627221Y1535646D02*
X1631125Y1539391D01*
G01X1627079Y1535738D02*
X1630931Y1539433D01*
G01X1626939Y1535830D02*
X1630767Y1539502D01*
G01X1626798Y1535922D02*
X1630615Y1539584D01*
G01X1626683Y1536040D02*
X1630498Y1539698D01*
G01X1626573Y1536162D02*
X1630398Y1539830D01*
G01X1626463Y1536283D02*
X1630321Y1539983D01*
G01X1626353Y1536405D02*
X1630270Y1540162D01*
G01X1626244Y1536527D02*
X1630233Y1540353D01*
G01X1626161Y1536675D02*
X1630226Y1540573D01*
G01X1626082Y1536826D02*
X1630224Y1540800D01*
G01X1626002Y1536976D02*
X1630253Y1541053D01*
G01X1625922Y1537127D02*
X1630285Y1541312D01*
G01X1625842Y1537278D02*
X1630329Y1541582D01*
G01X1625793Y1537458D02*
X1630378Y1541855D01*
G01X1625744Y1537638D02*
X1630425Y1542128D01*
G01X1625696Y1537819D02*
X1630474Y1542402D01*
G01X1625647Y1538000D02*
X1630521Y1542676D01*
G01X1625605Y1538186D02*
X1630569Y1542948D01*
G01X1625591Y1538399D02*
X1630618Y1543221D01*
G01X1625576Y1538612D02*
X1630665Y1543495D01*
G01X1625561Y1538826D02*
X1630714Y1543769D01*
G01X1625546Y1539039D02*
X1630761Y1544041D01*
G01X1625556Y1539275D02*
X1630809Y1544314D01*
G01X1625580Y1539526D02*
X1630858Y1544588D01*
G01X1625606Y1539778D02*
X1630905Y1544861D01*
G01X1625630Y1540028D02*
X1630954Y1545135D01*
G01X1625664Y1540287D02*
X1631002Y1545407D01*
G01X1625712Y1540560D02*
X1631049Y1545681D01*
G01X1625759Y1540834D02*
X1631098Y1545955D01*
G01X1631145Y1546228D02*
X1625808Y1541107D01*
G01X1625856Y1541380D02*
X1631194Y1546500D01*
G01X1625903Y1541653D02*
X1631242Y1546774D01*
G01X1625952Y1541927D02*
X1631290Y1547048D01*
G01X1625999Y1542200D02*
X1631338Y1547320D01*
G01X1626047Y1542472D02*
X1631385Y1547594D01*
G01X1626094Y1542746D02*
X1631434Y1547867D01*
G01X1626143Y1543019D02*
X1631482Y1548141D01*
G01X1625759Y1540834D02*
X1625712Y1540560D01*
G01X1626191Y1543292D02*
X1626143Y1543019D01*
G01X1633683Y1538664D02*
X1633580Y1538338D01*
G01X1633787Y1538991D02*
X1633683Y1538664D01*
G01X1633580Y1538338D02*
X1633476Y1538010D01*
G01X1633891Y1539318D02*
X1633787Y1538991D01*
G01X1633476Y1538010D02*
X1633371Y1537683D01*
G01X1633995Y1539646D02*
X1633891Y1539318D01*
G01X1633371Y1537683D02*
X1633267Y1537357D01*
G01D02*
X1633164Y1537030D01*
G01D02*
X1633059Y1536703D01*
G01X1626143Y1543019D02*
X1626094Y1542746D01*
G01X1634099Y1539972D02*
X1633995Y1539646D01*
G01X1626094Y1542746D02*
X1626047Y1542472D01*
G01X1634203Y1540299D02*
X1634099Y1539972D01*
G01X1634307Y1540626D02*
X1634203Y1540299D01*
G01X1633059Y1536703D02*
X1632955Y1536375D01*
G01X1625999Y1542200D02*
X1625952Y1541927D01*
G01D02*
X1625903Y1541653D01*
G01X1626047Y1542472D02*
X1625999Y1542200D01*
G01X1625903Y1541653D02*
X1625856Y1541380D01*
G01X1625759Y1540834D02*
X1625808Y1541107D01*
G01X1630425Y1542128D02*
X1630378Y1541855D01*
G01D02*
X1630329Y1541582D01*
G01X1625856Y1541380D02*
X1625808Y1541107D01*
G01X1630474Y1542402D02*
X1630521Y1542676D01*
G01D02*
X1630569Y1542948D01*
G01X1625712Y1540560D02*
X1625664Y1540287D01*
G01X1630474Y1542402D02*
X1630425Y1542128D01*
G01X1630569Y1542948D02*
X1630618Y1543221D01*
G01X1639240Y1535589D02*
X1642695Y1538902D01*
G01X1639073Y1535656D02*
X1642478Y1538921D01*
G01X1638917Y1535733D02*
X1642292Y1538970D01*
G01X1638764Y1535814D02*
X1642106Y1539018D01*
G01X1638612Y1535895D02*
X1641928Y1539077D01*
G01X1638467Y1535983D02*
X1641776Y1539157D01*
G01X1638330Y1536077D02*
X1641623Y1539237D01*
G01X1638190Y1536172D02*
X1641490Y1539338D01*
G01X1638057Y1536272D02*
X1641371Y1539450D01*
G01X1637934Y1536379D02*
X1641254Y1539566D01*
G01X1637809Y1536487D02*
X1641167Y1539709D01*
G01X1637687Y1536598D02*
X1641082Y1539854D01*
G01X1637577Y1536720D02*
X1641022Y1540025D01*
G01X1637469Y1536842D02*
X1640971Y1540202D01*
G01X1637359Y1536965D02*
X1640942Y1540401D01*
G01X1637264Y1537100D02*
X1640926Y1540614D01*
G01X1637169Y1537237D02*
X1640938Y1540853D01*
G01X1637075Y1537374D02*
X1640964Y1541104D01*
G01X1636992Y1537522D02*
X1641082Y1541445D01*
G01X1636915Y1537675D02*
X1641208Y1541793D01*
G01X1636838Y1537828D02*
X1641870Y1542656D01*
G01X1636767Y1537988D02*
X1645748Y1546602D01*
G01X1636708Y1538158D02*
X1645547Y1546637D01*
G01X1636648Y1538328D02*
X1645338Y1546665D01*
G01X1636594Y1538503D02*
X1645114Y1546676D01*
G01X1636553Y1538691D02*
X1644889Y1546688D01*
G01X1636514Y1538879D02*
X1644665Y1546700D01*
G01X1636476Y1539070D02*
X1644442Y1546712D01*
G01X1636457Y1539280D02*
X1644197Y1546706D01*
G01X1636438Y1539489D02*
X1643945Y1546690D01*
G01X1632462Y1535903D02*
X1632955Y1536375D01*
G01X1643691Y1546675D02*
X1636420Y1539699D01*
G01X1631978Y1535665D02*
X1633059Y1536703D01*
G01X1636426Y1539932D02*
X1643438Y1546658D01*
G01X1636431Y1540164D02*
X1643184Y1546643D01*
G01X1631592Y1535522D02*
X1633164Y1537030D01*
G01X1636438Y1540398D02*
X1642928Y1546624D01*
G01X1631220Y1535392D02*
X1633267Y1537357D01*
G01X1630912Y1535323D02*
X1633371Y1537683D01*
G01X1636470Y1540657D02*
X1642631Y1546566D01*
G01X1630603Y1535255D02*
X1633476Y1538010D01*
G01X1636504Y1540916D02*
X1642332Y1546507D01*
G01X1630295Y1535187D02*
X1633580Y1538338D01*
G01X1636548Y1541186D02*
X1642034Y1546448D01*
G01X1630037Y1535166D02*
X1633683Y1538664D01*
G01X1636634Y1541496D02*
X1641737Y1546390D01*
G01X1629779Y1535147D02*
X1633787Y1538991D01*
G01X1636721Y1541806D02*
X1641394Y1546289D01*
G01X1629522Y1535128D02*
X1633891Y1539318D01*
G01X1636809Y1542117D02*
X1641019Y1546157D01*
G01X1636896Y1542428D02*
X1640645Y1546024D01*
G01X1629264Y1535106D02*
X1633995Y1539646D01*
G01X1637131Y1542881D02*
X1640222Y1545847D01*
G01X1629050Y1535128D02*
X1634099Y1539972D01*
G01X1628835Y1535149D02*
X1634203Y1540299D01*
G01X1628620Y1535171D02*
X1634307Y1540626D01*
G01X1628406Y1535193D02*
X1633454Y1540035D01*
G01X1628212Y1535233D02*
X1632862Y1539694D01*
G01X1628037Y1535293D02*
X1632449Y1539525D01*
G01X1627862Y1535351D02*
X1632095Y1539413D01*
G01X1627685Y1535411D02*
X1631825Y1539381D01*
G01X1627512Y1535469D02*
X1631559Y1539353D01*
G01X1627363Y1535553D02*
X1631335Y1539365D01*
G01X1627221Y1535646D02*
X1631125Y1539391D01*
G01X1627079Y1535738D02*
X1630931Y1539433D01*
G01X1626939Y1535830D02*
X1630767Y1539502D01*
G01X1626798Y1535922D02*
X1630615Y1539584D01*
G01X1626683Y1536040D02*
X1630498Y1539698D01*
G01X1626573Y1536162D02*
X1630398Y1539830D01*
G01X1626463Y1536283D02*
X1630321Y1539983D01*
G01X1626353Y1536405D02*
X1630270Y1540162D01*
G01X1626244Y1536527D02*
X1630233Y1540353D01*
G01X1626161Y1536675D02*
X1630226Y1540573D01*
G01X1626082Y1536826D02*
X1630224Y1540800D01*
G01X1626002Y1536976D02*
X1630253Y1541053D01*
G01X1625922Y1537127D02*
X1630285Y1541312D01*
G01X1625842Y1537278D02*
X1630329Y1541582D01*
G01X1625793Y1537458D02*
X1630378Y1541855D01*
G01X1625744Y1537638D02*
X1630425Y1542128D01*
G01X1625696Y1537819D02*
X1630474Y1542402D01*
G01X1625647Y1538000D02*
X1630521Y1542676D01*
G01X1625605Y1538186D02*
X1630569Y1542948D01*
G01X1625591Y1538399D02*
X1630618Y1543221D01*
G01X1625576Y1538612D02*
X1630665Y1543495D01*
G01X1625561Y1538826D02*
X1630714Y1543769D01*
G01X1625546Y1539039D02*
X1630761Y1544041D01*
G01X1625556Y1539275D02*
X1630809Y1544314D01*
G01X1625580Y1539526D02*
X1630858Y1544588D01*
G01X1625606Y1539778D02*
X1630905Y1544861D01*
G01X1625630Y1540028D02*
X1630954Y1545135D01*
G01X1625664Y1540287D02*
X1631002Y1545407D01*
G01X1625712Y1540560D02*
X1631049Y1545681D01*
G01X1625759Y1540834D02*
X1631098Y1545955D01*
G01X1631145Y1546228D02*
X1625808Y1541107D01*
G01X1625856Y1541380D02*
X1631194Y1546500D01*
G01X1625903Y1541653D02*
X1631242Y1546774D01*
G01X1625952Y1541927D02*
X1631290Y1547048D01*
G01X1625999Y1542200D02*
X1631338Y1547320D01*
G01X1626047Y1542472D02*
X1631385Y1547594D01*
G01X1626094Y1542746D02*
X1631434Y1547867D01*
G01X1626143Y1543019D02*
X1631482Y1548141D01*
G01X1625759Y1540834D02*
X1625712Y1540560D01*
G01X1626191Y1543292D02*
X1626143Y1543019D01*
G01X1633683Y1538664D02*
X1633580Y1538338D01*
G01X1633787Y1538991D02*
X1633683Y1538664D01*
G01X1633580Y1538338D02*
X1633476Y1538010D01*
G01X1633891Y1539318D02*
X1633787Y1538991D01*
G01X1633476Y1538010D02*
X1633371Y1537683D01*
G01X1633995Y1539646D02*
X1633891Y1539318D01*
G01X1633371Y1537683D02*
X1633267Y1537357D01*
G01D02*
X1633164Y1537030D01*
G01D02*
X1633059Y1536703D01*
G01X1626143Y1543019D02*
X1626094Y1542746D01*
G01X1634099Y1539972D02*
X1633995Y1539646D01*
G01X1626094Y1542746D02*
X1626047Y1542472D01*
G01X1634203Y1540299D02*
X1634099Y1539972D01*
G01X1634307Y1540626D02*
X1634203Y1540299D01*
G01X1633059Y1536703D02*
X1632955Y1536375D01*
G01X1625999Y1542200D02*
X1625952Y1541927D01*
G01D02*
X1625903Y1541653D01*
G01X1626047Y1542472D02*
X1625999Y1542200D01*
G01X1625903Y1541653D02*
X1625856Y1541380D01*
G01X1625759Y1540834D02*
X1625808Y1541107D01*
G01X1630425Y1542128D02*
X1630378Y1541855D01*
G01D02*
X1630329Y1541582D01*
G01X1625856Y1541380D02*
X1625808Y1541107D01*
G01X1630474Y1542402D02*
X1630521Y1542676D01*
G01D02*
X1630569Y1542948D01*
G01X1625712Y1540560D02*
X1625664Y1540287D01*
G01X1630474Y1542402D02*
X1630425Y1542128D01*
G01X1630569Y1542948D02*
X1630618Y1543221D01*
G01X1637370Y1543336D02*
X1639673Y1545546D01*
G01X1635539Y1548169D02*
X1635532Y1548163D01*
G01X1635586Y1548443D02*
X1635294Y1548163D01*
G01X1635633Y1548715D02*
X1635058Y1548163D01*
G01X1635682Y1548988D02*
X1634822Y1548163D01*
G01X1635730Y1549261D02*
X1634585Y1548163D01*
G01X1635777Y1549535D02*
X1634348Y1548163D01*
G01X1635825Y1549808D02*
X1634112Y1548163D01*
G01X1635874Y1550081D02*
X1633874Y1548163D01*
G01X1635921Y1550354D02*
X1633637Y1548163D01*
G01X1635968Y1550628D02*
X1633400Y1548163D01*
G01X1636016Y1550900D02*
X1633164Y1548163D01*
G01X1636065Y1551173D02*
X1632928Y1548163D01*
G01X1636112Y1551446D02*
X1632690Y1548163D01*
G01X1636160Y1551720D02*
X1632453Y1548163D01*
G01X1636209Y1551992D02*
X1632215Y1548163D01*
G01X1636256Y1552265D02*
X1631979Y1548163D01*
G01X1636101Y1552345D02*
X1631742Y1548163D01*
G01X1631482Y1548141D02*
X1631505Y1548163D01*
G01X1635864Y1552345D02*
X1631505Y1548163D01*
G01X1626191Y1543292D02*
X1635628Y1552345D01*
G01X1635392D02*
X1626238Y1543565D01*
G01X1635155Y1552345D02*
X1626287Y1543839D01*
G01X1634917Y1552345D02*
X1626334Y1544112D01*
G01X1634680Y1552345D02*
X1626382Y1544385D01*
G01X1634444Y1552345D02*
X1626431Y1544657D01*
G01X1634207Y1552345D02*
X1626478Y1544931D01*
G01X1633969Y1552345D02*
X1626526Y1545205D01*
G01X1633733Y1552345D02*
X1626574Y1545478D01*
G01X1633496Y1552345D02*
X1626622Y1545750D01*
G01X1633260Y1552345D02*
X1626669Y1546024D01*
G01X1633022Y1552345D02*
X1626718Y1546297D01*
G01X1632785Y1552345D02*
X1626766Y1546570D01*
G01X1632549Y1552345D02*
X1626813Y1546843D01*
G01X1632312Y1552345D02*
X1626862Y1547116D01*
G01X1626909Y1547390D02*
X1632245Y1552509D01*
G01X1632294Y1552782D02*
X1626957Y1547663D01*
G01X1632342Y1553055D02*
X1627006Y1547935D01*
G01Y1548163D02*
X1632389Y1553328D01*
G01X1626768Y1548163D02*
X1632438Y1553602D01*
G01X1626531Y1548163D02*
X1632485Y1553875D01*
G01X1626295Y1548163D02*
X1632534Y1554148D01*
G01X1626058Y1548163D02*
X1632582Y1554422D01*
G01X1625820Y1548163D02*
X1632631Y1554695D01*
G01X1625584Y1548163D02*
X1632678Y1554968D01*
G01X1625347Y1548163D02*
X1632725Y1555241D01*
G01X1625111Y1548163D02*
X1632774Y1555515D01*
G01X1624874Y1548163D02*
X1632822Y1555789D01*
G01X1624636Y1548163D02*
X1632869Y1556061D01*
G01X1624400Y1548163D02*
X1632918Y1556334D01*
G01X1624227Y1548224D02*
X1632966Y1556608D01*
G01X1633014Y1556882D02*
X1624274Y1548498D01*
G01X1633062Y1557155D02*
X1624323Y1548771D01*
G01X1633111Y1557427D02*
X1624370Y1549044D01*
G01X1624419Y1549318D02*
X1627574Y1552345D01*
G01X1624467Y1549591D02*
X1627338Y1552345D01*
G01X1624514Y1549864D02*
X1627101Y1552345D01*
G01X1624563Y1550137D02*
X1626865Y1552345D01*
G01X1624610Y1550411D02*
X1626627Y1552345D01*
G01X1624659Y1550684D02*
X1626390Y1552345D01*
G01X1624707Y1550957D02*
X1626154Y1552345D01*
G01X1624756Y1551230D02*
X1625917Y1552345D01*
G01X1631290Y1547048D02*
X1631338Y1547320D01*
G01X1624514Y1549864D02*
X1624563Y1550137D01*
G01X1631338Y1547320D02*
X1631385Y1547594D01*
G01X1624803Y1551504D02*
X1624756Y1551230D01*
G01X1627045Y1548163D02*
X1627006Y1547935D01*
G01Y1548163D02*
X1627045D01*
G01X1631385Y1547594D02*
X1631434Y1547867D01*
G01X1624610Y1550411D02*
X1624659Y1550684D01*
G01X1631242Y1546774D02*
X1631290Y1547048D01*
G01X1624707Y1550957D02*
X1624756Y1551230D01*
G01X1624659Y1550684D02*
X1624707Y1550957D01*
G01X1626909Y1547390D02*
X1626862Y1547116D01*
G01X1635539Y1548169D02*
X1635586Y1548443D01*
G01X1624467Y1549591D02*
X1624514Y1549864D01*
G01X1624419Y1549318D02*
X1624467Y1549591D01*
G01X1635968Y1550628D02*
X1636016Y1550900D01*
G01D02*
X1636065Y1551173D01*
G01X1633637Y1548163D02*
X1633874D01*
G01X1633400D02*
X1633637D01*
G01X1635874Y1550081D02*
X1635921Y1550354D01*
G01X1633164Y1548163D02*
X1632928D01*
G01X1635825Y1549808D02*
X1635874Y1550081D01*
G01X1633164Y1548163D02*
X1633400D01*
G01X1633874D02*
X1634112D01*
G01X1635921Y1550354D02*
X1635968Y1550628D01*
G01X1634585Y1548163D02*
X1634822D01*
G01X1634112D02*
X1634348D01*
G01D02*
X1634585D01*
G01X1632928D02*
X1632690D01*
G01X1635586Y1548443D02*
X1635633Y1548715D01*
G01X1635777Y1549535D02*
X1635825Y1549808D01*
G01X1632453Y1548163D02*
X1632215D01*
G01X1635682Y1548988D02*
X1635730Y1549261D01*
G01D02*
X1635777Y1549535D01*
G01X1632690Y1548163D02*
X1632453D01*
G01X1632215D02*
X1631979D01*
G01X1631742D02*
X1631505D01*
G01X1635633Y1548715D02*
X1635682Y1548988D01*
G01X1631979Y1548163D02*
X1631742D01*
G01X1636065Y1551173D02*
X1636112Y1551446D01*
G01X1631002Y1545407D02*
X1631049Y1545681D01*
G01X1631145Y1546228D02*
X1631098Y1545955D01*
G01D02*
X1631049Y1545681D01*
G01X1630665Y1543495D02*
X1630714Y1543769D01*
G01X1631194Y1546500D02*
X1631242Y1546774D01*
G01X1635537Y1548163D02*
X1635532D01*
G01X1635539Y1548169D02*
X1635537Y1548163D01*
G01X1630618Y1543221D02*
X1630665Y1543495D01*
G01X1635294Y1548163D02*
X1635532D01*
G01X1624563Y1550137D02*
X1624610Y1550411D01*
G01X1631145Y1546228D02*
X1631194Y1546500D01*
G01X1635058Y1548163D02*
X1635294D01*
G01X1630905Y1544861D02*
X1630954Y1545135D01*
G01X1630714Y1543769D02*
X1630761Y1544041D01*
G01X1634822Y1548163D02*
X1635058D01*
G01X1630858Y1544588D02*
X1630905Y1544861D01*
G01X1630761Y1544041D02*
X1630809Y1544314D01*
G01D02*
X1630858Y1544588D01*
G01X1630954Y1545135D02*
X1631002Y1545407D01*
G01X1626768Y1548163D02*
X1627006D01*
G01Y1547935D02*
X1626957Y1547663D01*
G01D02*
X1626909Y1547390D01*
G01X1626813Y1546843D02*
X1626766Y1546570D01*
G01X1626862Y1547116D02*
X1626813Y1546843D01*
G01X1625584Y1548163D02*
X1625820D01*
G01X1625347D02*
X1625584D01*
G01X1625111D02*
X1625347D01*
G01X1626295D02*
X1626531D01*
G01X1625820D02*
X1626058D01*
G01D02*
X1626295D01*
G01X1626766Y1546570D02*
X1626718Y1546297D01*
G01X1626287Y1543839D02*
X1626238Y1543565D01*
G01X1626382Y1544385D02*
X1626334Y1544112D01*
G01D02*
X1626287Y1543839D01*
G01X1631434Y1547867D02*
X1631482Y1548141D01*
G01X1631486Y1548163D02*
X1631505D01*
G01X1631482Y1548141D02*
X1631486Y1548163D01*
G01X1626238Y1543565D02*
X1626191Y1543292D01*
G01X1626431Y1544657D02*
X1626382Y1544385D01*
G01X1626574Y1545478D02*
X1626526Y1545205D01*
G01X1626622Y1545750D02*
X1626574Y1545478D01*
G01X1626669Y1546024D02*
X1626622Y1545750D01*
G01X1626718Y1546297D02*
X1626669Y1546024D01*
G01X1626478Y1544931D02*
X1626431Y1544657D01*
G01X1626526Y1545205D02*
X1626478Y1544931D01*
G01X1626531Y1548163D02*
X1626768D01*
G01X1624874D02*
X1625111D01*
G01X1624323Y1548771D02*
X1624274Y1548498D01*
G01X1624370Y1549044D02*
X1624323Y1548771D01*
G01X1624274Y1548498D02*
X1624227Y1548224D01*
G01X1624370Y1549044D02*
X1624419Y1549318D01*
G01X1624636Y1548163D02*
X1624874D01*
G01X1624216D02*
X1624400D01*
G01X1624227Y1548224D02*
X1624216Y1548163D01*
G01X1624400D02*
X1624636D01*
G01X1637370Y1543336D02*
X1639673Y1545546D01*
G01X1635539Y1548169D02*
X1635532Y1548163D01*
G01X1635586Y1548443D02*
X1635294Y1548163D01*
G01X1635633Y1548715D02*
X1635058Y1548163D01*
G01X1635682Y1548988D02*
X1634822Y1548163D01*
G01X1635730Y1549261D02*
X1634585Y1548163D01*
G01X1635777Y1549535D02*
X1634348Y1548163D01*
G01X1635825Y1549808D02*
X1634112Y1548163D01*
G01X1635874Y1550081D02*
X1633874Y1548163D01*
G01X1635921Y1550354D02*
X1633637Y1548163D01*
G01X1635968Y1550628D02*
X1633400Y1548163D01*
G01X1636016Y1550900D02*
X1633164Y1548163D01*
G01X1636065Y1551173D02*
X1632928Y1548163D01*
G01X1636112Y1551446D02*
X1632690Y1548163D01*
G01X1636160Y1551720D02*
X1632453Y1548163D01*
G01X1636209Y1551992D02*
X1632215Y1548163D01*
G01X1636256Y1552265D02*
X1631979Y1548163D01*
G01X1636101Y1552345D02*
X1631742Y1548163D01*
G01X1631482Y1548141D02*
X1631505Y1548163D01*
G01X1635864Y1552345D02*
X1631505Y1548163D01*
G01X1626191Y1543292D02*
X1635628Y1552345D01*
G01X1635392D02*
X1626238Y1543565D01*
G01X1635155Y1552345D02*
X1626287Y1543839D01*
G01X1634917Y1552345D02*
X1626334Y1544112D01*
G01X1634680Y1552345D02*
X1626382Y1544385D01*
G01X1634444Y1552345D02*
X1626431Y1544657D01*
G01X1634207Y1552345D02*
X1626478Y1544931D01*
G01X1633969Y1552345D02*
X1626526Y1545205D01*
G01X1633733Y1552345D02*
X1626574Y1545478D01*
G01X1633496Y1552345D02*
X1626622Y1545750D01*
G01X1633260Y1552345D02*
X1626669Y1546024D01*
G01X1633022Y1552345D02*
X1626718Y1546297D01*
G01X1632785Y1552345D02*
X1626766Y1546570D01*
G01X1632549Y1552345D02*
X1626813Y1546843D01*
G01X1632312Y1552345D02*
X1626862Y1547116D01*
G01X1626909Y1547390D02*
X1632245Y1552509D01*
G01X1632294Y1552782D02*
X1626957Y1547663D01*
G01X1632342Y1553055D02*
X1627006Y1547935D01*
G01Y1548163D02*
X1632389Y1553328D01*
G01X1626768Y1548163D02*
X1632438Y1553602D01*
G01X1626531Y1548163D02*
X1632485Y1553875D01*
G01X1626295Y1548163D02*
X1632534Y1554148D01*
G01X1626058Y1548163D02*
X1632582Y1554422D01*
G01X1625820Y1548163D02*
X1632631Y1554695D01*
G01X1625584Y1548163D02*
X1632678Y1554968D01*
G01X1625347Y1548163D02*
X1632725Y1555241D01*
G01X1625111Y1548163D02*
X1632774Y1555515D01*
G01X1624874Y1548163D02*
X1632822Y1555789D01*
G01X1624636Y1548163D02*
X1632869Y1556061D01*
G01X1624400Y1548163D02*
X1632918Y1556334D01*
G01X1624227Y1548224D02*
X1632966Y1556608D01*
G01X1633014Y1556882D02*
X1624274Y1548498D01*
G01X1633062Y1557155D02*
X1624323Y1548771D01*
G01X1633111Y1557427D02*
X1624370Y1549044D01*
G01X1624419Y1549318D02*
X1627574Y1552345D01*
G01X1624467Y1549591D02*
X1627338Y1552345D01*
G01X1624514Y1549864D02*
X1627101Y1552345D01*
G01X1624563Y1550137D02*
X1626865Y1552345D01*
G01X1624610Y1550411D02*
X1626627Y1552345D01*
G01X1624659Y1550684D02*
X1626390Y1552345D01*
G01X1624707Y1550957D02*
X1626154Y1552345D01*
G01X1624756Y1551230D02*
X1625917Y1552345D01*
G01X1631290Y1547048D02*
X1631338Y1547320D01*
G01X1624514Y1549864D02*
X1624563Y1550137D01*
G01X1631338Y1547320D02*
X1631385Y1547594D01*
G01X1624803Y1551504D02*
X1624756Y1551230D01*
G01X1627045Y1548163D02*
X1627006Y1547935D01*
G01Y1548163D02*
X1627045D01*
G01X1631385Y1547594D02*
X1631434Y1547867D01*
G01X1624610Y1550411D02*
X1624659Y1550684D01*
G01X1631242Y1546774D02*
X1631290Y1547048D01*
G01X1624707Y1550957D02*
X1624756Y1551230D01*
G01X1624659Y1550684D02*
X1624707Y1550957D01*
G01X1626909Y1547390D02*
X1626862Y1547116D01*
G01X1635539Y1548169D02*
X1635586Y1548443D01*
G01X1624467Y1549591D02*
X1624514Y1549864D01*
G01X1624419Y1549318D02*
X1624467Y1549591D01*
G01X1635968Y1550628D02*
X1636016Y1550900D01*
G01D02*
X1636065Y1551173D01*
G01X1633637Y1548163D02*
X1633874D01*
G01X1633400D02*
X1633637D01*
G01X1635874Y1550081D02*
X1635921Y1550354D01*
G01X1633164Y1548163D02*
X1632928D01*
G01X1635825Y1549808D02*
X1635874Y1550081D01*
G01X1633164Y1548163D02*
X1633400D01*
G01X1633874D02*
X1634112D01*
G01X1635921Y1550354D02*
X1635968Y1550628D01*
G01X1634585Y1548163D02*
X1634822D01*
G01X1634112D02*
X1634348D01*
G01D02*
X1634585D01*
G01X1632928D02*
X1632690D01*
G01X1635586Y1548443D02*
X1635633Y1548715D01*
G01X1635777Y1549535D02*
X1635825Y1549808D01*
G01X1632453Y1548163D02*
X1632215D01*
G01X1635682Y1548988D02*
X1635730Y1549261D01*
G01D02*
X1635777Y1549535D01*
G01X1632690Y1548163D02*
X1632453D01*
G01X1632215D02*
X1631979D01*
G01X1631742D02*
X1631505D01*
G01X1635633Y1548715D02*
X1635682Y1548988D01*
G01X1631979Y1548163D02*
X1631742D01*
G01X1636065Y1551173D02*
X1636112Y1551446D01*
G01X1631002Y1545407D02*
X1631049Y1545681D01*
G01X1631145Y1546228D02*
X1631098Y1545955D01*
G01D02*
X1631049Y1545681D01*
G01X1630665Y1543495D02*
X1630714Y1543769D01*
G01X1631194Y1546500D02*
X1631242Y1546774D01*
G01X1635537Y1548163D02*
X1635532D01*
G01X1635539Y1548169D02*
X1635537Y1548163D01*
G01X1630618Y1543221D02*
X1630665Y1543495D01*
G01X1635294Y1548163D02*
X1635532D01*
G01X1624563Y1550137D02*
X1624610Y1550411D01*
G01X1631145Y1546228D02*
X1631194Y1546500D01*
G01X1635058Y1548163D02*
X1635294D01*
G01X1630905Y1544861D02*
X1630954Y1545135D01*
G01X1630714Y1543769D02*
X1630761Y1544041D01*
G01X1634822Y1548163D02*
X1635058D01*
G01X1630858Y1544588D02*
X1630905Y1544861D01*
G01X1630761Y1544041D02*
X1630809Y1544314D01*
G01D02*
X1630858Y1544588D01*
G01X1630954Y1545135D02*
X1631002Y1545407D01*
G01X1626768Y1548163D02*
X1627006D01*
G01Y1547935D02*
X1626957Y1547663D01*
G01D02*
X1626909Y1547390D01*
G01X1626813Y1546843D02*
X1626766Y1546570D01*
G01X1626862Y1547116D02*
X1626813Y1546843D01*
G01X1625584Y1548163D02*
X1625820D01*
G01X1625347D02*
X1625584D01*
G01X1625111D02*
X1625347D01*
G01X1626295D02*
X1626531D01*
G01X1625820D02*
X1626058D01*
G01D02*
X1626295D01*
G01X1626766Y1546570D02*
X1626718Y1546297D01*
G01X1626287Y1543839D02*
X1626238Y1543565D01*
G01X1626382Y1544385D02*
X1626334Y1544112D01*
G01D02*
X1626287Y1543839D01*
G01X1631434Y1547867D02*
X1631482Y1548141D01*
G01X1631486Y1548163D02*
X1631505D01*
G01X1631482Y1548141D02*
X1631486Y1548163D01*
G01X1626238Y1543565D02*
X1626191Y1543292D01*
G01X1626431Y1544657D02*
X1626382Y1544385D01*
G01X1626574Y1545478D02*
X1626526Y1545205D01*
G01X1626622Y1545750D02*
X1626574Y1545478D01*
G01X1626669Y1546024D02*
X1626622Y1545750D01*
G01X1626718Y1546297D02*
X1626669Y1546024D01*
G01X1626478Y1544931D02*
X1626431Y1544657D01*
G01X1626526Y1545205D02*
X1626478Y1544931D01*
G01X1626531Y1548163D02*
X1626768D01*
G01X1624874D02*
X1625111D01*
G01X1624323Y1548771D02*
X1624274Y1548498D01*
G01X1624370Y1549044D02*
X1624323Y1548771D01*
G01X1624274Y1548498D02*
X1624227Y1548224D01*
G01X1624370Y1549044D02*
X1624419Y1549318D01*
G01X1624636Y1548163D02*
X1624874D01*
G01X1624216D02*
X1624400D01*
G01X1624227Y1548224D02*
X1624216Y1548163D01*
G01X1624400D02*
X1624636D01*
G01X1633158Y1557701D02*
X1627818Y1552579D01*
G01X1633206Y1557974D02*
X1627867Y1552852D01*
G01X1633254Y1558248D02*
X1627915Y1553126D01*
G01X1633302Y1558520D02*
X1627962Y1553398D01*
G01X1633351Y1558794D02*
X1628011Y1553672D01*
G01X1633100Y1558781D02*
X1628058Y1553945D01*
G01X1632645Y1558573D02*
X1628107Y1554218D01*
G01X1632192Y1558364D02*
X1628155Y1554491D01*
G01X1625679Y1552345D02*
X1624803Y1551504D01*
G01X1631737Y1558155D02*
X1628202Y1554765D01*
G01X1631281Y1557946D02*
X1628251Y1555039D01*
G01X1624851Y1551777D02*
X1625443Y1552345D01*
G01X1624899Y1552051D02*
X1625206Y1552345D01*
G01X1630827Y1557737D02*
X1628298Y1555311D01*
G01X1624947Y1552323D02*
X1624970Y1552345D01*
G01X1630374Y1557528D02*
X1628346Y1555584D01*
G01X1629918Y1557319D02*
X1628395Y1555858D01*
G01X1629462Y1557110D02*
X1628442Y1556131D01*
G01X1629009Y1556902D02*
X1628491Y1556404D01*
G01X1628555Y1556693D02*
X1628538Y1556677D01*
G01X1624851Y1551777D02*
X1624899Y1552051D01*
G01X1624851Y1551777D02*
X1624803Y1551504D01*
G01X1627101Y1552345D02*
X1626865D01*
G01X1627338D02*
X1627101D01*
G01X1627574D02*
X1627338D01*
G01X1636160Y1551720D02*
X1636209Y1551992D01*
G01X1636112Y1551446D02*
X1636160Y1551720D01*
G01X1636209Y1551992D02*
X1636256Y1552265D01*
G01X1633496Y1552345D02*
X1633260D01*
G01X1633733D02*
X1633496D01*
G01X1634207D02*
X1633969D01*
G01D02*
X1633733D01*
G01X1634680D02*
X1634444D01*
G01D02*
X1634207D01*
G01X1632785D02*
X1632549D01*
G01X1632342Y1553055D02*
X1632389Y1553328D01*
G01D02*
X1632438Y1553602D01*
G01X1634917Y1552345D02*
X1634680D01*
G01X1633260D02*
X1633022D01*
G01D02*
X1632785D01*
G01X1632245Y1552509D02*
X1632294Y1552782D01*
G01D02*
X1632342Y1553055D01*
G01X1632549Y1552345D02*
X1632312D01*
G01X1636270D02*
X1636101D01*
G01X1636256Y1552265D02*
X1636270Y1552345D01*
G01X1635628D02*
X1635392D01*
G01X1635155D02*
X1634917D01*
G01X1635392D02*
X1635155D01*
G01X1636101D02*
X1635864D01*
G01D02*
X1635628D01*
G01X1632217D02*
X1632312D01*
G01X1632245Y1552509D02*
X1632217Y1552345D01*
G01X1628395Y1555858D02*
X1628346Y1555584D01*
G01X1628395Y1555858D02*
X1628442Y1556131D01*
G01X1628251Y1555039D02*
X1628202Y1554765D01*
G01X1628346Y1555584D02*
X1628298Y1555311D01*
G01X1628202Y1554765D02*
X1628155Y1554491D01*
G01X1628442Y1556131D02*
X1628491Y1556404D01*
G01X1628298Y1555311D02*
X1628251Y1555039D01*
G01X1628540Y1556686D02*
X1628538Y1556677D01*
G01X1628555Y1556693D02*
X1628540Y1556686D01*
G01X1628491Y1556404D02*
X1628538Y1556677D01*
G01X1628155Y1554491D02*
X1628107Y1554218D01*
G01X1628011Y1553672D02*
X1627962Y1553398D01*
G01X1628058Y1553945D02*
X1628011Y1553672D01*
G01X1628107Y1554218D02*
X1628058Y1553945D01*
G01X1627867Y1552852D02*
X1627818Y1552579D01*
G01X1627778Y1552345D02*
X1627818Y1552579D01*
G01X1627574Y1552345D02*
X1627778D01*
G01X1627915Y1553126D02*
X1627867Y1552852D01*
G01X1627962Y1553398D02*
X1627915Y1553126D01*
G01X1633100Y1558781D02*
X1632645Y1558573D01*
G01X1632918Y1556334D02*
X1632966Y1556608D01*
G01X1632645Y1558573D02*
X1632192Y1558364D01*
G01X1626627Y1552345D02*
X1626390D01*
G01X1626865D02*
X1626627D01*
G01X1631737Y1558155D02*
X1631281Y1557946D01*
G01X1632192Y1558364D02*
X1631737Y1558155D01*
G01X1633370Y1558906D02*
X1633100Y1558781D01*
G01X1633351Y1558794D02*
X1633370Y1558906D01*
G01X1633014Y1556882D02*
X1633062Y1557155D01*
G01D02*
X1633111Y1557427D01*
G01X1632966Y1556608D02*
X1633014Y1556882D01*
G01X1633254Y1558248D02*
X1633302Y1558520D01*
G01X1633206Y1557974D02*
X1633254Y1558248D01*
G01X1633111Y1557427D02*
X1633158Y1557701D01*
G01D02*
X1633206Y1557974D01*
G01X1633302Y1558520D02*
X1633351Y1558794D01*
G01X1629918Y1557319D02*
X1629462Y1557110D01*
G01X1631281Y1557946D02*
X1630827Y1557737D01*
G01X1624899Y1552051D02*
X1624947Y1552323D01*
G01X1624951Y1552345D02*
X1624970D01*
G01X1624947Y1552323D02*
X1624951Y1552345D01*
G01X1629009Y1556902D02*
X1628555Y1556693D01*
G01X1629462Y1557110D02*
X1629009Y1556902D01*
G01X1625443Y1552345D02*
X1625206D01*
G01D02*
X1624970D01*
G01X1626154D02*
X1625917D01*
G01X1630827Y1557737D02*
X1630374Y1557528D01*
G01X1626390Y1552345D02*
X1626154D01*
G01X1632438Y1553602D02*
X1632485Y1553875D01*
G01X1625443Y1552345D02*
X1625679D01*
G01D02*
X1625917D01*
G01X1630374Y1557528D02*
X1629918Y1557319D01*
G01X1632822Y1555789D02*
X1632869Y1556061D01*
G01X1632631Y1554695D02*
X1632678Y1554968D01*
G01X1632485Y1553875D02*
X1632534Y1554148D01*
G01X1632774Y1555515D02*
X1632822Y1555789D01*
G01X1632678Y1554968D02*
X1632725Y1555241D01*
G01X1632869Y1556061D02*
X1632918Y1556334D01*
G01X1632534Y1554148D02*
X1632582Y1554422D01*
G01X1632725Y1555241D02*
X1632774Y1555515D01*
G01X1632582Y1554422D02*
X1632631Y1554695D01*
G01X1633158Y1557701D02*
X1627818Y1552579D01*
G01X1633206Y1557974D02*
X1627867Y1552852D01*
G01X1633254Y1558248D02*
X1627915Y1553126D01*
G01X1633302Y1558520D02*
X1627962Y1553398D01*
G01X1633351Y1558794D02*
X1628011Y1553672D01*
G01X1633100Y1558781D02*
X1628058Y1553945D01*
G01X1632645Y1558573D02*
X1628107Y1554218D01*
G01X1632192Y1558364D02*
X1628155Y1554491D01*
G01X1625679Y1552345D02*
X1624803Y1551504D01*
G01X1631737Y1558155D02*
X1628202Y1554765D01*
G01X1631281Y1557946D02*
X1628251Y1555039D01*
G01X1624851Y1551777D02*
X1625443Y1552345D01*
G01X1624899Y1552051D02*
X1625206Y1552345D01*
G01X1630827Y1557737D02*
X1628298Y1555311D01*
G01X1624947Y1552323D02*
X1624970Y1552345D01*
G01X1630374Y1557528D02*
X1628346Y1555584D01*
G01X1629918Y1557319D02*
X1628395Y1555858D01*
G01X1629462Y1557110D02*
X1628442Y1556131D01*
G01X1629009Y1556902D02*
X1628491Y1556404D01*
G01X1628555Y1556693D02*
X1628538Y1556677D01*
G01X1624851Y1551777D02*
X1624899Y1552051D01*
G01X1624851Y1551777D02*
X1624803Y1551504D01*
G01X1627101Y1552345D02*
X1626865D01*
G01X1627338D02*
X1627101D01*
G01X1627574D02*
X1627338D01*
G01X1636160Y1551720D02*
X1636209Y1551992D01*
G01X1636112Y1551446D02*
X1636160Y1551720D01*
G01X1636209Y1551992D02*
X1636256Y1552265D01*
G01X1633496Y1552345D02*
X1633260D01*
G01X1633733D02*
X1633496D01*
G01X1634207D02*
X1633969D01*
G01D02*
X1633733D01*
G01X1634680D02*
X1634444D01*
G01D02*
X1634207D01*
G01X1632785D02*
X1632549D01*
G01X1632342Y1553055D02*
X1632389Y1553328D01*
G01D02*
X1632438Y1553602D01*
G01X1634917Y1552345D02*
X1634680D01*
G01X1633260D02*
X1633022D01*
G01D02*
X1632785D01*
G01X1632245Y1552509D02*
X1632294Y1552782D01*
G01D02*
X1632342Y1553055D01*
G01X1632549Y1552345D02*
X1632312D01*
G01X1636270D02*
X1636101D01*
G01X1636256Y1552265D02*
X1636270Y1552345D01*
G01X1635628D02*
X1635392D01*
G01X1635155D02*
X1634917D01*
G01X1635392D02*
X1635155D01*
G01X1636101D02*
X1635864D01*
G01D02*
X1635628D01*
G01X1632217D02*
X1632312D01*
G01X1632245Y1552509D02*
X1632217Y1552345D01*
G01X1628395Y1555858D02*
X1628346Y1555584D01*
G01X1628395Y1555858D02*
X1628442Y1556131D01*
G01X1628251Y1555039D02*
X1628202Y1554765D01*
G01X1628346Y1555584D02*
X1628298Y1555311D01*
G01X1628202Y1554765D02*
X1628155Y1554491D01*
G01X1628442Y1556131D02*
X1628491Y1556404D01*
G01X1628298Y1555311D02*
X1628251Y1555039D01*
G01X1628540Y1556686D02*
X1628538Y1556677D01*
G01X1628555Y1556693D02*
X1628540Y1556686D01*
G01X1628491Y1556404D02*
X1628538Y1556677D01*
G01X1628155Y1554491D02*
X1628107Y1554218D01*
G01X1628011Y1553672D02*
X1627962Y1553398D01*
G01X1628058Y1553945D02*
X1628011Y1553672D01*
G01X1628107Y1554218D02*
X1628058Y1553945D01*
G01X1627867Y1552852D02*
X1627818Y1552579D01*
G01X1627778Y1552345D02*
X1627818Y1552579D01*
G01X1627574Y1552345D02*
X1627778D01*
G01X1627915Y1553126D02*
X1627867Y1552852D01*
G01X1627962Y1553398D02*
X1627915Y1553126D01*
G01X1633100Y1558781D02*
X1632645Y1558573D01*
G01X1632918Y1556334D02*
X1632966Y1556608D01*
G01X1632645Y1558573D02*
X1632192Y1558364D01*
G01X1626627Y1552345D02*
X1626390D01*
G01X1626865D02*
X1626627D01*
G01X1631737Y1558155D02*
X1631281Y1557946D01*
G01X1632192Y1558364D02*
X1631737Y1558155D01*
G01X1633370Y1558906D02*
X1633100Y1558781D01*
G01X1633351Y1558794D02*
X1633370Y1558906D01*
G01X1633014Y1556882D02*
X1633062Y1557155D01*
G01D02*
X1633111Y1557427D01*
G01X1632966Y1556608D02*
X1633014Y1556882D01*
G01X1633254Y1558248D02*
X1633302Y1558520D01*
G01X1633206Y1557974D02*
X1633254Y1558248D01*
G01X1633111Y1557427D02*
X1633158Y1557701D01*
G01D02*
X1633206Y1557974D01*
G01X1633302Y1558520D02*
X1633351Y1558794D01*
G01X1629918Y1557319D02*
X1629462Y1557110D01*
G01X1631281Y1557946D02*
X1630827Y1557737D01*
G01X1624899Y1552051D02*
X1624947Y1552323D01*
G01X1624951Y1552345D02*
X1624970D01*
G01X1624947Y1552323D02*
X1624951Y1552345D01*
G01X1629009Y1556902D02*
X1628555Y1556693D01*
G01X1629462Y1557110D02*
X1629009Y1556902D01*
G01X1625443Y1552345D02*
X1625206D01*
G01D02*
X1624970D01*
G01X1626154D02*
X1625917D01*
G01X1630827Y1557737D02*
X1630374Y1557528D01*
G01X1626390Y1552345D02*
X1626154D01*
G01X1632438Y1553602D02*
X1632485Y1553875D01*
G01X1625443Y1552345D02*
X1625679D01*
G01D02*
X1625917D01*
G01X1630374Y1557528D02*
X1629918Y1557319D01*
G01X1632822Y1555789D02*
X1632869Y1556061D01*
G01X1632631Y1554695D02*
X1632678Y1554968D01*
G01X1632485Y1553875D02*
X1632534Y1554148D01*
G01X1632774Y1555515D02*
X1632822Y1555789D01*
G01X1632678Y1554968D02*
X1632725Y1555241D01*
G01X1632869Y1556061D02*
X1632918Y1556334D01*
G01X1632534Y1554148D02*
X1632582Y1554422D01*
G01X1632725Y1555241D02*
X1632774Y1555515D01*
G01X1632582Y1554422D02*
X1632631Y1554695D01*
G01X1650002Y1535460D02*
X1650085Y1535540D01*
G01X1649765Y1535460D02*
X1650134Y1535814D01*
G01X1649528Y1535460D02*
X1650182Y1536088D01*
G01X1649292Y1535460D02*
X1650229Y1536360D01*
G01X1649054Y1535460D02*
X1650276Y1536632D01*
G01X1648817Y1535460D02*
X1650325Y1536906D01*
G01X1648580Y1535460D02*
X1650373Y1537180D01*
G01X1648344Y1535460D02*
X1650420Y1537452D01*
G01X1648108Y1535460D02*
X1650469Y1537725D01*
G01X1647870Y1535460D02*
X1650517Y1537999D01*
G01X1647633Y1535460D02*
X1650564Y1538273D01*
G01X1647396Y1535460D02*
X1650613Y1538545D01*
G01X1647160Y1535460D02*
X1650660Y1538818D01*
G01X1646922Y1535460D02*
X1650708Y1539091D01*
G01X1646685Y1535460D02*
X1650757Y1539365D01*
G01X1646449Y1535460D02*
X1650804Y1539637D01*
G01X1646213Y1535460D02*
X1650852Y1539910D01*
G01X1645976Y1535460D02*
X1650899Y1540184D01*
G01X1645738Y1535460D02*
X1650948Y1540457D01*
G01X1645661Y1535612D02*
X1650995Y1540730D01*
G01X1645708Y1535886D02*
X1651043Y1541003D01*
G01X1645757Y1536159D02*
X1651092Y1541277D01*
G01X1651139Y1541550D02*
X1645805Y1536433D01*
G01X1645421Y1536292D02*
X1651187Y1541822D01*
G01X1644747Y1535872D02*
X1651234Y1542095D01*
G01X1644273Y1535645D02*
X1651283Y1542369D01*
G01X1643868Y1535483D02*
X1651330Y1542642D01*
G01X1643531Y1535388D02*
X1651378Y1542915D01*
G01X1643195Y1535292D02*
X1651427Y1543188D01*
G01X1642876Y1535214D02*
X1651474Y1543462D01*
G01X1642612Y1535187D02*
X1651522Y1543735D01*
G01X1642349Y1535163D02*
X1651569Y1544008D01*
G01X1642086Y1535136D02*
X1651618Y1544280D01*
G01X1641821Y1535111D02*
X1651665Y1544554D01*
G01X1641588Y1535114D02*
X1651713Y1544827D01*
G01X1641360Y1535122D02*
X1651762Y1545100D01*
G01X1651809Y1545373D02*
X1641137Y1535136D01*
G01X1651857Y1545647D02*
X1646523Y1540531D01*
G01X1640926Y1535160D02*
X1645563Y1539609D01*
G01X1640716Y1535186D02*
X1644991Y1539287D01*
G01X1651905Y1545920D02*
X1646571Y1540804D01*
G01X1651953Y1546193D02*
X1646620Y1541076D01*
G01X1640514Y1535218D02*
X1644610Y1539148D01*
G01X1652000Y1546465D02*
X1646667Y1541349D01*
G01X1640318Y1535258D02*
X1644229Y1539009D01*
G01X1652048Y1546739D02*
X1646715Y1541623D01*
G01X1640123Y1535298D02*
X1643946Y1538967D01*
G01X1652074Y1546990D02*
X1646764Y1541896D01*
G01X1639937Y1535349D02*
X1643674Y1538933D01*
G01X1652093Y1547236D02*
X1646811Y1542169D01*
G01X1639757Y1535402D02*
X1643403Y1538900D01*
G01X1639576Y1535456D02*
X1643134Y1538869D01*
G01X1652113Y1547482D02*
X1646858Y1542442D01*
G01X1639407Y1535521D02*
X1642914Y1538885D01*
G01X1652133Y1547729D02*
X1646783Y1542596D01*
G01X1652154Y1547977D02*
X1646640Y1542688D01*
G01X1652155Y1548205D02*
X1646491Y1542771D01*
G01X1652128Y1548405D02*
X1646339Y1542852D01*
G01X1652101Y1548607D02*
X1646174Y1542921D01*
G01X1652072Y1548808D02*
X1646004Y1542986D01*
G01X1652045Y1549008D02*
X1645825Y1543041D01*
G01X1642374Y1542912D02*
X1646148Y1546532D01*
G01X1641909Y1542693D02*
X1645947Y1546567D01*
G01X1648817Y1535460D02*
X1649054D01*
G01X1648344D02*
X1648580D01*
G01D02*
X1648817D01*
G01X1647870D02*
X1648108D01*
G01D02*
X1648344D01*
G01X1649765D02*
X1650002D01*
G01X1650072D02*
X1650085Y1535540D01*
G01X1650002Y1535460D02*
X1650072D01*
G01X1647633D02*
X1647870D01*
G01X1649054D02*
X1649292D01*
G01X1649528D02*
X1649765D01*
G01X1649292D02*
X1649528D01*
G01X1645738D02*
X1645976D01*
G01X1645757Y1536159D02*
X1645708Y1535886D01*
G01X1645634Y1535460D02*
X1645738D01*
G01X1645661Y1535612D02*
X1645634Y1535460D01*
G01X1645708Y1535886D02*
X1645661Y1535612D01*
G01X1647160Y1535460D02*
X1647396D01*
G01X1646922D02*
X1647160D01*
G01X1647396D02*
X1647633D01*
G01X1646213D02*
X1646449D01*
G01D02*
X1646685D01*
G01D02*
X1646922D01*
G01X1651092Y1541277D02*
X1651139Y1541550D01*
G01D02*
X1651187Y1541822D01*
G01D02*
X1651234Y1542095D01*
G01X1650995Y1540730D02*
X1651043Y1541003D01*
G01X1650948Y1540457D02*
X1650995Y1540730D01*
G01X1651043Y1541003D02*
X1651092Y1541277D01*
G01X1650899Y1540184D02*
X1650948Y1540457D01*
G01X1651378Y1542915D02*
X1651427Y1543188D01*
G01X1650085Y1535540D02*
X1650134Y1535814D01*
G01X1651330Y1542642D02*
X1651378Y1542915D01*
G01X1651234Y1542095D02*
X1651283Y1542369D01*
G01D02*
X1651330Y1542642D01*
G01X1650276Y1536632D02*
X1650325Y1536906D01*
G01X1650852Y1539910D02*
X1650899Y1540184D01*
G01X1650373Y1537180D02*
X1650420Y1537452D01*
G01X1650325Y1536906D02*
X1650373Y1537180D01*
G01X1650229Y1536360D02*
X1650276Y1536632D01*
G01X1650134Y1535814D02*
X1650182Y1536088D01*
G01D02*
X1650229Y1536360D01*
G01X1650708Y1539091D02*
X1650757Y1539365D01*
G01X1650804Y1539637D02*
X1650852Y1539910D01*
G01X1650660Y1538818D02*
X1650708Y1539091D01*
G01X1650757Y1539365D02*
X1650804Y1539637D01*
G01X1650469Y1537725D02*
X1650517Y1537999D01*
G01X1650420Y1537452D02*
X1650469Y1537725D01*
G01X1650517Y1537999D02*
X1650564Y1538273D01*
G01D02*
X1650613Y1538545D01*
G01D02*
X1650660Y1538818D01*
G01X1645976Y1535460D02*
X1646213D01*
G01X1646764Y1541896D02*
X1646715Y1541623D01*
G01D02*
X1646667Y1541349D01*
G01X1646858Y1542442D02*
X1646811Y1542169D01*
G01D02*
X1646764Y1541896D01*
G01X1646571Y1540804D02*
X1646523Y1540531D01*
G01X1646667Y1541349D02*
X1646620Y1541076D01*
G01D02*
X1646571Y1540804D01*
G01X1645805Y1536433D02*
X1645757Y1536159D01*
G01X1650002Y1535460D02*
X1650085Y1535540D01*
G01X1649765Y1535460D02*
X1650134Y1535814D01*
G01X1649528Y1535460D02*
X1650182Y1536088D01*
G01X1649292Y1535460D02*
X1650229Y1536360D01*
G01X1649054Y1535460D02*
X1650276Y1536632D01*
G01X1648817Y1535460D02*
X1650325Y1536906D01*
G01X1648580Y1535460D02*
X1650373Y1537180D01*
G01X1648344Y1535460D02*
X1650420Y1537452D01*
G01X1648108Y1535460D02*
X1650469Y1537725D01*
G01X1647870Y1535460D02*
X1650517Y1537999D01*
G01X1647633Y1535460D02*
X1650564Y1538273D01*
G01X1647396Y1535460D02*
X1650613Y1538545D01*
G01X1647160Y1535460D02*
X1650660Y1538818D01*
G01X1646922Y1535460D02*
X1650708Y1539091D01*
G01X1646685Y1535460D02*
X1650757Y1539365D01*
G01X1646449Y1535460D02*
X1650804Y1539637D01*
G01X1646213Y1535460D02*
X1650852Y1539910D01*
G01X1645976Y1535460D02*
X1650899Y1540184D01*
G01X1645738Y1535460D02*
X1650948Y1540457D01*
G01X1645661Y1535612D02*
X1650995Y1540730D01*
G01X1645708Y1535886D02*
X1651043Y1541003D01*
G01X1645757Y1536159D02*
X1651092Y1541277D01*
G01X1651139Y1541550D02*
X1645805Y1536433D01*
G01X1645421Y1536292D02*
X1651187Y1541822D01*
G01X1644747Y1535872D02*
X1651234Y1542095D01*
G01X1644273Y1535645D02*
X1651283Y1542369D01*
G01X1643868Y1535483D02*
X1651330Y1542642D01*
G01X1643531Y1535388D02*
X1651378Y1542915D01*
G01X1643195Y1535292D02*
X1651427Y1543188D01*
G01X1642876Y1535214D02*
X1651474Y1543462D01*
G01X1642612Y1535187D02*
X1651522Y1543735D01*
G01X1642349Y1535163D02*
X1651569Y1544008D01*
G01X1642086Y1535136D02*
X1651618Y1544280D01*
G01X1641821Y1535111D02*
X1651665Y1544554D01*
G01X1641588Y1535114D02*
X1651713Y1544827D01*
G01X1641360Y1535122D02*
X1651762Y1545100D01*
G01X1651809Y1545373D02*
X1641137Y1535136D01*
G01X1651857Y1545647D02*
X1646523Y1540531D01*
G01X1640926Y1535160D02*
X1645563Y1539609D01*
G01X1640716Y1535186D02*
X1644991Y1539287D01*
G01X1651905Y1545920D02*
X1646571Y1540804D01*
G01X1651953Y1546193D02*
X1646620Y1541076D01*
G01X1640514Y1535218D02*
X1644610Y1539148D01*
G01X1652000Y1546465D02*
X1646667Y1541349D01*
G01X1640318Y1535258D02*
X1644229Y1539009D01*
G01X1652048Y1546739D02*
X1646715Y1541623D01*
G01X1640123Y1535298D02*
X1643946Y1538967D01*
G01X1652074Y1546990D02*
X1646764Y1541896D01*
G01X1639937Y1535349D02*
X1643674Y1538933D01*
G01X1652093Y1547236D02*
X1646811Y1542169D01*
G01X1639757Y1535402D02*
X1643403Y1538900D01*
G01X1639576Y1535456D02*
X1643134Y1538869D01*
G01X1652113Y1547482D02*
X1646858Y1542442D01*
G01X1639407Y1535521D02*
X1642914Y1538885D01*
G01X1652133Y1547729D02*
X1646783Y1542596D01*
G01X1652154Y1547977D02*
X1646640Y1542688D01*
G01X1652155Y1548205D02*
X1646491Y1542771D01*
G01X1652128Y1548405D02*
X1646339Y1542852D01*
G01X1652101Y1548607D02*
X1646174Y1542921D01*
G01X1652072Y1548808D02*
X1646004Y1542986D01*
G01X1652045Y1549008D02*
X1645825Y1543041D01*
G01X1642374Y1542912D02*
X1646148Y1546532D01*
G01X1641909Y1542693D02*
X1645947Y1546567D01*
G01X1648817Y1535460D02*
X1649054D01*
G01X1648344D02*
X1648580D01*
G01D02*
X1648817D01*
G01X1647870D02*
X1648108D01*
G01D02*
X1648344D01*
G01X1649765D02*
X1650002D01*
G01X1650072D02*
X1650085Y1535540D01*
G01X1650002Y1535460D02*
X1650072D01*
G01X1647633D02*
X1647870D01*
G01X1649054D02*
X1649292D01*
G01X1649528D02*
X1649765D01*
G01X1649292D02*
X1649528D01*
G01X1645738D02*
X1645976D01*
G01X1645757Y1536159D02*
X1645708Y1535886D01*
G01X1645634Y1535460D02*
X1645738D01*
G01X1645661Y1535612D02*
X1645634Y1535460D01*
G01X1645708Y1535886D02*
X1645661Y1535612D01*
G01X1647160Y1535460D02*
X1647396D01*
G01X1646922D02*
X1647160D01*
G01X1647396D02*
X1647633D01*
G01X1646213D02*
X1646449D01*
G01D02*
X1646685D01*
G01D02*
X1646922D01*
G01X1651092Y1541277D02*
X1651139Y1541550D01*
G01D02*
X1651187Y1541822D01*
G01D02*
X1651234Y1542095D01*
G01X1650995Y1540730D02*
X1651043Y1541003D01*
G01X1650948Y1540457D02*
X1650995Y1540730D01*
G01X1651043Y1541003D02*
X1651092Y1541277D01*
G01X1650899Y1540184D02*
X1650948Y1540457D01*
G01X1651378Y1542915D02*
X1651427Y1543188D01*
G01X1650085Y1535540D02*
X1650134Y1535814D01*
G01X1651330Y1542642D02*
X1651378Y1542915D01*
G01X1651234Y1542095D02*
X1651283Y1542369D01*
G01D02*
X1651330Y1542642D01*
G01X1650276Y1536632D02*
X1650325Y1536906D01*
G01X1650852Y1539910D02*
X1650899Y1540184D01*
G01X1650373Y1537180D02*
X1650420Y1537452D01*
G01X1650325Y1536906D02*
X1650373Y1537180D01*
G01X1650229Y1536360D02*
X1650276Y1536632D01*
G01X1650134Y1535814D02*
X1650182Y1536088D01*
G01D02*
X1650229Y1536360D01*
G01X1650708Y1539091D02*
X1650757Y1539365D01*
G01X1650804Y1539637D02*
X1650852Y1539910D01*
G01X1650660Y1538818D02*
X1650708Y1539091D01*
G01X1650757Y1539365D02*
X1650804Y1539637D01*
G01X1650469Y1537725D02*
X1650517Y1537999D01*
G01X1650420Y1537452D02*
X1650469Y1537725D01*
G01X1650517Y1537999D02*
X1650564Y1538273D01*
G01D02*
X1650613Y1538545D01*
G01D02*
X1650660Y1538818D01*
G01X1645976Y1535460D02*
X1646213D01*
G01X1646764Y1541896D02*
X1646715Y1541623D01*
G01D02*
X1646667Y1541349D01*
G01X1646858Y1542442D02*
X1646811Y1542169D01*
G01D02*
X1646764Y1541896D01*
G01X1646571Y1540804D02*
X1646523Y1540531D01*
G01X1646667Y1541349D02*
X1646620Y1541076D01*
G01D02*
X1646571Y1540804D01*
G01X1645805Y1536433D02*
X1645757Y1536159D01*
G01X1652018Y1549209D02*
X1645639Y1543089D01*
G01X1651971Y1549391D02*
X1645444Y1543130D01*
G01X1651903Y1549554D02*
X1645240Y1543163D01*
G01X1651836Y1549716D02*
X1645033Y1543190D01*
G01X1651770Y1549879D02*
X1644817Y1543209D01*
G01X1651703Y1550043D02*
X1644595Y1543224D01*
G01X1651636Y1550206D02*
X1647530Y1546267D01*
G01X1647358Y1546103D02*
X1644368Y1543235D01*
G01X1651558Y1550359D02*
X1647579Y1546541D01*
G01X1647199Y1546178D02*
X1644138Y1543240D01*
G01X1647040Y1546252D02*
X1643904Y1543243D01*
G01X1651458Y1550489D02*
X1647626Y1546814D01*
G01X1646873Y1546319D02*
X1643632Y1543209D01*
G01X1651356Y1550619D02*
X1647655Y1547069D01*
G01X1646694Y1546376D02*
X1643358Y1543175D01*
G01X1651254Y1550750D02*
X1647676Y1547316D01*
G01X1643087Y1543141D02*
X1646517Y1546431D01*
G01X1651154Y1550879D02*
X1647655Y1547522D01*
G01X1642814Y1543107D02*
X1646339Y1546488D01*
G01X1651052Y1551009D02*
X1647630Y1547727D01*
G01X1650951Y1551140D02*
X1647572Y1547898D01*
G01X1650824Y1551245D02*
X1647514Y1548070D01*
G01X1650692Y1551345D02*
X1647425Y1548212D01*
G01X1650560Y1551445D02*
X1647335Y1548351D01*
G01X1650427Y1551545D02*
X1647223Y1548472D01*
G01X1650294Y1551646D02*
X1647100Y1548582D01*
G01X1650163Y1551745D02*
X1646970Y1548684D01*
G01X1650024Y1551840D02*
X1646818Y1548764D01*
G01X1649861Y1551912D02*
X1646663Y1548844D01*
G01X1649699Y1551984D02*
X1646486Y1548901D01*
G01X1649537Y1552055D02*
X1646301Y1548951D01*
G01X1649376Y1552127D02*
X1646107Y1548992D01*
G01X1649213Y1552199D02*
X1645887Y1549009D01*
G01X1649052Y1552271D02*
X1645669Y1549027D01*
G01X1648874Y1552329D02*
X1645434Y1549028D01*
G01X1648684Y1552372D02*
X1645193Y1549023D01*
G01X1648493Y1552416D02*
X1644950Y1549019D01*
G01X1648300Y1552460D02*
X1644699Y1549005D01*
G01X1648110Y1552504D02*
X1644444Y1548987D01*
G01X1647919Y1552548D02*
X1644187Y1548968D01*
G01X1647728Y1552592D02*
X1643913Y1548932D01*
G01X1647511Y1552611D02*
X1643639Y1548897D01*
G01X1647290Y1552626D02*
X1643342Y1548838D01*
G01X1647070Y1552641D02*
X1643040Y1548776D01*
G01X1646848Y1552657D02*
X1642707Y1548684D01*
G01X1642357Y1548575D02*
X1646627Y1552672D01*
G01X1641982Y1548443D02*
X1646405Y1552687D01*
G01X1641566Y1548271D02*
X1646179Y1552696D01*
G01X1641117Y1548068D02*
X1645935Y1552689D01*
G01X1640758Y1547950D02*
X1645691Y1552683D01*
G01X1640694Y1548117D02*
X1645447Y1552676D01*
G01X1640632Y1548283D02*
X1645198Y1552665D01*
G01X1640569Y1548451D02*
X1644938Y1552641D01*
G01X1640505Y1548618D02*
X1644676Y1552618D01*
G01X1640443Y1548785D02*
X1644414Y1552595D01*
G01X1640381Y1548951D02*
X1644136Y1552554D01*
G01X1640317Y1549118D02*
X1643853Y1552509D01*
G01X1640254Y1549286D02*
X1643568Y1552464D01*
G01X1640192Y1549452D02*
X1643260Y1552396D01*
G01X1640128Y1549619D02*
X1642948Y1552323D01*
G01X1640066Y1549786D02*
X1642625Y1552241D01*
G01X1640004Y1549953D02*
X1642274Y1552132D01*
G01X1639940Y1550120D02*
X1641923Y1552022D01*
G01X1639877Y1550287D02*
X1641529Y1551871D01*
G01X1639815Y1550454D02*
X1641129Y1551714D01*
G01X1639751Y1550621D02*
X1640683Y1551515D01*
G01X1639689Y1550788D02*
X1640221Y1551298D01*
G01X1639627Y1550954D02*
X1639726Y1551050D01*
G01X1651665Y1544554D02*
X1651713Y1544827D01*
G01X1652000Y1546465D02*
X1652048Y1546739D01*
G01X1651953Y1546193D02*
X1652000Y1546465D01*
G01X1651905Y1545920D02*
X1651953Y1546193D01*
G01X1651857Y1545647D02*
X1651905Y1545920D01*
G01X1651762Y1545100D02*
X1651809Y1545373D01*
G01X1651713Y1544827D02*
X1651762Y1545100D01*
G01X1651809Y1545373D02*
X1651857Y1545647D01*
G01X1639940Y1550120D02*
X1640004Y1549953D01*
G01X1639877Y1550287D02*
X1639940Y1550120D01*
G01X1640128Y1549619D02*
X1640192Y1549452D01*
G01X1640004Y1549953D02*
X1640066Y1549786D01*
G01X1640192Y1549452D02*
X1640254Y1549286D01*
G01X1639815Y1550454D02*
X1639877Y1550287D01*
G01X1640066Y1549786D02*
X1640128Y1549619D01*
G01X1651427Y1543188D02*
X1651474Y1543462D01*
G01X1651522Y1543735D02*
X1651569Y1544008D01*
G01D02*
X1651618Y1544280D01*
G01X1639751Y1550621D02*
X1639815Y1550454D01*
G01X1639627Y1550954D02*
X1639689Y1550788D01*
G01X1651618Y1544280D02*
X1651665Y1544554D01*
G01X1651474Y1543462D02*
X1651522Y1543735D01*
G01X1639689Y1550788D02*
X1639751Y1550621D01*
G01X1640694Y1548117D02*
X1640758Y1547950D01*
G01X1640632Y1548283D02*
X1640694Y1548117D01*
G01X1640317Y1549118D02*
X1640381Y1548951D01*
G01D02*
X1640443Y1548785D01*
G01X1640254Y1549286D02*
X1640317Y1549118D01*
G01X1640569Y1548451D02*
X1640632Y1548283D01*
G01X1640505Y1548618D02*
X1640569Y1548451D01*
G01X1640443Y1548785D02*
X1640505Y1548618D01*
G01X1647626Y1546814D02*
X1647579Y1546541D01*
G01D02*
X1647530Y1546267D01*
G01X1652018Y1549209D02*
X1645639Y1543089D01*
G01X1651971Y1549391D02*
X1645444Y1543130D01*
G01X1651903Y1549554D02*
X1645240Y1543163D01*
G01X1651836Y1549716D02*
X1645033Y1543190D01*
G01X1651770Y1549879D02*
X1644817Y1543209D01*
G01X1651703Y1550043D02*
X1644595Y1543224D01*
G01X1651636Y1550206D02*
X1647530Y1546267D01*
G01X1647358Y1546103D02*
X1644368Y1543235D01*
G01X1651558Y1550359D02*
X1647579Y1546541D01*
G01X1647199Y1546178D02*
X1644138Y1543240D01*
G01X1647040Y1546252D02*
X1643904Y1543243D01*
G01X1651458Y1550489D02*
X1647626Y1546814D01*
G01X1646873Y1546319D02*
X1643632Y1543209D01*
G01X1651356Y1550619D02*
X1647655Y1547069D01*
G01X1646694Y1546376D02*
X1643358Y1543175D01*
G01X1651254Y1550750D02*
X1647676Y1547316D01*
G01X1643087Y1543141D02*
X1646517Y1546431D01*
G01X1651154Y1550879D02*
X1647655Y1547522D01*
G01X1642814Y1543107D02*
X1646339Y1546488D01*
G01X1651052Y1551009D02*
X1647630Y1547727D01*
G01X1650951Y1551140D02*
X1647572Y1547898D01*
G01X1650824Y1551245D02*
X1647514Y1548070D01*
G01X1650692Y1551345D02*
X1647425Y1548212D01*
G01X1650560Y1551445D02*
X1647335Y1548351D01*
G01X1650427Y1551545D02*
X1647223Y1548472D01*
G01X1650294Y1551646D02*
X1647100Y1548582D01*
G01X1650163Y1551745D02*
X1646970Y1548684D01*
G01X1650024Y1551840D02*
X1646818Y1548764D01*
G01X1649861Y1551912D02*
X1646663Y1548844D01*
G01X1649699Y1551984D02*
X1646486Y1548901D01*
G01X1649537Y1552055D02*
X1646301Y1548951D01*
G01X1649376Y1552127D02*
X1646107Y1548992D01*
G01X1649213Y1552199D02*
X1645887Y1549009D01*
G01X1649052Y1552271D02*
X1645669Y1549027D01*
G01X1648874Y1552329D02*
X1645434Y1549028D01*
G01X1648684Y1552372D02*
X1645193Y1549023D01*
G01X1648493Y1552416D02*
X1644950Y1549019D01*
G01X1648300Y1552460D02*
X1644699Y1549005D01*
G01X1648110Y1552504D02*
X1644444Y1548987D01*
G01X1647919Y1552548D02*
X1644187Y1548968D01*
G01X1647728Y1552592D02*
X1643913Y1548932D01*
G01X1647511Y1552611D02*
X1643639Y1548897D01*
G01X1647290Y1552626D02*
X1643342Y1548838D01*
G01X1647070Y1552641D02*
X1643040Y1548776D01*
G01X1646848Y1552657D02*
X1642707Y1548684D01*
G01X1642357Y1548575D02*
X1646627Y1552672D01*
G01X1641982Y1548443D02*
X1646405Y1552687D01*
G01X1641566Y1548271D02*
X1646179Y1552696D01*
G01X1641117Y1548068D02*
X1645935Y1552689D01*
G01X1640758Y1547950D02*
X1645691Y1552683D01*
G01X1640694Y1548117D02*
X1645447Y1552676D01*
G01X1640632Y1548283D02*
X1645198Y1552665D01*
G01X1640569Y1548451D02*
X1644938Y1552641D01*
G01X1640505Y1548618D02*
X1644676Y1552618D01*
G01X1640443Y1548785D02*
X1644414Y1552595D01*
G01X1640381Y1548951D02*
X1644136Y1552554D01*
G01X1640317Y1549118D02*
X1643853Y1552509D01*
G01X1640254Y1549286D02*
X1643568Y1552464D01*
G01X1640192Y1549452D02*
X1643260Y1552396D01*
G01X1640128Y1549619D02*
X1642948Y1552323D01*
G01X1640066Y1549786D02*
X1642625Y1552241D01*
G01X1640004Y1549953D02*
X1642274Y1552132D01*
G01X1639940Y1550120D02*
X1641923Y1552022D01*
G01X1639877Y1550287D02*
X1641529Y1551871D01*
G01X1639815Y1550454D02*
X1641129Y1551714D01*
G01X1639751Y1550621D02*
X1640683Y1551515D01*
G01X1639689Y1550788D02*
X1640221Y1551298D01*
G01X1639627Y1550954D02*
X1639726Y1551050D01*
G01X1651665Y1544554D02*
X1651713Y1544827D01*
G01X1652000Y1546465D02*
X1652048Y1546739D01*
G01X1651953Y1546193D02*
X1652000Y1546465D01*
G01X1651905Y1545920D02*
X1651953Y1546193D01*
G01X1651857Y1545647D02*
X1651905Y1545920D01*
G01X1651762Y1545100D02*
X1651809Y1545373D01*
G01X1651713Y1544827D02*
X1651762Y1545100D01*
G01X1651809Y1545373D02*
X1651857Y1545647D01*
G01X1639940Y1550120D02*
X1640004Y1549953D01*
G01X1639877Y1550287D02*
X1639940Y1550120D01*
G01X1640128Y1549619D02*
X1640192Y1549452D01*
G01X1640004Y1549953D02*
X1640066Y1549786D01*
G01X1640192Y1549452D02*
X1640254Y1549286D01*
G01X1639815Y1550454D02*
X1639877Y1550287D01*
G01X1640066Y1549786D02*
X1640128Y1549619D01*
G01X1651427Y1543188D02*
X1651474Y1543462D01*
G01X1651522Y1543735D02*
X1651569Y1544008D01*
G01D02*
X1651618Y1544280D01*
G01X1639751Y1550621D02*
X1639815Y1550454D01*
G01X1639627Y1550954D02*
X1639689Y1550788D01*
G01X1651618Y1544280D02*
X1651665Y1544554D01*
G01X1651474Y1543462D02*
X1651522Y1543735D01*
G01X1639689Y1550788D02*
X1639751Y1550621D01*
G01X1640694Y1548117D02*
X1640758Y1547950D01*
G01X1640632Y1548283D02*
X1640694Y1548117D01*
G01X1640317Y1549118D02*
X1640381Y1548951D01*
G01D02*
X1640443Y1548785D01*
G01X1640254Y1549286D02*
X1640317Y1549118D01*
G01X1640569Y1548451D02*
X1640632Y1548283D01*
G01X1640505Y1548618D02*
X1640569Y1548451D01*
G01X1640443Y1548785D02*
X1640505Y1548618D01*
G01X1647626Y1546814D02*
X1647579Y1546541D01*
G01D02*
X1647530Y1546267D01*
G01X1700012Y294362D02*
Y260110D01*
G02X1660642I-19685J0D01*
G01Y294362D01*
G02X1700012I19685J0D01*
G01X1660547Y1644764D02*
Y1671142D01*
G02X1699917I19685J0D01*
G01Y1644764D01*
G02X1660547I-19685J0D01*
G01X1720059Y605413D02*
G02X1759429I19685J0D01*
G02X1720059I-19685J0D01*
G01X1760827Y1714961D02*
G02X1773031I6102J0D01*
G02X1760827I-6102J0D01*
G01X1799528Y1420331D02*
G02X1838898I19685J0D01*
G02X1799528I-19685J0D01*
G01X1795276Y1714961D02*
G02X1817323I11024J0D01*
G02X1795276I-11023J0D01*
G01X1805748Y631890D02*
G02X1827795I11024J0D01*
G02X1805748I-11023J0D01*
G01Y1368898D02*
G02X1827795I11024J0D01*
G02X1805748I-11023J0D01*
G01X1818898Y87795D02*
G02X1840945I11023J0D01*
G02X1818898I-11023J0D01*
G01X1835827Y133465D02*
Y127165D01*
G02X1823622I-6103J0D01*
G01Y133465D01*
G02X1835827I6102J0D01*
G01X1962687Y1844296D02*
Y1845296D01*
X1962853D01*
X1962920Y1845246D01*
X1962970Y1845179D01*
X1963012Y1845079D01*
X1963045Y1844963D01*
X1963053Y1844796D01*
X1963045Y1844629D01*
X1963012Y1844513D01*
X1962970Y1844413D01*
X1962920Y1844346D01*
X1962853Y1844296D01*
X1962687D01*
G01X1963253D02*
Y1845296D01*
X1963470Y1844463D01*
X1963687Y1845296D01*
Y1844296D01*
G01X1964070D02*
Y1845296D01*
X1963970Y1845096D01*
G01Y1844296D02*
X1964170D01*
G01X1964487Y1844496D02*
X1964537Y1844379D01*
X1964603Y1844313D01*
X1964678Y1844296D01*
X1964745Y1844313D01*
X1964812Y1844396D01*
X1964853Y1844496D01*
X1964862Y1844596D01*
X1964845Y1844713D01*
X1964787Y1844796D01*
X1964728Y1844829D01*
X1964653D01*
G01X1964728D02*
X1964778Y1844879D01*
X1964820Y1844963D01*
X1964837Y1845063D01*
X1964820Y1845163D01*
X1964778Y1845246D01*
X1964703Y1845296D01*
X1964628Y1845279D01*
X1964553Y1845213D01*
G01X1956937Y1844416D02*
Y1845416D01*
X1957103D01*
X1957170Y1845366D01*
X1957220Y1845299D01*
X1957262Y1845199D01*
X1957295Y1845083D01*
X1957303Y1844916D01*
X1957295Y1844749D01*
X1957262Y1844633D01*
X1957220Y1844533D01*
X1957170Y1844466D01*
X1957103Y1844416D01*
X1956937D01*
G01X1957503D02*
Y1845416D01*
X1957720Y1844583D01*
X1957937Y1845416D01*
Y1844416D01*
G01X1958178Y1844533D02*
X1958237Y1844449D01*
X1958303Y1844416D01*
X1958370Y1844449D01*
X1958428Y1844549D01*
X1958470Y1844699D01*
X1958487Y1844849D01*
Y1845033D01*
X1958470Y1845183D01*
X1958428Y1845316D01*
X1958378Y1845383D01*
X1958320Y1845416D01*
X1958253Y1845383D01*
X1958203Y1845316D01*
X1958170Y1845216D01*
X1958153Y1845083D01*
X1958170Y1844966D01*
X1958212Y1844849D01*
X1958262Y1844783D01*
X1958320Y1844766D01*
X1958387Y1844799D01*
X1958437Y1844883D01*
X1958487Y1845033D01*
G01X-984580Y-698988D02*
Y4193602D01*
X5868320D01*
Y-698988D01*
X-984580D01*
G01X7723Y-521204D02*
X7253Y-520889D01*
X6705Y-520679D01*
X6078D01*
X5373Y-520994D01*
X4825Y-521519D01*
X4433Y-522149D01*
X4120Y-523199D01*
X4042Y-524144D01*
X4198Y-525089D01*
X4433Y-525719D01*
X4903Y-526349D01*
X5452Y-526769D01*
X6000Y-526979D01*
X6548D01*
X7097Y-526769D01*
X7567Y-526454D01*
X7958Y-526034D01*
G01X11360Y-520679D02*
X13240D01*
G01X12300D02*
Y-526979D01*
G01X11360D02*
X13240D01*
G01X18600Y-520679D02*
Y-526979D01*
G01X16798Y-520679D02*
X20402D01*
G01X24900Y-526979D02*
Y-524144D01*
X23333Y-520679D01*
G01X26467D02*
X24900Y-524144D01*
G01X35777Y-525719D02*
X36247Y-526454D01*
X36873Y-526874D01*
X37578Y-526979D01*
X38205Y-526874D01*
X38832Y-526349D01*
X39223Y-525719D01*
X39302Y-525089D01*
X39145Y-524354D01*
X38597Y-523829D01*
X38048Y-523619D01*
X37343D01*
G01X38048D02*
X38518Y-523304D01*
X38910Y-522779D01*
X39067Y-522149D01*
X38910Y-521519D01*
X38518Y-520994D01*
X37813Y-520679D01*
X37108Y-520784D01*
X36403Y-521204D01*
G01X42077Y-525719D02*
X42547Y-526454D01*
X43173Y-526874D01*
X43878Y-526979D01*
X44505Y-526874D01*
X45132Y-526349D01*
X45523Y-525719D01*
X45602Y-525089D01*
X45445Y-524354D01*
X44897Y-523829D01*
X44348Y-523619D01*
X43643D01*
G01X44348D02*
X44818Y-523304D01*
X45210Y-522779D01*
X45367Y-522149D01*
X45210Y-521519D01*
X44818Y-520994D01*
X44113Y-520679D01*
X43408Y-520784D01*
X42703Y-521204D01*
G01X48377Y-525719D02*
X48847Y-526454D01*
X49473Y-526874D01*
X50178Y-526979D01*
X50805Y-526874D01*
X51432Y-526349D01*
X51823Y-525719D01*
X51902Y-525089D01*
X51745Y-524354D01*
X51197Y-523829D01*
X50648Y-523619D01*
X49943D01*
G01X50648D02*
X51118Y-523304D01*
X51510Y-522779D01*
X51667Y-522149D01*
X51510Y-521519D01*
X51118Y-520994D01*
X50413Y-520679D01*
X49708Y-520784D01*
X49003Y-521204D01*
G01X56243Y-526979D02*
X56400Y-525614D01*
X56635Y-524459D01*
X56948Y-523409D01*
X57340Y-522254D01*
X57967Y-520679D01*
X54833D01*
G01X62543Y-526979D02*
X62700Y-525614D01*
X62935Y-524459D01*
X63248Y-523409D01*
X63640Y-522254D01*
X64267Y-520679D01*
X61133D01*
G01X68843Y-528134D02*
X69157Y-526769D01*
G01X75300Y-520679D02*
Y-526979D01*
G01X73498Y-520679D02*
X77102D01*
G01X79642Y-526979D02*
X81600Y-520679D01*
X83558Y-526979D01*
G01X82853Y-524774D02*
X80347D01*
G01X86960Y-520679D02*
X88840D01*
G01X87900D02*
Y-526979D01*
G01X86960D02*
X88840D01*
G01X91850Y-520679D02*
X92947Y-526979D01*
X94200Y-520679D01*
X95453Y-526979D01*
X96550Y-520679D01*
G01X98542Y-526979D02*
X100500Y-520679D01*
X102458Y-526979D01*
G01X101753Y-524774D02*
X99247D01*
G01X104998Y-526979D02*
Y-520679D01*
X108602Y-526979D01*
Y-520679D01*
G01X119008Y-529079D02*
X118225Y-528029D01*
X117833Y-526979D01*
Y-522779D01*
X118225Y-521729D01*
X119008Y-520679D01*
G01X130433Y-526979D02*
Y-520679D01*
X132392D01*
X133018Y-520994D01*
X133410Y-521414D01*
X133567Y-522254D01*
X133410Y-523094D01*
X132940Y-523619D01*
X132392Y-523934D01*
X130433D01*
G01X132392D02*
X133567Y-526979D01*
G01X138300Y-527189D02*
X138143Y-527084D01*
Y-526874D01*
X138300Y-526769D01*
X138457Y-526874D01*
Y-527084D01*
X138300Y-527189D01*
G01X144600Y-526979D02*
X143973Y-526874D01*
X143425Y-526454D01*
X142955Y-525824D01*
X142642Y-525089D01*
X142485Y-524249D01*
Y-523409D01*
X142642Y-522569D01*
X142955Y-521834D01*
X143425Y-521204D01*
X143973Y-520784D01*
X144600Y-520679D01*
X145227Y-520784D01*
X145775Y-521204D01*
X146245Y-521834D01*
X146558Y-522569D01*
X146715Y-523409D01*
Y-524249D01*
X146558Y-525089D01*
X146245Y-525824D01*
X145775Y-526454D01*
X145227Y-526874D01*
X144600Y-526979D01*
G01X150900Y-527189D02*
X150743Y-527084D01*
Y-526874D01*
X150900Y-526769D01*
X151057Y-526874D01*
Y-527084D01*
X150900Y-527189D01*
G01X158923Y-521204D02*
X158453Y-520889D01*
X157905Y-520679D01*
X157278D01*
X156573Y-520994D01*
X156025Y-521519D01*
X155633Y-522149D01*
X155320Y-523199D01*
X155242Y-524144D01*
X155398Y-525089D01*
X155633Y-525719D01*
X156103Y-526349D01*
X156652Y-526769D01*
X157200Y-526979D01*
X157748D01*
X158297Y-526769D01*
X158767Y-526454D01*
X159158Y-526034D01*
G01X163500Y-527189D02*
X163343Y-527084D01*
Y-526874D01*
X163500Y-526769D01*
X163657Y-526874D01*
Y-527084D01*
X163500Y-527189D01*
G01X170192Y-529079D02*
X170975Y-528029D01*
X171367Y-526979D01*
Y-522779D01*
X170975Y-521729D01*
X170192Y-520679D01*
G01X6470Y-513829D02*
X8037D01*
Y-515719D01*
X7567Y-516349D01*
X7018Y-516769D01*
X6235Y-516979D01*
X5452Y-516769D01*
X4903Y-516349D01*
X4433Y-515719D01*
X4120Y-514984D01*
X3963Y-514144D01*
Y-513409D01*
X4120Y-512779D01*
X4433Y-512044D01*
X4903Y-511414D01*
X5373Y-510994D01*
X6000Y-510679D01*
X6548D01*
X7175Y-510889D01*
X7645Y-511309D01*
G01X10577Y-510679D02*
Y-515194D01*
X10890Y-516139D01*
X11517Y-516769D01*
X12300Y-516979D01*
X13083Y-516769D01*
X13710Y-516139D01*
X14023Y-515194D01*
Y-510679D01*
G01X17660D02*
X19540D01*
G01X18600D02*
Y-516979D01*
G01X17660D02*
X19540D01*
G01X23255Y-516139D02*
X23882Y-516664D01*
X24587Y-516979D01*
X25213D01*
X25840Y-516664D01*
X26310Y-516139D01*
X26545Y-515404D01*
X26388Y-514669D01*
X25997Y-514039D01*
X25292Y-513619D01*
X24352Y-513409D01*
X23803Y-512989D01*
X23568Y-512254D01*
X23725Y-511519D01*
X24117Y-510994D01*
X24665Y-510679D01*
X25213D01*
X25762Y-510889D01*
X26232Y-511414D01*
G01X29555Y-516979D02*
Y-510679D01*
G01X32845D02*
Y-516979D01*
G01Y-513829D02*
X29555D01*
G01X35542Y-516979D02*
X37500Y-510679D01*
X39458Y-516979D01*
G01X38753Y-514774D02*
X36247D01*
G01X41998Y-516979D02*
Y-510679D01*
X45602Y-516979D01*
Y-510679D01*
G01X54677Y-516979D02*
Y-510679D01*
X56243D01*
X56870Y-510994D01*
X57340Y-511414D01*
X57732Y-512044D01*
X58045Y-512779D01*
X58123Y-513829D01*
X58045Y-514879D01*
X57732Y-515614D01*
X57340Y-516244D01*
X56870Y-516664D01*
X56243Y-516979D01*
X54677D01*
G01X61760Y-510679D02*
X63640D01*
G01X62700D02*
Y-516979D01*
G01X61760D02*
X63640D01*
G01X67355Y-516139D02*
X67982Y-516664D01*
X68687Y-516979D01*
X69313D01*
X69940Y-516664D01*
X70410Y-516139D01*
X70645Y-515404D01*
X70488Y-514669D01*
X70097Y-514039D01*
X69392Y-513619D01*
X68452Y-513409D01*
X67903Y-512989D01*
X67668Y-512254D01*
X67825Y-511519D01*
X68217Y-510994D01*
X68765Y-510679D01*
X69313D01*
X69862Y-510889D01*
X70332Y-511414D01*
G01X75300Y-510679D02*
Y-516979D01*
G01X73498Y-510679D02*
X77102D01*
G01X81600Y-517189D02*
X81443Y-517084D01*
Y-516874D01*
X81600Y-516769D01*
X81757Y-516874D01*
Y-517084D01*
X81600Y-517189D01*
G01X87743Y-518134D02*
X88057Y-516769D01*
G01X94200Y-510679D02*
Y-516979D01*
G01X92398Y-510679D02*
X96002D01*
G01X98542Y-516979D02*
X100500Y-510679D01*
X102458Y-516979D01*
G01X101753Y-514774D02*
X99247D01*
G01X106800Y-516979D02*
X106173Y-516874D01*
X105625Y-516454D01*
X105155Y-515824D01*
X104842Y-515089D01*
X104685Y-514249D01*
Y-513409D01*
X104842Y-512569D01*
X105155Y-511834D01*
X105625Y-511204D01*
X106173Y-510784D01*
X106800Y-510679D01*
X107427Y-510784D01*
X107975Y-511204D01*
X108445Y-511834D01*
X108758Y-512569D01*
X108915Y-513409D01*
Y-514249D01*
X108758Y-515089D01*
X108445Y-515824D01*
X107975Y-516454D01*
X107427Y-516874D01*
X106800Y-516979D01*
G01X113100D02*
Y-514144D01*
X111533Y-510679D01*
G01X114667D02*
X113100Y-514144D01*
G01X117677Y-510679D02*
Y-515194D01*
X117990Y-516139D01*
X118617Y-516769D01*
X119400Y-516979D01*
X120183Y-516769D01*
X120810Y-516139D01*
X121123Y-515194D01*
Y-510679D01*
G01X123742Y-516979D02*
X125700Y-510679D01*
X127658Y-516979D01*
G01X126953Y-514774D02*
X124447D01*
G01X130198Y-516979D02*
Y-510679D01*
X133802Y-516979D01*
Y-510679D01*
G01X4198Y-506979D02*
Y-500679D01*
X7802Y-506979D01*
Y-500679D01*
G01X12300Y-506979D02*
X11673Y-506874D01*
X11125Y-506454D01*
X10655Y-505824D01*
X10342Y-505089D01*
X10185Y-504249D01*
Y-503409D01*
X10342Y-502569D01*
X10655Y-501834D01*
X11125Y-501204D01*
X11673Y-500784D01*
X12300Y-500679D01*
X12927Y-500784D01*
X13475Y-501204D01*
X13945Y-501834D01*
X14258Y-502569D01*
X14415Y-503409D01*
Y-504249D01*
X14258Y-505089D01*
X13945Y-505824D01*
X13475Y-506454D01*
X12927Y-506874D01*
X12300Y-506979D01*
G01X18600Y-507189D02*
X18443Y-507084D01*
Y-506874D01*
X18600Y-506769D01*
X18757Y-506874D01*
Y-507084D01*
X18600Y-507189D01*
G01X23412Y-501729D02*
X23882Y-501099D01*
X24430Y-500784D01*
X25057Y-500679D01*
X25840Y-500889D01*
X26388Y-501414D01*
X26545Y-502044D01*
X26467Y-502674D01*
X26153Y-503199D01*
X24587Y-504249D01*
X23882Y-504984D01*
X23412Y-506034D01*
X23255Y-506979D01*
X26545D01*
G01X31200D02*
Y-500679D01*
X30260Y-501939D01*
G01Y-506979D02*
X32140D01*
G01X37500D02*
Y-500679D01*
X36560Y-501939D01*
G01Y-506979D02*
X38440D01*
G01X43643Y-508134D02*
X43957Y-506769D01*
G01X47750Y-500679D02*
X48847Y-506979D01*
X50100Y-500679D01*
X51353Y-506979D01*
X52450Y-500679D01*
G01X57967Y-506979D02*
X54833D01*
Y-500679D01*
X57967D01*
G01X56713Y-503724D02*
X54833D01*
G01X60898Y-506979D02*
Y-500679D01*
X64502Y-506979D01*
Y-500679D01*
G01X67355Y-506979D02*
Y-500679D01*
G01X70645D02*
Y-506979D01*
G01Y-503829D02*
X67355D01*
G01X73577Y-500679D02*
Y-505194D01*
X73890Y-506139D01*
X74517Y-506769D01*
X75300Y-506979D01*
X76083Y-506769D01*
X76710Y-506139D01*
X77023Y-505194D01*
Y-500679D01*
G01X79642Y-506979D02*
X81600Y-500679D01*
X83558Y-506979D01*
G01X82853Y-504774D02*
X80347D01*
G01X92712Y-501729D02*
X93182Y-501099D01*
X93730Y-500784D01*
X94357Y-500679D01*
X95140Y-500889D01*
X95688Y-501414D01*
X95845Y-502044D01*
X95767Y-502674D01*
X95453Y-503199D01*
X93887Y-504249D01*
X93182Y-504984D01*
X92712Y-506034D01*
X92555Y-506979D01*
X95845D01*
G01X98698D02*
Y-500679D01*
X102302Y-506979D01*
Y-500679D01*
G01X105077Y-506979D02*
Y-500679D01*
X106643D01*
X107270Y-500994D01*
X107740Y-501414D01*
X108132Y-502044D01*
X108445Y-502779D01*
X108523Y-503829D01*
X108445Y-504879D01*
X108132Y-505614D01*
X107740Y-506244D01*
X107270Y-506664D01*
X106643Y-506979D01*
X105077D01*
G01X117833D02*
Y-500679D01*
X119792D01*
X120418Y-500994D01*
X120810Y-501414D01*
X120967Y-502254D01*
X120810Y-503094D01*
X120340Y-503619D01*
X119792Y-503934D01*
X117833D01*
G01X119792D02*
X120967Y-506979D01*
G01X123977D02*
Y-500679D01*
X125543D01*
X126170Y-500994D01*
X126640Y-501414D01*
X127032Y-502044D01*
X127345Y-502779D01*
X127423Y-503829D01*
X127345Y-504879D01*
X127032Y-505614D01*
X126640Y-506244D01*
X126170Y-506664D01*
X125543Y-506979D01*
X123977D01*
G01X132000Y-507189D02*
X131843Y-507084D01*
Y-506874D01*
X132000Y-506769D01*
X132157Y-506874D01*
Y-507084D01*
X132000Y-507189D01*
G01X11474Y109882D02*
Y112982D01*
G01X13084D02*
Y109882D01*
G01Y111432D02*
X11474D01*
G01X15379Y109882D02*
Y112982D01*
X14919Y112362D01*
G01Y109882D02*
X15839D01*
G01X18479Y112982D02*
X18172Y112879D01*
X17942Y112620D01*
X17789Y112310D01*
X17674Y111897D01*
X17636Y111432D01*
X17674Y110967D01*
X17789Y110554D01*
X17942Y110244D01*
X18172Y109985D01*
X18479Y109882D01*
X18786Y109985D01*
X19016Y110244D01*
X19169Y110554D01*
X19284Y110967D01*
X19322Y111432D01*
X19284Y111897D01*
X19169Y112310D01*
X19016Y112620D01*
X18786Y112879D01*
X18479Y112982D01*
G01X21579D02*
X21272Y112879D01*
X21042Y112620D01*
X20889Y112310D01*
X20774Y111897D01*
X20736Y111432D01*
X20774Y110967D01*
X20889Y110554D01*
X21042Y110244D01*
X21272Y109985D01*
X21579Y109882D01*
X21886Y109985D01*
X22116Y110244D01*
X22269Y110554D01*
X22384Y110967D01*
X22422Y111432D01*
X22384Y111897D01*
X22269Y112310D01*
X22116Y112620D01*
X21886Y112879D01*
X21579Y112982D01*
G01X55768Y1819506D02*
Y1816406D01*
X54848D01*
X54541Y1816561D01*
X54311Y1816923D01*
X54234Y1817336D01*
X54311Y1817749D01*
X54503Y1818059D01*
X54848Y1818214D01*
X55768D01*
G01X52591Y1819609D02*
X51211Y1816406D01*
G01X49683Y1819506D02*
Y1816406D01*
X47919Y1819506D01*
Y1816406D01*
G01X45701Y1819609D02*
X45778Y1819558D01*
Y1819454D01*
X45701Y1819403D01*
X45624Y1819454D01*
Y1819558D01*
X45701Y1819609D01*
G01Y1818214D02*
X45778Y1818163D01*
Y1818059D01*
X45701Y1818008D01*
X45624Y1818059D01*
Y1818163D01*
X45701Y1818214D01*
G01X43444Y1819506D02*
Y1816406D01*
X42678D01*
X42371Y1816561D01*
X42141Y1816768D01*
X41949Y1817078D01*
X41796Y1817439D01*
X41758Y1817956D01*
X41796Y1818473D01*
X41949Y1818834D01*
X42141Y1819144D01*
X42371Y1819351D01*
X42678Y1819506D01*
X43444D01*
G01X40459D02*
X39501Y1816406D01*
X38543Y1819506D01*
G01X38888Y1818421D02*
X40114D01*
G01X36401Y1816406D02*
X36708Y1816509D01*
X36938Y1816768D01*
X37091Y1817078D01*
X37206Y1817491D01*
X37244Y1817956D01*
X37206Y1818421D01*
X37091Y1818834D01*
X36938Y1819144D01*
X36708Y1819403D01*
X36401Y1819506D01*
X36094Y1819403D01*
X35864Y1819144D01*
X35711Y1818834D01*
X35596Y1818421D01*
X35558Y1817956D01*
X35596Y1817491D01*
X35711Y1817078D01*
X35864Y1816768D01*
X36094Y1816509D01*
X36401Y1816406D01*
G01X34029Y1819506D02*
Y1816406D01*
X32573D01*
G01X33109Y1817904D02*
X34029D01*
G01X30201Y1816406D02*
X30508Y1816509D01*
X30738Y1816768D01*
X30891Y1817078D01*
X31006Y1817491D01*
X31044Y1817956D01*
X31006Y1818421D01*
X30891Y1818834D01*
X30738Y1819144D01*
X30508Y1819403D01*
X30201Y1819506D01*
X29894Y1819403D01*
X29664Y1819144D01*
X29511Y1818834D01*
X29396Y1818421D01*
X29358Y1817956D01*
X29396Y1817491D01*
X29511Y1817078D01*
X29664Y1816768D01*
X29894Y1816509D01*
X30201Y1816406D01*
G01X27101D02*
Y1819506D01*
G01X27983Y1816406D02*
X26219D01*
G01X24998Y1819506D02*
Y1816406D01*
X24001Y1818989D01*
X23004Y1816406D01*
Y1819506D01*
G01X20594Y1817853D02*
X20441Y1817698D01*
X20326Y1817439D01*
X20249Y1817078D01*
X20326Y1816768D01*
X20479Y1816561D01*
X20748Y1816406D01*
X21783D01*
Y1819506D01*
X20518D01*
X20249Y1819299D01*
X20096Y1818989D01*
X20019Y1818628D01*
X20096Y1818266D01*
X20326Y1817956D01*
X20594Y1817853D01*
X21783D01*
G01X18261Y1816406D02*
X17341D01*
G01X17801D02*
Y1819506D01*
G01X18261D02*
X17341D01*
G01X15468Y1818886D02*
X15276Y1819196D01*
X15046Y1819403D01*
X14778Y1819506D01*
X14471Y1819403D01*
X14241Y1819196D01*
X14011Y1818886D01*
X13934Y1818473D01*
Y1816406D01*
G01X11601D02*
X11908Y1816509D01*
X12138Y1816768D01*
X12291Y1817078D01*
X12406Y1817491D01*
X12444Y1817956D01*
X12406Y1818421D01*
X12291Y1818834D01*
X12138Y1819144D01*
X11908Y1819403D01*
X11601Y1819506D01*
X11294Y1819403D01*
X11064Y1819144D01*
X10911Y1818834D01*
X10796Y1818421D01*
X10758Y1817956D01*
X10796Y1817491D01*
X10911Y1817078D01*
X11064Y1816768D01*
X11294Y1816509D01*
X11601Y1816406D01*
G01X28300Y-494279D02*
X25780Y-493862D01*
X23575Y-492196D01*
X21685Y-489696D01*
X20425Y-486779D01*
X19795Y-483446D01*
Y-480112D01*
X20425Y-476779D01*
X21685Y-473862D01*
X23575Y-471363D01*
X25780Y-469696D01*
X28300Y-469279D01*
X30820Y-469696D01*
X33025Y-471363D01*
X34915Y-473862D01*
X36175Y-476779D01*
X36805Y-480112D01*
Y-483446D01*
X36175Y-486779D01*
X34915Y-489696D01*
X33025Y-492196D01*
X30820Y-493862D01*
X28300Y-494279D01*
G01X30820Y-487612D02*
X34600Y-494279D01*
G01X48145Y-477613D02*
Y-489279D01*
X49405Y-492196D01*
X51295Y-493862D01*
X53500Y-494279D01*
X55705Y-493862D01*
X57595Y-492196D01*
X58855Y-489279D01*
G01Y-494279D02*
Y-477613D01*
G01X84370Y-494279D02*
Y-477613D01*
G01Y-480529D02*
X83110Y-478863D01*
X81220Y-478029D01*
X79015Y-477613D01*
X76810Y-478446D01*
X74920Y-480112D01*
X73660Y-482613D01*
X73030Y-485946D01*
X73660Y-489279D01*
X74920Y-491780D01*
X76810Y-493446D01*
X79015Y-494279D01*
X81220Y-493862D01*
X83110Y-492613D01*
X84370Y-490946D01*
G01X98545Y-494279D02*
Y-477613D01*
G01Y-481779D02*
X99805Y-479696D01*
X101695Y-478029D01*
X104215Y-477613D01*
X106420Y-478029D01*
X108310Y-479696D01*
X109255Y-482613D01*
Y-494279D01*
G01X129100Y-469279D02*
Y-494279D01*
G01X124690Y-477613D02*
X133510D01*
G01X159970Y-494279D02*
Y-477613D01*
G01Y-480529D02*
X158710Y-478863D01*
X156820Y-478029D01*
X154615Y-477613D01*
X152410Y-478446D01*
X150520Y-480112D01*
X149260Y-482613D01*
X148630Y-485946D01*
X149260Y-489279D01*
X150520Y-491780D01*
X152410Y-493446D01*
X154615Y-494279D01*
X156820Y-493862D01*
X158710Y-492613D01*
X159970Y-490946D01*
G01X21600Y194962D02*
Y191762D01*
G01X15400Y194962D02*
X21600D01*
G01X15400Y191762D02*
Y194962D01*
G01X21600Y191762D02*
X15400D01*
G01X21600Y201962D02*
Y198762D01*
G01X15400D02*
Y201962D01*
G01X21600Y198762D02*
X15400D01*
G01Y201962D02*
X21600D01*
G01X26120Y214762D02*
Y217962D01*
G01X32320Y214762D02*
X26120D01*
G01Y230762D02*
Y233962D01*
G01X32320Y230762D02*
X26120D01*
G01Y217962D02*
X32320D01*
G01X26120Y222762D02*
Y225962D01*
G01X32320Y222762D02*
X26120D01*
G01Y225962D02*
X32320D01*
G01X26120Y233962D02*
X32320D01*
G01X26120Y241962D02*
X32320D01*
G01X26120Y238762D02*
Y241962D01*
G01X32320Y238762D02*
X26120D01*
G01X16517Y286349D02*
Y284127D01*
X16670Y283662D01*
X16977Y283352D01*
X17360Y283249D01*
X17743Y283352D01*
X18050Y283662D01*
X18203Y284127D01*
Y286349D01*
G01X19732Y285832D02*
X19962Y286142D01*
X20230Y286297D01*
X20537Y286349D01*
X20920Y286246D01*
X21188Y285987D01*
X21265Y285677D01*
X21227Y285367D01*
X21073Y285109D01*
X20307Y284592D01*
X19962Y284231D01*
X19732Y283714D01*
X19655Y283249D01*
X21265D01*
G01X24020D02*
Y286349D01*
X22602Y284127D01*
X24518D01*
G01X26660Y283249D02*
Y286349D01*
X26200Y285729D01*
G01Y283249D02*
X27120D01*
G01X24082Y300274D02*
X21080Y296672D01*
G01X25832Y288070D02*
Y300274D01*
G01X16328Y288070D02*
X25832D01*
G01X16328Y300274D02*
Y288070D01*
G01X21080Y296672D02*
X18078Y300274D01*
G01X25832D02*
X24082D01*
G01X18078D02*
X16328D01*
G01X26215Y344339D02*
Y347439D01*
G01X27825D02*
Y344339D01*
G01Y345889D02*
X26215D01*
G01X29392Y346922D02*
X29622Y347232D01*
X29890Y347387D01*
X30197Y347439D01*
X30580Y347336D01*
X30848Y347077D01*
X30925Y346767D01*
X30887Y346457D01*
X30733Y346199D01*
X29967Y345682D01*
X29622Y345321D01*
X29392Y344804D01*
X29315Y344339D01*
X30925D01*
G01X33220D02*
X33488Y344391D01*
X33795Y344546D01*
X33987Y344804D01*
X34063Y345166D01*
X33987Y345527D01*
X33757Y345837D01*
X33412Y345992D01*
X33028D01*
X32798Y346096D01*
X32607Y346354D01*
X32530Y346716D01*
X32645Y347077D01*
X32913Y347336D01*
X33220Y347439D01*
X33527Y347336D01*
X33795Y347077D01*
X33910Y346716D01*
X33833Y346354D01*
X33642Y346096D01*
X33412Y345992D01*
X33028D01*
X32683Y345837D01*
X32453Y345527D01*
X32377Y345166D01*
X32453Y344804D01*
X32645Y344546D01*
X32952Y344391D01*
X33220Y344339D01*
G01X23640Y385229D02*
X33440D01*
G01X23640Y397029D02*
Y385229D01*
G01X21990Y400556D02*
Y401951D01*
X21223Y403656D01*
G01X22757D02*
X21990Y401951D01*
G01X25550Y400556D02*
Y403656D01*
X24132Y401434D01*
X26048D01*
G01X33440Y397029D02*
X23640D01*
G01X16635Y650780D02*
Y653880D01*
G01X18245D02*
Y650780D01*
G01Y652330D02*
X16635D01*
G01X20540Y650780D02*
Y653880D01*
X20080Y653260D01*
G01Y650780D02*
X21000D01*
G01X22912Y653363D02*
X23142Y653673D01*
X23410Y653828D01*
X23717Y653880D01*
X24100Y653777D01*
X24368Y653518D01*
X24445Y653208D01*
X24407Y652898D01*
X24253Y652640D01*
X23487Y652123D01*
X23142Y651762D01*
X22912Y651245D01*
X22835Y650780D01*
X24445D01*
G01X26740D02*
X27008Y650832D01*
X27315Y650987D01*
X27507Y651245D01*
X27583Y651607D01*
X27507Y651968D01*
X27277Y652278D01*
X26932Y652433D01*
X26548D01*
X26318Y652537D01*
X26127Y652795D01*
X26050Y653157D01*
X26165Y653518D01*
X26433Y653777D01*
X26740Y653880D01*
X27047Y653777D01*
X27315Y653518D01*
X27430Y653157D01*
X27353Y652795D01*
X27162Y652537D01*
X26932Y652433D01*
X26548D01*
X26203Y652278D01*
X25973Y651968D01*
X25897Y651607D01*
X25973Y651245D01*
X26165Y650987D01*
X26472Y650832D01*
X26740Y650780D01*
G01X27325Y697211D02*
X52915D01*
G01X27325Y1335007D02*
Y697211D01*
G01X52915Y732644D02*
X27325D01*
G01X52915Y1299574D02*
X27325D01*
G01X18083Y1332186D02*
X18275Y1331876D01*
X18505Y1331669D01*
X18773Y1331566D01*
X19080Y1331669D01*
X19310Y1331876D01*
X19540Y1332186D01*
X19617Y1332599D01*
Y1334666D01*
G01X21222Y1334149D02*
X21452Y1334459D01*
X21720Y1334614D01*
X22027Y1334666D01*
X22410Y1334563D01*
X22678Y1334304D01*
X22755Y1333994D01*
X22717Y1333684D01*
X22563Y1333426D01*
X21797Y1332909D01*
X21452Y1332548D01*
X21222Y1332031D01*
X21145Y1331566D01*
X22755D01*
G01X24207Y1332186D02*
X24437Y1331824D01*
X24743Y1331618D01*
X25088Y1331566D01*
X25395Y1331618D01*
X25702Y1331876D01*
X25893Y1332186D01*
X25932Y1332496D01*
X25855Y1332858D01*
X25587Y1333116D01*
X25318Y1333219D01*
X24973D01*
G01X25318D02*
X25548Y1333374D01*
X25740Y1333633D01*
X25817Y1333943D01*
X25740Y1334253D01*
X25548Y1334511D01*
X25203Y1334666D01*
X24858Y1334614D01*
X24513Y1334408D01*
G01X52915Y1335007D02*
X27325D01*
G01X17645Y1386360D02*
Y1389460D01*
G01X19255D02*
Y1386360D01*
G01Y1387910D02*
X17645D01*
G01X20898Y1386722D02*
X21167Y1386463D01*
X21473Y1386360D01*
X21780Y1386463D01*
X22048Y1386773D01*
X22240Y1387238D01*
X22317Y1387703D01*
Y1388272D01*
X22240Y1388737D01*
X22048Y1389150D01*
X21818Y1389357D01*
X21550Y1389460D01*
X21243Y1389357D01*
X21013Y1389150D01*
X20860Y1388840D01*
X20783Y1388427D01*
X20860Y1388065D01*
X21052Y1387703D01*
X21282Y1387497D01*
X21550Y1387445D01*
X21857Y1387548D01*
X22087Y1387807D01*
X22317Y1388272D01*
G01X24573Y1386360D02*
X24650Y1387032D01*
X24765Y1387600D01*
X24918Y1388117D01*
X25110Y1388685D01*
X25417Y1389460D01*
X23883D01*
G01X61246Y1420330D02*
G03I-22900J0D01*
G01X34900Y199262D02*
Y202462D01*
G01X41100Y199262D02*
X34900D01*
G01X41100Y202462D02*
Y199262D01*
G01X34900Y191262D02*
Y194462D01*
G01X41100Y191262D02*
X34900D01*
G01X41100Y194462D02*
Y191262D01*
G01X34900Y194462D02*
X41100D01*
G01X34620Y214762D02*
Y217962D01*
G01X40820Y214762D02*
X34620D01*
G01X40820Y217962D02*
Y214762D01*
G01X32320Y217962D02*
Y214762D01*
G01X34620Y206762D02*
Y209962D01*
G01X40820Y206762D02*
X34620D01*
G01X40820Y209962D02*
Y206762D01*
G01X34620Y209962D02*
X40820D01*
G01X34900Y202462D02*
X41100D01*
G01X32320Y233962D02*
Y230762D01*
G01X34620D02*
Y233962D01*
G01X40820Y230762D02*
X34620D01*
G01X40820Y233962D02*
Y230762D01*
G01Y225942D02*
Y222742D01*
G01X34620D02*
Y225942D01*
G01X40820Y222742D02*
X34620D01*
G01Y225942D02*
X40820D01*
G01X34620Y217962D02*
X40820D01*
G01X32320Y225962D02*
Y222762D01*
G01X34620Y233962D02*
X40820D01*
G01X34620Y238762D02*
Y241962D01*
G01X40820Y238762D02*
X34620D01*
G01X40820Y241962D02*
Y238762D01*
G01X34620Y241962D02*
X40820D01*
G01X32320D02*
Y238762D01*
G01X31580Y300872D02*
Y304072D01*
G01X37780Y300872D02*
X31580D01*
G01X37780Y304072D02*
Y300872D01*
G01X31580Y304072D02*
X37780D01*
G01X58730Y337402D02*
G03I-9450J0D01*
G01X45234Y361812D02*
Y368012D01*
G01X48434Y361812D02*
X45234D01*
G01X44409D02*
X41209D01*
G01X44409Y368012D02*
Y361812D01*
G01X41209D02*
Y368012D01*
G01X40608Y361812D02*
X37408D01*
G01X40608Y368012D02*
Y361812D01*
G01X37408D02*
Y368012D01*
G01X38310Y373042D02*
Y375542D01*
X37990Y375042D01*
G01Y373042D02*
X38630D01*
G01X39923Y373417D02*
X40083Y373209D01*
X40270Y373084D01*
X40510Y373042D01*
X40750Y373125D01*
X40937Y373292D01*
X41070Y373584D01*
X41097Y373917D01*
X41043Y374250D01*
X40910Y374459D01*
X40723Y374625D01*
X40537Y374667D01*
X40350Y374625D01*
X40110Y374459D01*
X40190Y375542D01*
X40910D01*
G01X45234Y368012D02*
X48434D01*
G01X41209D02*
X44409D01*
G01X37408D02*
X40608D01*
G01X40440Y383332D02*
Y385832D01*
X40120Y385332D01*
G01Y383332D02*
X40760D01*
G01X42960D02*
Y385832D01*
X41973Y384040D01*
X43307D01*
G01X43590Y397302D02*
X43777Y397344D01*
X43990Y397469D01*
X44123Y397677D01*
X44177Y397969D01*
X44123Y398260D01*
X43963Y398510D01*
X43723Y398635D01*
X43457D01*
X43297Y398719D01*
X43163Y398927D01*
X43110Y399219D01*
X43190Y399510D01*
X43377Y399719D01*
X43590Y399802D01*
X43803Y399719D01*
X43990Y399510D01*
X44070Y399219D01*
X44017Y398927D01*
X43883Y398719D01*
X43723Y398635D01*
X43457D01*
X43217Y398510D01*
X43057Y398260D01*
X43003Y397969D01*
X43057Y397677D01*
X43190Y397469D01*
X43403Y397344D01*
X43590Y397302D01*
G01X43874Y392301D02*
X40874D01*
G01X33440Y385229D02*
Y397029D01*
G01X34995Y389652D02*
X38195D01*
G01X34995Y383452D02*
Y389652D01*
G01X38195Y383452D02*
X34995D01*
G01X38195Y389652D02*
Y383452D01*
G01X38124Y390671D02*
X34924D01*
G01X38124Y396871D02*
Y390671D01*
G01X34924D02*
Y396871D01*
G01X43367Y412185D02*
Y418385D01*
X46567D01*
G01X34924Y396871D02*
X38124D01*
G01X37585Y402600D02*
Y399400D01*
G01X31385Y402600D02*
X37585D01*
G01X31385Y399400D02*
Y402600D01*
G01X37585Y399400D02*
X31385D01*
G01X46567Y415335D02*
X43367D01*
Y421535D01*
G01X43097Y1339660D02*
Y1337438D01*
X43250Y1336973D01*
X43557Y1336663D01*
X43940Y1336560D01*
X44323Y1336663D01*
X44630Y1336973D01*
X44783Y1337438D01*
Y1339660D01*
G01X47040Y1336560D02*
Y1339660D01*
X46580Y1339040D01*
G01Y1336560D02*
X47500D01*
G01X50140Y1339660D02*
X49833Y1339557D01*
X49603Y1339298D01*
X49450Y1338988D01*
X49335Y1338575D01*
X49297Y1338110D01*
X49335Y1337645D01*
X49450Y1337232D01*
X49603Y1336922D01*
X49833Y1336663D01*
X50140Y1336560D01*
X50447Y1336663D01*
X50677Y1336922D01*
X50830Y1337232D01*
X50945Y1337645D01*
X50983Y1338110D01*
X50945Y1338575D01*
X50830Y1338988D01*
X50677Y1339298D01*
X50447Y1339557D01*
X50140Y1339660D01*
G01X52397Y1337180D02*
X52627Y1336818D01*
X52933Y1336612D01*
X53278Y1336560D01*
X53585Y1336612D01*
X53892Y1336870D01*
X54083Y1337180D01*
X54122Y1337490D01*
X54045Y1337852D01*
X53777Y1338110D01*
X53508Y1338213D01*
X53163D01*
G01X53508D02*
X53738Y1338368D01*
X53930Y1338627D01*
X54007Y1338937D01*
X53930Y1339247D01*
X53738Y1339505D01*
X53393Y1339660D01*
X53048Y1339608D01*
X52703Y1339402D01*
G01X30595Y1450562D02*
Y1453662D01*
G01X32205D02*
Y1450562D01*
G01Y1452112D02*
X30595D01*
G01X34500Y1450562D02*
Y1453662D01*
X34040Y1453042D01*
G01Y1450562D02*
X34960D01*
G01X36872Y1453145D02*
X37102Y1453455D01*
X37370Y1453610D01*
X37677Y1453662D01*
X38060Y1453559D01*
X38328Y1453300D01*
X38405Y1452990D01*
X38367Y1452680D01*
X38213Y1452422D01*
X37447Y1451905D01*
X37102Y1451544D01*
X36872Y1451027D01*
X36795Y1450562D01*
X38405D01*
G01X39857Y1451027D02*
X40087Y1450769D01*
X40355Y1450614D01*
X40700Y1450562D01*
X41045Y1450665D01*
X41313Y1450872D01*
X41505Y1451234D01*
X41543Y1451647D01*
X41467Y1452060D01*
X41275Y1452319D01*
X41007Y1452525D01*
X40738Y1452577D01*
X40470Y1452525D01*
X40125Y1452319D01*
X40240Y1453662D01*
X41275D01*
G01X51320Y1511291D02*
G03I-9450J0D01*
G01X31815Y1539002D02*
Y1542102D01*
G01X33425D02*
Y1539002D01*
G01Y1540552D02*
X31815D01*
G01X34877Y1539622D02*
X35107Y1539260D01*
X35413Y1539054D01*
X35758Y1539002D01*
X36065Y1539054D01*
X36372Y1539312D01*
X36563Y1539622D01*
X36602Y1539932D01*
X36525Y1540294D01*
X36257Y1540552D01*
X35988Y1540655D01*
X35643D01*
G01X35988D02*
X36218Y1540810D01*
X36410Y1541069D01*
X36487Y1541379D01*
X36410Y1541689D01*
X36218Y1541947D01*
X35873Y1542102D01*
X35528Y1542050D01*
X35183Y1541844D01*
G01X38820Y1542102D02*
X38513Y1541999D01*
X38283Y1541740D01*
X38130Y1541430D01*
X38015Y1541017D01*
X37977Y1540552D01*
X38015Y1540087D01*
X38130Y1539674D01*
X38283Y1539364D01*
X38513Y1539105D01*
X38820Y1539002D01*
X39127Y1539105D01*
X39357Y1539364D01*
X39510Y1539674D01*
X39625Y1540087D01*
X39663Y1540552D01*
X39625Y1541017D01*
X39510Y1541430D01*
X39357Y1541740D01*
X39127Y1541999D01*
X38820Y1542102D01*
G01X36044Y1649440D02*
Y1647218D01*
X36197Y1646753D01*
X36504Y1646443D01*
X36887Y1646340D01*
X37270Y1646443D01*
X37577Y1646753D01*
X37730Y1647218D01*
Y1649440D01*
G01X39987Y1646340D02*
Y1649440D01*
X39527Y1648820D01*
G01Y1646340D02*
X40447D01*
G01X43087D02*
X43355Y1646392D01*
X43662Y1646547D01*
X43854Y1646805D01*
X43930Y1647167D01*
X43854Y1647528D01*
X43624Y1647838D01*
X43279Y1647993D01*
X42895D01*
X42665Y1648097D01*
X42474Y1648355D01*
X42397Y1648717D01*
X42512Y1649078D01*
X42780Y1649337D01*
X43087Y1649440D01*
X43394Y1649337D01*
X43662Y1649078D01*
X43777Y1648717D01*
X43700Y1648355D01*
X43509Y1648097D01*
X43279Y1647993D01*
X42895D01*
X42550Y1647838D01*
X42320Y1647528D01*
X42244Y1647167D01*
X42320Y1646805D01*
X42512Y1646547D01*
X42819Y1646392D01*
X43087Y1646340D01*
G01X46187D02*
Y1649440D01*
X45727Y1648820D01*
G01Y1646340D02*
X46647D01*
G01X30015Y1733470D02*
Y1736570D01*
G01X31625D02*
Y1733470D01*
G01Y1735020D02*
X30015D01*
G01X33268Y1733832D02*
X33537Y1733573D01*
X33843Y1733470D01*
X34150Y1733573D01*
X34418Y1733883D01*
X34610Y1734348D01*
X34687Y1734813D01*
Y1735382D01*
X34610Y1735847D01*
X34418Y1736260D01*
X34188Y1736467D01*
X33920Y1736570D01*
X33613Y1736467D01*
X33383Y1736260D01*
X33230Y1735950D01*
X33153Y1735537D01*
X33230Y1735175D01*
X33422Y1734813D01*
X33652Y1734607D01*
X33920Y1734555D01*
X34227Y1734658D01*
X34457Y1734917D01*
X34687Y1735382D01*
G01X36292Y1734762D02*
X36560Y1735123D01*
X36790Y1735330D01*
X37097Y1735433D01*
X37365Y1735330D01*
X37557Y1735123D01*
X37710Y1734813D01*
X37748Y1734452D01*
X37710Y1734142D01*
X37557Y1733832D01*
X37327Y1733573D01*
X37058Y1733470D01*
X36752Y1733573D01*
X36483Y1733883D01*
X36330Y1734348D01*
X36292Y1734865D01*
X36368Y1735537D01*
X36483Y1735898D01*
X36675Y1736260D01*
X36943Y1736518D01*
X37212Y1736570D01*
X37480Y1736467D01*
X37672Y1736208D01*
G01X64662Y43779D02*
X53472D01*
Y79D01*
X319772D01*
Y43779D01*
G01X51346Y51142D02*
Y-2520D01*
X321898D01*
Y51142D01*
G01X72535Y51139D02*
X55450D01*
G01X56220Y57217D02*
X53020D01*
G01X56220Y63417D02*
Y57217D01*
G01X53020Y63417D02*
X56220D01*
G01X53020Y57217D02*
Y63417D01*
G01X51908Y57217D02*
X48708D01*
G01X51908Y63417D02*
Y57217D01*
G01X48708Y63417D02*
X51908D01*
G01X48708Y57217D02*
Y63417D01*
G01X58070Y160137D02*
Y166941D01*
G01X82874Y160137D02*
X58070D01*
G01Y171641D02*
Y174815D01*
G01Y179515D02*
Y182689D01*
G01Y187389D02*
Y190563D01*
G01Y195263D02*
Y198437D01*
G01Y203137D02*
Y206311D01*
G01Y211011D02*
Y214185D01*
G01Y218885D02*
Y222059D01*
G01Y226759D02*
Y229933D01*
G01X55555Y251511D02*
X55747Y251201D01*
X55977Y250994D01*
X56245Y250891D01*
X56552Y250994D01*
X56782Y251201D01*
X57012Y251511D01*
X57089Y251924D01*
Y253991D01*
G01X59422Y250891D02*
Y253991D01*
X58962Y253371D01*
G01Y250891D02*
X59882D01*
G01X62522Y253991D02*
X62215Y253888D01*
X61985Y253629D01*
X61832Y253319D01*
X61717Y252906D01*
X61679Y252441D01*
X61717Y251976D01*
X61832Y251563D01*
X61985Y251253D01*
X62215Y250994D01*
X62522Y250891D01*
X62829Y250994D01*
X63059Y251253D01*
X63212Y251563D01*
X63327Y251976D01*
X63365Y252441D01*
X63327Y252906D01*
X63212Y253319D01*
X63059Y253629D01*
X62829Y253888D01*
X62522Y253991D01*
G01X65622D02*
X65315Y253888D01*
X65085Y253629D01*
X64932Y253319D01*
X64817Y252906D01*
X64779Y252441D01*
X64817Y251976D01*
X64932Y251563D01*
X65085Y251253D01*
X65315Y250994D01*
X65622Y250891D01*
X65929Y250994D01*
X66159Y251253D01*
X66312Y251563D01*
X66427Y251976D01*
X66465Y252441D01*
X66427Y252906D01*
X66312Y253319D01*
X66159Y253629D01*
X65929Y253888D01*
X65622Y253991D01*
G01X58070Y234633D02*
Y237807D01*
G01Y242507D02*
Y249311D01*
G01D02*
X82874D01*
G01X54682Y300774D02*
X51680Y297172D01*
G01X56432Y288570D02*
Y300774D01*
G01X46928Y288570D02*
X56432D01*
G01X46928Y300774D02*
Y288570D01*
G01X51680Y297172D02*
X48678Y300774D01*
G01X56432D02*
X54682D01*
G01X48678D02*
X46928D01*
G01X61206Y301326D02*
Y304526D01*
G01X67406Y301326D02*
X61206D01*
G01Y304526D02*
X67406D01*
G01X48434Y368012D02*
Y361812D01*
G01X53590D02*
Y368012D01*
G01X56790Y361812D02*
X53590D01*
G01X56790Y368012D02*
Y361812D01*
G01X60922D02*
X57722D01*
G01X60922Y368012D02*
Y361812D01*
G01X57722D02*
Y368012D01*
G01X52714Y361812D02*
X49514D01*
G01X52714Y368012D02*
Y361812D01*
G01X49514D02*
Y368012D01*
G01X59374Y378801D02*
Y375801D01*
G01X49374Y378801D02*
Y377301D01*
G01X53590Y368012D02*
X56790D01*
G01X57722D02*
X60922D01*
G01X49514D02*
X52714D01*
G01X45531Y380458D02*
Y383301D01*
G01X48374Y380458D02*
X45531D01*
G01X58589Y409245D02*
Y412370D01*
G01X61789Y412395D02*
X58589D01*
G01X48739Y412270D02*
Y415630D01*
G01Y418470D02*
X51939D01*
Y412270D01*
G01X46567Y415350D02*
Y412185D01*
G01X48221Y401568D02*
X48274Y402110D01*
X48354Y402568D01*
X48461Y402985D01*
X48594Y403443D01*
X48807Y404068D01*
X47741D01*
G01X53374Y401801D02*
Y403301D01*
G01X45531Y400144D02*
X48374D01*
G01X45531Y397301D02*
Y400144D01*
G01X57763Y412403D02*
X54563D01*
G01D02*
Y418603D01*
G01X58589Y415445D02*
X61789D01*
G01X58589Y415390D02*
Y418595D01*
G01X51939Y421620D02*
Y415420D01*
X48739D01*
G01Y418530D02*
Y421620D01*
G01X46567Y421535D02*
Y418400D01*
G01X55507Y423346D02*
X58660D01*
G01X55507Y420146D02*
Y423346D01*
G01X58620Y420146D02*
X55507D01*
G01X54563Y418603D02*
X57763D01*
G01D02*
Y415520D01*
G01X57025Y697211D02*
X82615D01*
G01X57025Y1314752D02*
Y697211D01*
G01X52915D02*
Y1335007D01*
G01X82615Y732644D02*
X57025D01*
G01X82615Y1299574D02*
X57025D01*
G01X56545Y1316324D02*
X72235D01*
G01X56545Y1328332D02*
Y1316324D01*
G01X72235Y1328332D02*
X56545D01*
G01X58153Y1337782D02*
X58345Y1337472D01*
X58575Y1337265D01*
X58843Y1337162D01*
X59150Y1337265D01*
X59380Y1337472D01*
X59610Y1337782D01*
X59687Y1338195D01*
Y1340262D01*
G01X61292Y1339745D02*
X61522Y1340055D01*
X61790Y1340210D01*
X62097Y1340262D01*
X62480Y1340159D01*
X62748Y1339900D01*
X62825Y1339590D01*
X62787Y1339280D01*
X62633Y1339022D01*
X61867Y1338505D01*
X61522Y1338144D01*
X61292Y1337627D01*
X61215Y1337162D01*
X62825D01*
G01X65580D02*
Y1340262D01*
X64162Y1338040D01*
X66078D01*
G01X57025Y1335007D02*
Y1329792D01*
G01X75830Y1335007D02*
X57025D01*
G01X57674Y1518494D02*
Y1521694D01*
G01X63874Y1518494D02*
X57674D01*
G01Y1525694D02*
X63874D01*
G01X57674Y1522494D02*
Y1525694D01*
G01X63874Y1522494D02*
X57674D01*
G01Y1521694D02*
X63874D01*
G01X57674Y1533694D02*
X63874D01*
G01X57674Y1530494D02*
Y1533694D01*
G01X63874Y1530494D02*
X57674D01*
G01Y1534494D02*
Y1537694D01*
G01X63874Y1534494D02*
X57674D01*
G01Y1529794D02*
X63874D01*
G01X57674Y1526594D02*
Y1529794D01*
G01X63874Y1526594D02*
X57674D01*
G01Y1549694D02*
X63874D01*
G01X57674Y1546494D02*
Y1549694D01*
G01X63874Y1546494D02*
X57674D01*
G01Y1538494D02*
Y1541694D01*
G01X63874Y1538494D02*
X57674D01*
G01Y1541694D02*
X63874D01*
G01X57674Y1550494D02*
Y1553694D01*
G01X63874Y1550494D02*
X57674D01*
G01Y1545694D02*
X63874D01*
G01X57674Y1542494D02*
Y1545694D01*
G01X63874Y1542494D02*
X57674D01*
G01Y1537694D02*
X63874D01*
G01X57674Y1557694D02*
X63874D01*
G01X57674Y1554494D02*
Y1557694D01*
G01X63874Y1554494D02*
X57674D01*
G01Y1553694D02*
X63874D01*
G01X57674Y1558494D02*
Y1561694D01*
G01X63874Y1558494D02*
X57674D01*
G01Y1561694D02*
X63874D01*
G01X61433Y1614234D02*
X58233D01*
G01X61433Y1620434D02*
Y1614234D01*
G01X58233D02*
Y1620434D01*
G01X61433Y1605234D02*
X58233D01*
G01X61433Y1611434D02*
Y1605234D01*
G01X58233Y1611434D02*
X61433D01*
G01X58233Y1605234D02*
Y1611434D01*
G01X52733D02*
X55933D01*
G01X52733Y1605234D02*
Y1611434D01*
G01X55933Y1605234D02*
X52733D01*
G01X55933Y1611434D02*
Y1605234D01*
G01X51933Y1614234D02*
X48733D01*
G01X51933Y1620434D02*
Y1614234D01*
G01X48733D02*
Y1620434D01*
G01X55933Y1614234D02*
X52733D01*
G01X55933Y1620434D02*
Y1614234D01*
G01X52733D02*
Y1620434D01*
G01X58233D02*
X61433D01*
G01X48733D02*
X51933D01*
G01X52733D02*
X55933D01*
G01X52618Y1648080D02*
X58169Y1642529D01*
G01X52618Y1650787D02*
Y1648080D01*
G01Y1634271D02*
X83720D01*
G01X52618Y1636978D02*
Y1634271D01*
G01X58169Y1642529D02*
X52618Y1636978D01*
G01X83720Y1650787D02*
X52618D01*
G01X48933Y1655234D02*
X45733D01*
G01X48933Y1661434D02*
Y1655234D01*
G01X45733Y1661434D02*
X48933D01*
G01X45733Y1655234D02*
Y1661434D01*
G01X56233Y1664734D02*
Y1670934D01*
G01X59433Y1664734D02*
X56233D01*
G01X59433Y1670934D02*
Y1664734D01*
G01X51733D02*
Y1670934D01*
G01X54933Y1664734D02*
X51733D01*
G01X54933Y1670934D02*
Y1664734D01*
G01X47733D02*
Y1670934D01*
G01X50933Y1664734D02*
X47733D01*
G01X50933Y1670934D02*
Y1664734D01*
G01X55300Y1673100D02*
X52100D01*
G01X55300Y1679300D02*
Y1673100D01*
G01X52100Y1679300D02*
X55300D01*
G01X52100Y1673100D02*
Y1679300D01*
G01X56233Y1670934D02*
X59433D01*
G01X51733D02*
X54933D01*
G01X47733D02*
X50933D01*
G01X62600Y1680800D02*
Y1674600D01*
X59400D01*
Y1680800D01*
X62600D01*
G01X80609Y51139D02*
X76588D01*
G01X71846Y80676D02*
Y83776D01*
X73610Y80676D01*
Y83776D01*
G01X75368D02*
X76288D01*
G01X75828D02*
Y80676D01*
G01X75368D02*
X76288D01*
G01X79771Y83518D02*
X79541Y83673D01*
X79273Y83776D01*
X78966D01*
X78621Y83621D01*
X78353Y83363D01*
X78161Y83053D01*
X78008Y82536D01*
X77970Y82071D01*
X78046Y81606D01*
X78161Y81296D01*
X78391Y80986D01*
X78660Y80779D01*
X78928Y80676D01*
X79196D01*
X79465Y80779D01*
X79695Y80934D01*
X79886Y81141D01*
G01X82028Y80676D02*
Y83776D01*
X81568Y83156D01*
G01Y80676D02*
X82488D01*
G01X71879Y87485D02*
X72071Y87175D01*
X72301Y86968D01*
X72569Y86865D01*
X72876Y86968D01*
X73106Y87175D01*
X73336Y87485D01*
X73413Y87898D01*
Y89965D01*
G01X74903Y87485D02*
X75133Y87123D01*
X75439Y86917D01*
X75784Y86865D01*
X76091Y86917D01*
X76398Y87175D01*
X76589Y87485D01*
X76628Y87795D01*
X76551Y88157D01*
X76283Y88415D01*
X76014Y88518D01*
X75669D01*
G01X76014D02*
X76244Y88673D01*
X76436Y88932D01*
X76513Y89242D01*
X76436Y89552D01*
X76244Y89810D01*
X75899Y89965D01*
X75554Y89913D01*
X75209Y89707D01*
G01X78003Y87330D02*
X78233Y87072D01*
X78501Y86917D01*
X78846Y86865D01*
X79191Y86968D01*
X79459Y87175D01*
X79651Y87537D01*
X79689Y87950D01*
X79613Y88363D01*
X79421Y88622D01*
X79153Y88828D01*
X78884Y88880D01*
X78616Y88828D01*
X78271Y88622D01*
X78386Y89965D01*
X79421D01*
G01X69671Y251216D02*
Y254316D01*
X70668Y251733D01*
X71665Y254316D01*
Y251216D01*
G01X74535D02*
X73001D01*
Y254316D01*
X74535D01*
G01X73921Y252818D02*
X73001D01*
G01X79086Y251216D02*
Y254316D01*
X80850Y251216D01*
Y254316D01*
G01X83068Y251216D02*
X82761Y251268D01*
X82493Y251474D01*
X82263Y251784D01*
X82110Y252146D01*
X82033Y252559D01*
Y252973D01*
X82110Y253386D01*
X82263Y253748D01*
X82493Y254058D01*
X82761Y254264D01*
X83068Y254316D01*
X83375Y254264D01*
X83643Y254058D01*
X83873Y253748D01*
X84026Y253386D01*
X84103Y252973D01*
Y252559D01*
X84026Y252146D01*
X83873Y251784D01*
X83643Y251474D01*
X83375Y251268D01*
X83068Y251216D01*
G01X85325D02*
Y254316D01*
X86091D01*
X86398Y254161D01*
X86628Y253954D01*
X86820Y253644D01*
X86973Y253283D01*
X87011Y252766D01*
X86973Y252249D01*
X86820Y251888D01*
X86628Y251578D01*
X86398Y251371D01*
X86091Y251216D01*
X85325D01*
G01X90035D02*
X88501D01*
Y254316D01*
X90035D01*
G01X89421Y252818D02*
X88501D01*
G01X94471Y251216D02*
Y254316D01*
X95468Y251733D01*
X96465Y254316D01*
Y251216D01*
G01X97686D02*
Y254316D01*
X99450Y251216D01*
Y254316D01*
G01X101898Y252766D02*
X102665D01*
Y251836D01*
X102435Y251526D01*
X102166Y251319D01*
X101783Y251216D01*
X101400Y251319D01*
X101131Y251526D01*
X100901Y251836D01*
X100748Y252198D01*
X100671Y252611D01*
Y252973D01*
X100748Y253283D01*
X100901Y253644D01*
X101131Y253954D01*
X101361Y254161D01*
X101668Y254316D01*
X101936D01*
X102243Y254213D01*
X102473Y254006D01*
G01X62597Y292439D02*
Y290217D01*
X62750Y289752D01*
X63057Y289442D01*
X63440Y289339D01*
X63823Y289442D01*
X64130Y289752D01*
X64283Y290217D01*
Y292439D01*
G01X65812Y291922D02*
X66042Y292232D01*
X66310Y292387D01*
X66617Y292439D01*
X67000Y292336D01*
X67268Y292077D01*
X67345Y291767D01*
X67307Y291457D01*
X67153Y291199D01*
X66387Y290682D01*
X66042Y290321D01*
X65812Y289804D01*
X65735Y289339D01*
X67345D01*
G01X70100D02*
Y292439D01*
X68682Y290217D01*
X70598D01*
G01X72012Y291922D02*
X72242Y292232D01*
X72510Y292387D01*
X72817Y292439D01*
X73200Y292336D01*
X73468Y292077D01*
X73545Y291767D01*
X73507Y291457D01*
X73353Y291199D01*
X72587Y290682D01*
X72242Y290321D01*
X72012Y289804D01*
X71935Y289339D01*
X73545D01*
G01X67406Y304526D02*
Y301326D01*
G01X65029Y361812D02*
X61829D01*
G01X65029Y368012D02*
Y361812D01*
G01X61829D02*
Y368012D01*
G01X69281Y361812D02*
X66081D01*
G01X69281Y368012D02*
Y361812D01*
G01X66081D02*
Y368012D01*
G01X71843Y378205D02*
X72003Y378455D01*
X72190Y378580D01*
X72403Y378622D01*
X72670Y378539D01*
X72857Y378330D01*
X72910Y378080D01*
X72883Y377830D01*
X72777Y377622D01*
X72243Y377205D01*
X72003Y376914D01*
X71843Y376497D01*
X71790Y376122D01*
X72910D01*
G01X74043Y378205D02*
X74203Y378455D01*
X74390Y378580D01*
X74603Y378622D01*
X74870Y378539D01*
X75057Y378330D01*
X75110Y378080D01*
X75083Y377830D01*
X74977Y377622D01*
X74443Y377205D01*
X74203Y376914D01*
X74043Y376497D01*
X73990Y376122D01*
X75110D01*
G01X69413Y373315D02*
X69573Y373565D01*
X69760Y373690D01*
X69973Y373732D01*
X70240Y373649D01*
X70427Y373440D01*
X70480Y373190D01*
X70453Y372940D01*
X70347Y372732D01*
X69813Y372315D01*
X69573Y372024D01*
X69413Y371607D01*
X69360Y371232D01*
X70480D01*
G01X72120D02*
Y373732D01*
X71800Y373232D01*
G01Y371232D02*
X72440D01*
G01X61829Y368012D02*
X65029D01*
G01X66081D02*
X69281D01*
G01X67433Y396395D02*
X67593Y396645D01*
X67780Y396770D01*
X67993Y396812D01*
X68260Y396729D01*
X68447Y396520D01*
X68500Y396270D01*
X68473Y396020D01*
X68367Y395812D01*
X67833Y395395D01*
X67593Y395104D01*
X67433Y394687D01*
X67380Y394312D01*
X68500D01*
G01X70140D02*
X70327Y394354D01*
X70540Y394479D01*
X70673Y394687D01*
X70727Y394979D01*
X70673Y395270D01*
X70513Y395520D01*
X70273Y395645D01*
X70007D01*
X69847Y395729D01*
X69713Y395937D01*
X69660Y396229D01*
X69740Y396520D01*
X69927Y396729D01*
X70140Y396812D01*
X70353Y396729D01*
X70540Y396520D01*
X70620Y396229D01*
X70567Y395937D01*
X70433Y395729D01*
X70273Y395645D01*
X70007D01*
X69767Y395520D01*
X69607Y395270D01*
X69553Y394979D01*
X69607Y394687D01*
X69740Y394479D01*
X69953Y394354D01*
X70140Y394312D01*
G01X66874Y390301D02*
X68374D01*
G01X65217Y380458D02*
X62374D01*
G01X65217Y383301D02*
Y380458D01*
G01X63933Y409365D02*
Y412470D01*
G01X67133Y412540D02*
Y409365D01*
G01X61789Y412290D02*
Y409245D01*
G01X67133Y412515D02*
X63933D01*
G01X69518Y405083D02*
Y402861D01*
X69671Y402396D01*
X69978Y402086D01*
X70361Y401983D01*
X70744Y402086D01*
X71051Y402396D01*
X71204Y402861D01*
Y405083D01*
G01X72733Y404566D02*
X72963Y404876D01*
X73231Y405031D01*
X73538Y405083D01*
X73921Y404980D01*
X74189Y404721D01*
X74266Y404411D01*
X74228Y404101D01*
X74074Y403843D01*
X73308Y403326D01*
X72963Y402965D01*
X72733Y402448D01*
X72656Y401983D01*
X74266D01*
G01X75833Y403275D02*
X76101Y403636D01*
X76331Y403843D01*
X76638Y403946D01*
X76906Y403843D01*
X77098Y403636D01*
X77251Y403326D01*
X77289Y402965D01*
X77251Y402655D01*
X77098Y402345D01*
X76868Y402086D01*
X76599Y401983D01*
X76293Y402086D01*
X76024Y402396D01*
X75871Y402861D01*
X75833Y403378D01*
X75909Y404050D01*
X76024Y404411D01*
X76216Y404773D01*
X76484Y405031D01*
X76753Y405083D01*
X77021Y404980D01*
X77213Y404721D01*
G01X79661Y401983D02*
X79929Y402035D01*
X80236Y402190D01*
X80428Y402448D01*
X80504Y402810D01*
X80428Y403171D01*
X80198Y403481D01*
X79853Y403636D01*
X79469D01*
X79239Y403740D01*
X79048Y403998D01*
X78971Y404360D01*
X79086Y404721D01*
X79354Y404980D01*
X79661Y405083D01*
X79968Y404980D01*
X80236Y404721D01*
X80351Y404360D01*
X80274Y403998D01*
X80083Y403740D01*
X79853Y403636D01*
X79469D01*
X79124Y403481D01*
X78894Y403171D01*
X78818Y402810D01*
X78894Y402448D01*
X79086Y402190D01*
X79393Y402035D01*
X79661Y401983D01*
G01X62374Y400144D02*
X65217D01*
G01D02*
Y397301D01*
G01X71123Y412403D02*
X67923D01*
G01X71123Y418603D02*
Y412403D01*
G01X63933Y415565D02*
X67133D01*
G01Y418715D02*
Y415500D01*
G01X63933Y415550D02*
Y418715D01*
G01X61789Y418595D02*
Y415500D01*
G01X70208Y420146D02*
X67220D01*
G01X70208Y423346D02*
Y420146D01*
G01X67170Y423346D02*
X70208D01*
G01X67923Y418603D02*
X71123D01*
G01X67923Y415400D02*
Y418603D01*
G01X76391Y422719D02*
Y425919D01*
G01X82591Y422719D02*
X76391D01*
G01Y425919D02*
X82591D01*
G01X76391Y418719D02*
Y421919D01*
G01X82591Y418719D02*
X76391D01*
G01Y421919D02*
X82591D01*
G01X73796Y439883D02*
Y444483D01*
G01D02*
X83796D01*
G01X73796Y444383D02*
Y444483D01*
G01X83796Y439883D02*
X73796D01*
G01X76391Y438119D02*
X82591D01*
G01X76391Y434919D02*
Y438119D01*
G01X82591Y434919D02*
X76391D01*
G01Y434119D02*
X82591D01*
G01X76391Y430919D02*
Y434119D01*
G01X82591Y430919D02*
X76391D01*
G01X78097Y602340D02*
Y605440D01*
G01X79707D02*
Y602340D01*
G01Y603890D02*
X78097D01*
G01X82002Y602340D02*
Y605440D01*
X81542Y604820D01*
G01Y602340D02*
X82462D01*
G01X84374Y604923D02*
X84604Y605233D01*
X84872Y605388D01*
X85179Y605440D01*
X85562Y605337D01*
X85830Y605078D01*
X85907Y604768D01*
X85869Y604458D01*
X85715Y604200D01*
X84949Y603683D01*
X84604Y603322D01*
X84374Y602805D01*
X84297Y602340D01*
X85907D01*
G01X87474Y603632D02*
X87742Y603993D01*
X87972Y604200D01*
X88279Y604303D01*
X88547Y604200D01*
X88739Y603993D01*
X88892Y603683D01*
X88930Y603322D01*
X88892Y603012D01*
X88739Y602702D01*
X88509Y602443D01*
X88240Y602340D01*
X87934Y602443D01*
X87665Y602753D01*
X87512Y603218D01*
X87474Y603735D01*
X87550Y604407D01*
X87665Y604768D01*
X87857Y605130D01*
X88125Y605388D01*
X88394Y605440D01*
X88662Y605337D01*
X88854Y605078D01*
G01X77303Y621592D02*
Y624692D01*
X78223D01*
X78530Y624537D01*
X78760Y624175D01*
X78837Y623762D01*
X78760Y623349D01*
X78568Y623039D01*
X78223Y622884D01*
X77303D01*
G01X80403Y622212D02*
X80595Y621902D01*
X80825Y621695D01*
X81093Y621592D01*
X81400Y621695D01*
X81630Y621902D01*
X81860Y622212D01*
X81937Y622625D01*
Y624692D01*
G01X84730Y621592D02*
Y624692D01*
X83312Y622470D01*
X85228D01*
G01X87370Y621592D02*
X87638Y621644D01*
X87945Y621799D01*
X88137Y622057D01*
X88213Y622419D01*
X88137Y622780D01*
X87907Y623090D01*
X87562Y623245D01*
X87178D01*
X86948Y623349D01*
X86757Y623607D01*
X86680Y623969D01*
X86795Y624330D01*
X87063Y624589D01*
X87370Y624692D01*
X87677Y624589D01*
X87945Y624330D01*
X88060Y623969D01*
X87983Y623607D01*
X87792Y623349D01*
X87562Y623245D01*
X87178D01*
X86833Y623090D01*
X86603Y622780D01*
X86527Y622419D01*
X86603Y622057D01*
X86795Y621799D01*
X87102Y621644D01*
X87370Y621592D01*
G01X79188Y655052D02*
X75988D01*
G01D02*
Y661252D01*
G01X76090Y646974D02*
Y650174D01*
G01X82290Y646974D02*
X76090D01*
G01Y650174D02*
X82290D01*
G01X76090Y642964D02*
Y646164D01*
G01X82290Y642964D02*
X76090D01*
G01Y646164D02*
X82290D01*
G01X76090Y650964D02*
Y654164D01*
G01X82290Y650964D02*
X76090D01*
G01Y654164D02*
X82290D01*
G01X75988Y661252D02*
X79188D01*
G01X73748Y679214D02*
Y682314D01*
X74668D01*
X74975Y682159D01*
X75205Y681797D01*
X75282Y681384D01*
X75205Y680971D01*
X75013Y680661D01*
X74668Y680506D01*
X73748D01*
G01X76772Y682314D02*
Y680092D01*
X76925Y679627D01*
X77232Y679317D01*
X77615Y679214D01*
X77998Y679317D01*
X78305Y679627D01*
X78458Y680092D01*
Y682314D01*
G01X80715Y679214D02*
X80983Y679266D01*
X81290Y679421D01*
X81482Y679679D01*
X81558Y680041D01*
X81482Y680402D01*
X81252Y680712D01*
X80907Y680867D01*
X80523D01*
X80293Y680971D01*
X80102Y681229D01*
X80025Y681591D01*
X80140Y681952D01*
X80408Y682211D01*
X80715Y682314D01*
X81022Y682211D01*
X81290Y681952D01*
X81405Y681591D01*
X81328Y681229D01*
X81137Y680971D01*
X80907Y680867D01*
X80523D01*
X80178Y680712D01*
X79948Y680402D01*
X79872Y680041D01*
X79948Y679679D01*
X80140Y679421D01*
X80447Y679266D01*
X80715Y679214D01*
G01X83087Y681797D02*
X83317Y682107D01*
X83585Y682262D01*
X83892Y682314D01*
X84275Y682211D01*
X84543Y681952D01*
X84620Y681642D01*
X84582Y681332D01*
X84428Y681074D01*
X83662Y680557D01*
X83317Y680196D01*
X83087Y679679D01*
X83010Y679214D01*
X84620D01*
G01X65365Y704719D02*
Y716719D01*
G01X71365Y704719D02*
X65365D01*
G01X71365Y716719D02*
Y704719D01*
G01X73265D02*
Y716719D01*
G01X79265Y704719D02*
X73265D01*
G01X65365Y716719D02*
X71365D01*
G01X73265D02*
X79265D01*
G01X77530Y1306561D02*
Y1338361D01*
G01X91330Y1306561D02*
X77530D01*
G01X72235Y1316324D02*
Y1328332D01*
G01X77530Y1338361D02*
X91330D01*
G01X73600Y1355862D02*
Y1357262D01*
G01Y1355862D02*
X147200D01*
Y1357262D01*
G01X78140Y1371339D02*
X77825Y1371652D01*
X77300Y1371887D01*
X76565Y1372044D01*
X75935Y1371887D01*
X75515Y1371574D01*
X75200Y1371025D01*
Y1368910D01*
X81500D01*
Y1371495D01*
X81080Y1372044D01*
X80450Y1372357D01*
X79715Y1372514D01*
X78980Y1372357D01*
X78350Y1371887D01*
X78140Y1371339D01*
Y1368910D01*
G01X80240Y1375289D02*
X80975Y1375759D01*
X81395Y1376385D01*
X81500Y1377090D01*
X81395Y1377717D01*
X80870Y1378344D01*
X80240Y1378735D01*
X79610Y1378814D01*
X78875Y1378657D01*
X78350Y1378109D01*
X78140Y1377560D01*
Y1376855D01*
G01Y1377560D02*
X77825Y1378030D01*
X77300Y1378422D01*
X76670Y1378579D01*
X76040Y1378422D01*
X75515Y1378030D01*
X75200Y1377325D01*
X75305Y1376620D01*
X75725Y1375915D01*
G01X73600Y1380462D02*
X82800D01*
Y1366962D01*
X73600D01*
Y1380462D01*
G01Y1357262D02*
Y1366962D01*
G01X73985Y1516056D02*
Y1522256D01*
G01X77185Y1516056D02*
X73985D01*
G01Y1512906D02*
Y1519106D01*
X77185D01*
G01Y1515890D02*
Y1512906D01*
G01X62309Y1516035D02*
Y1513813D01*
X62462Y1513348D01*
X62769Y1513038D01*
X63152Y1512935D01*
X63535Y1513038D01*
X63842Y1513348D01*
X63995Y1513813D01*
Y1516035D01*
G01X65524Y1515518D02*
X65754Y1515828D01*
X66022Y1515983D01*
X66329Y1516035D01*
X66712Y1515932D01*
X66980Y1515673D01*
X67057Y1515363D01*
X67019Y1515053D01*
X66865Y1514795D01*
X66099Y1514278D01*
X65754Y1513917D01*
X65524Y1513400D01*
X65447Y1512935D01*
X67057D01*
G01X68509Y1513555D02*
X68739Y1513193D01*
X69045Y1512987D01*
X69390Y1512935D01*
X69697Y1512987D01*
X70004Y1513245D01*
X70195Y1513555D01*
X70234Y1513865D01*
X70157Y1514227D01*
X69889Y1514485D01*
X69620Y1514588D01*
X69275D01*
G01X69620D02*
X69850Y1514743D01*
X70042Y1515002D01*
X70119Y1515312D01*
X70042Y1515622D01*
X69850Y1515880D01*
X69505Y1516035D01*
X69160Y1515983D01*
X68815Y1515777D01*
G01X72375Y1512935D02*
X72452Y1513607D01*
X72567Y1514175D01*
X72720Y1514692D01*
X72912Y1515260D01*
X73219Y1516035D01*
X71685D01*
G01X63874Y1521694D02*
Y1518494D01*
G01X77185Y1522256D02*
Y1519150D01*
G01X74635Y1526765D02*
X74795Y1526473D01*
X75009Y1526307D01*
X75249Y1526265D01*
X75462Y1526307D01*
X75675Y1526515D01*
X75809Y1526765D01*
X75835Y1527015D01*
X75782Y1527307D01*
X75595Y1527515D01*
X75409Y1527598D01*
X75169D01*
G01X75409D02*
X75569Y1527723D01*
X75702Y1527932D01*
X75755Y1528182D01*
X75702Y1528432D01*
X75569Y1528640D01*
X75329Y1528765D01*
X75089Y1528723D01*
X74849Y1528557D01*
G01X77422Y1528765D02*
X77209Y1528682D01*
X77049Y1528473D01*
X76942Y1528223D01*
X76862Y1527890D01*
X76835Y1527515D01*
X76862Y1527140D01*
X76942Y1526807D01*
X77049Y1526557D01*
X77209Y1526348D01*
X77422Y1526265D01*
X77635Y1526348D01*
X77795Y1526557D01*
X77902Y1526807D01*
X77982Y1527140D01*
X78009Y1527515D01*
X77982Y1527890D01*
X77902Y1528223D01*
X77795Y1528473D01*
X77635Y1528682D01*
X77422Y1528765D01*
G01X75674Y1534894D02*
X72474D01*
G01X77219Y1534094D02*
Y1532976D01*
X78337D01*
G01X63874Y1525694D02*
Y1522494D01*
G01Y1533694D02*
Y1530494D01*
G01Y1537694D02*
Y1534494D01*
G01Y1529794D02*
Y1526594D01*
G01X72167Y1554294D02*
X72327Y1554544D01*
X72514Y1554669D01*
X72727Y1554711D01*
X72994Y1554628D01*
X73181Y1554419D01*
X73234Y1554169D01*
X73207Y1553919D01*
X73101Y1553711D01*
X72567Y1553294D01*
X72327Y1553003D01*
X72167Y1552586D01*
X72114Y1552211D01*
X73234D01*
G01X74287Y1552586D02*
X74447Y1552378D01*
X74634Y1552253D01*
X74874Y1552211D01*
X75114Y1552294D01*
X75301Y1552461D01*
X75434Y1552753D01*
X75461Y1553086D01*
X75407Y1553419D01*
X75274Y1553628D01*
X75087Y1553794D01*
X74901Y1553836D01*
X74714Y1553794D01*
X74474Y1553628D01*
X74554Y1554711D01*
X75274D01*
G01X66453Y1551215D02*
X66613Y1551465D01*
X66800Y1551590D01*
X67013Y1551632D01*
X67280Y1551549D01*
X67467Y1551340D01*
X67520Y1551090D01*
X67493Y1550840D01*
X67387Y1550632D01*
X66853Y1550215D01*
X66613Y1549924D01*
X66453Y1549507D01*
X66400Y1549132D01*
X67520D01*
G01X68653Y1550174D02*
X68840Y1550465D01*
X69000Y1550632D01*
X69213Y1550715D01*
X69400Y1550632D01*
X69533Y1550465D01*
X69640Y1550215D01*
X69667Y1549924D01*
X69640Y1549674D01*
X69533Y1549424D01*
X69373Y1549215D01*
X69187Y1549132D01*
X68973Y1549215D01*
X68787Y1549465D01*
X68680Y1549840D01*
X68653Y1550257D01*
X68707Y1550799D01*
X68787Y1551090D01*
X68920Y1551382D01*
X69107Y1551590D01*
X69293Y1551632D01*
X69480Y1551549D01*
X69613Y1551340D01*
G01X78337Y1543212D02*
X77219D01*
G01D02*
Y1542094D01*
G01X73674Y1551194D02*
X76874D01*
G01Y1544994D02*
X73674D01*
G01X76874Y1551194D02*
Y1544994D01*
G01X73674D02*
Y1551194D01*
G01X63874Y1549694D02*
Y1546494D01*
G01Y1541694D02*
Y1538494D01*
G01Y1553694D02*
Y1550494D01*
G01Y1545694D02*
Y1542494D01*
G01Y1557694D02*
Y1554494D01*
G01Y1561694D02*
Y1558494D01*
G01X76856Y1556002D02*
Y1559030D01*
G01Y1562202D02*
X80056D01*
Y1556002D01*
G01Y1565352D02*
Y1559152D01*
X76856D01*
G01Y1562170D02*
Y1565352D01*
G01X74989Y1565347D02*
Y1562240D01*
G01Y1559147D02*
X71789D01*
Y1565347D01*
G01Y1555997D02*
Y1562197D01*
X74989D01*
G01Y1559110D02*
Y1555997D01*
G01X68733Y1614234D02*
Y1620434D01*
G01X71933Y1614234D02*
X68733D01*
G01X71933Y1620434D02*
Y1614234D01*
G01X72501Y1614200D02*
Y1620400D01*
X75699D01*
Y1614200D01*
X72501D01*
G01X76400D02*
Y1620400D01*
X79600D01*
Y1614200D01*
X76400D01*
G01X68733Y1620434D02*
X71933D01*
G01X68233Y1664734D02*
Y1670934D01*
G01X71433Y1664734D02*
X68233D01*
G01X71433Y1670934D02*
Y1664734D01*
G01X72233D02*
Y1670934D01*
G01X75433Y1664734D02*
X72233D01*
G01X75433Y1670934D02*
Y1664734D01*
G01X76233D02*
Y1670934D01*
G01X79433Y1664734D02*
X76233D01*
G01X68233Y1670934D02*
X71433D01*
G01X72233D02*
X75433D01*
G01X76233D02*
X79433D01*
G01X66600Y1680800D02*
Y1674600D01*
X63400D01*
Y1680800D01*
X66600D01*
G01X75433Y1682134D02*
X72233D01*
G01X75433Y1688334D02*
Y1682134D01*
G01X72233Y1688334D02*
X75433D01*
G01X72233Y1682134D02*
Y1688334D01*
G01X79433Y1682034D02*
X76233D01*
G01Y1688234D02*
X79433D01*
G01X76233Y1682034D02*
Y1688234D01*
G01X71433Y1682034D02*
X68233D01*
G01X71433Y1688234D02*
Y1682034D01*
G01X68233Y1688234D02*
X71433D01*
G01X68233Y1682034D02*
Y1688234D01*
G01X96290Y51139D02*
X92100D01*
G01X89310D02*
X84757D01*
G01X82874Y166941D02*
Y160137D01*
G01Y174815D02*
Y171641D01*
G01Y182689D02*
Y179515D01*
G01Y190563D02*
Y187389D01*
G01Y198437D02*
Y195263D01*
G01Y206311D02*
Y203137D01*
G01Y214185D02*
Y211011D01*
G01Y222059D02*
Y218885D01*
G01Y229933D02*
Y226759D01*
G01Y237807D02*
Y234633D01*
G01Y249311D02*
Y242507D01*
G01X91700Y278431D02*
X102580D01*
G01X91700Y287093D02*
Y278431D01*
G01X78040Y277198D02*
Y280398D01*
G01X84240Y277198D02*
X78040D01*
G01X84240Y280398D02*
Y277198D01*
G01X78040Y280398D02*
X84240D01*
G01X91647Y291429D02*
Y289207D01*
X91800Y288742D01*
X92107Y288432D01*
X92490Y288329D01*
X92873Y288432D01*
X93180Y288742D01*
X93333Y289207D01*
Y291429D01*
G01X94747Y288794D02*
X94977Y288536D01*
X95245Y288381D01*
X95590Y288329D01*
X95935Y288432D01*
X96203Y288639D01*
X96395Y289001D01*
X96433Y289414D01*
X96357Y289827D01*
X96165Y290086D01*
X95897Y290292D01*
X95628Y290344D01*
X95360Y290292D01*
X95015Y290086D01*
X95130Y291429D01*
X96165D01*
G01X98038Y288691D02*
X98307Y288432D01*
X98613Y288329D01*
X98920Y288432D01*
X99188Y288742D01*
X99380Y289207D01*
X99457Y289672D01*
Y290241D01*
X99380Y290706D01*
X99188Y291119D01*
X98958Y291326D01*
X98690Y291429D01*
X98383Y291326D01*
X98153Y291119D01*
X98000Y290809D01*
X97923Y290396D01*
X98000Y290034D01*
X98192Y289672D01*
X98422Y289466D01*
X98690Y289414D01*
X98997Y289517D01*
X99227Y289776D01*
X99457Y290241D01*
G01X94809Y287093D02*
X91700D01*
G01Y295931D02*
X102580D01*
G01X91700Y304593D02*
Y295931D01*
G01X78040Y294198D02*
Y297398D01*
G01X84240Y294198D02*
X78040D01*
G01X84240Y297398D02*
Y294198D01*
G01X78040Y297398D02*
X84240D01*
G01X78040Y284662D02*
Y287862D01*
G01X84240Y284662D02*
X78040D01*
G01X84240Y287862D02*
Y284662D01*
G01X78040Y287862D02*
X84240D01*
G01X92747Y309922D02*
Y307700D01*
X92900Y307235D01*
X93207Y306925D01*
X93590Y306822D01*
X93973Y306925D01*
X94280Y307235D01*
X94433Y307700D01*
Y309922D01*
G01X95847Y307287D02*
X96077Y307029D01*
X96345Y306874D01*
X96690Y306822D01*
X97035Y306925D01*
X97303Y307132D01*
X97495Y307494D01*
X97533Y307907D01*
X97457Y308320D01*
X97265Y308579D01*
X96997Y308785D01*
X96728Y308837D01*
X96460Y308785D01*
X96115Y308579D01*
X96230Y309922D01*
X97265D01*
G01X99790Y306822D02*
X100058Y306874D01*
X100365Y307029D01*
X100557Y307287D01*
X100633Y307649D01*
X100557Y308010D01*
X100327Y308320D01*
X99982Y308475D01*
X99598D01*
X99368Y308579D01*
X99177Y308837D01*
X99100Y309199D01*
X99215Y309560D01*
X99483Y309819D01*
X99790Y309922D01*
X100097Y309819D01*
X100365Y309560D01*
X100480Y309199D01*
X100403Y308837D01*
X100212Y308579D01*
X99982Y308475D01*
X99598D01*
X99253Y308320D01*
X99023Y308010D01*
X98947Y307649D01*
X99023Y307287D01*
X99215Y307029D01*
X99522Y306874D01*
X99790Y306822D01*
G01X94809Y304593D02*
X91700D01*
G01X78040Y301662D02*
Y304862D01*
G01X84240Y301662D02*
X78040D01*
G01X84240Y304862D02*
Y301662D01*
G01X78040Y304862D02*
X84240D01*
G01X80291Y374426D02*
Y377626D01*
G01X86491Y374426D02*
X80291D01*
G01X86491Y377626D02*
Y374426D01*
G01X80291Y377626D02*
X86491D01*
G01X86474Y392991D02*
Y389791D01*
G01X80274Y392991D02*
X86474D01*
G01X80274Y389791D02*
Y392991D01*
G01X86474Y389791D02*
X80274D01*
G01X86474Y397465D02*
Y394265D01*
G01X80274D02*
Y397465D01*
G01X86474Y394265D02*
X80274D01*
G01X86474Y383819D02*
Y380619D01*
G01X80274Y383819D02*
X86474D01*
G01X80274Y380619D02*
Y383819D01*
G01X86474Y380619D02*
X80274D01*
G01Y384902D02*
Y388102D01*
G01X86474Y384902D02*
X80274D01*
G01X86474Y388102D02*
Y384902D01*
G01X80274Y388102D02*
X86474D01*
G01X80274Y397465D02*
X86474D01*
G01X82591Y425919D02*
Y422719D01*
G01X92901Y429919D02*
Y426719D01*
G01X86701D02*
Y429919D01*
G01X92901Y426719D02*
X86701D01*
G01X92901Y425919D02*
Y422719D01*
G01X86701Y425919D02*
X92901D01*
G01X86701Y422719D02*
Y425919D01*
G01X92901Y422719D02*
X86701D01*
G01X82591Y421919D02*
Y418719D01*
G01X92901Y421919D02*
Y418719D01*
G01X86701Y421919D02*
X92901D01*
G01X86701Y418719D02*
Y421919D01*
G01X92901Y418719D02*
X86701D01*
G01X78296Y439883D02*
Y444483D01*
G01X83796Y439883D02*
Y444483D01*
G01X79296Y439883D02*
Y444483D01*
G01X82591Y438119D02*
Y434919D01*
G01Y434119D02*
Y430919D01*
G01X86701Y429919D02*
X92901D01*
G01X86701Y436919D02*
Y440119D01*
G01X92901Y436919D02*
X86701D01*
G01X92901Y440119D02*
Y436919D01*
G01X86701Y440119D02*
X92901D01*
G01X86701Y440919D02*
Y444119D01*
G01X92901Y440919D02*
X86701D01*
G01X92901Y444119D02*
Y440919D01*
G01X86701Y444119D02*
X92901D01*
G01Y448119D02*
Y444919D01*
G01X86701D02*
Y448119D01*
G01X92901Y444919D02*
X86701D01*
G01Y452119D02*
X92901D01*
G01D02*
Y448919D01*
G01X86701D02*
Y452119D01*
G01X92901Y448919D02*
X86701D01*
G01Y448119D02*
X92901D01*
G01X93806Y529881D02*
Y532981D01*
X94726D01*
X95033Y532826D01*
X95263Y532464D01*
X95340Y532051D01*
X95263Y531638D01*
X95071Y531328D01*
X94726Y531173D01*
X93806D01*
G01X96906Y530501D02*
X97098Y530191D01*
X97328Y529984D01*
X97596Y529881D01*
X97903Y529984D01*
X98133Y530191D01*
X98363Y530501D01*
X98440Y530914D01*
Y532981D01*
G01X99930Y530346D02*
X100160Y530088D01*
X100428Y529933D01*
X100773Y529881D01*
X101118Y529984D01*
X101386Y530191D01*
X101578Y530553D01*
X101616Y530966D01*
X101540Y531379D01*
X101348Y531638D01*
X101080Y531844D01*
X100811Y531896D01*
X100543Y531844D01*
X100198Y531638D01*
X100313Y532981D01*
X101348D01*
G01X103873Y529881D02*
Y532981D01*
X103413Y532361D01*
G01Y529881D02*
X104333D01*
G01X88918Y635505D02*
Y641705D01*
G01X92118Y635505D02*
X88918D01*
G01X92118Y641705D02*
Y635505D01*
G01X87902D02*
X84702D01*
G01X87902Y641705D02*
Y635505D01*
G01X84702D02*
Y641705D01*
G01X88918D02*
X92118D01*
G01X79188Y661252D02*
Y655052D01*
G01X82290Y650174D02*
Y646974D01*
G01Y646164D02*
Y642964D01*
G01X84040D02*
Y646164D01*
G01X90240Y642964D02*
X84040D01*
G01X90240Y646164D02*
Y642964D01*
G01X84040Y646164D02*
X90240D01*
G01X84702Y641705D02*
X87902D01*
G01X82290Y654164D02*
Y650964D01*
G01X84040Y646964D02*
Y650164D01*
G01X90240Y646964D02*
X84040D01*
G01X90240Y650164D02*
Y646964D01*
G01X84040Y650164D02*
X90240D01*
G01X84040Y654964D02*
Y658164D01*
G01X90240Y654964D02*
X84040D01*
G01X90240Y658164D02*
Y654964D01*
G01X84040Y650964D02*
Y654164D01*
G01X90240Y650964D02*
X84040D01*
G01X90240Y654164D02*
Y650964D01*
G01X84040Y654164D02*
X90240D01*
G01X92240Y669334D02*
Y666134D01*
G01X86040Y669334D02*
X92240D01*
G01X86040Y666134D02*
Y669334D01*
G01X92240Y666134D02*
X86040D01*
G01X93360Y665170D02*
Y667670D01*
X93040Y667170D01*
G01Y665170D02*
X93680D01*
G01X95560D02*
Y667670D01*
X95240Y667170D01*
G01Y665170D02*
X95880D01*
G01X87861Y665231D02*
X91061D01*
G01Y659031D02*
X87861D01*
G01X91061Y665231D02*
Y659031D01*
G01X87861D02*
Y665231D01*
G01X84040Y658164D02*
X90240D01*
G01X83965Y665239D02*
X87165D01*
G01Y659039D02*
X83965D01*
G01X87165Y665239D02*
Y659039D01*
G01X83965D02*
Y665239D01*
G01X84919Y683888D02*
Y687088D01*
G01X91119Y683888D02*
X84919D01*
G01X91119Y687088D02*
Y683888D01*
G01X84919Y687088D02*
X91119D01*
G01X95147Y684045D02*
X91947D01*
G01D02*
Y690245D01*
G01X84908Y689044D02*
Y692244D01*
G01X91108Y689044D02*
X84908D01*
G01X91108Y692244D02*
Y689044D01*
G01X79265Y716719D02*
Y704719D01*
G01X86725Y701010D02*
Y697211D01*
X89670D01*
G01X91947Y690245D02*
X95147D01*
G01X86831Y702277D02*
Y703442D01*
G01X88981Y702277D02*
X86831D01*
G01X95099D02*
X92949D01*
G01X83908Y692609D02*
Y695809D01*
G01X90108Y692609D02*
X83908D01*
G01X90108Y695809D02*
Y692609D01*
G01X83908Y695809D02*
X90108D01*
G01X80414Y704192D02*
X83614D01*
G01X80414Y697992D02*
Y704192D01*
G01X83614Y697992D02*
X80414D01*
G01X83614Y704192D02*
Y697992D01*
G01X90496Y699280D02*
X93696D01*
G01X90496Y693080D02*
Y699280D01*
G01X93696Y693080D02*
X90496D01*
G01X93696Y699280D02*
Y693080D01*
G01X84908Y692244D02*
X91108D01*
G01X82615Y715772D02*
Y1302622D01*
G01X93135Y720479D02*
Y717279D01*
G01X86935Y720479D02*
X93135D01*
G01X86935Y717279D02*
Y720479D01*
G01X93135Y717279D02*
X86935D01*
G01X83911Y708249D02*
X80711D01*
G01X83911Y714449D02*
Y708249D01*
G01X80711Y714449D02*
X83911D01*
G01X80711Y708249D02*
Y714449D01*
G01X86831Y714481D02*
X88981D01*
G01X86831Y713316D02*
Y714481D01*
G01X92949D02*
X95099D01*
G01X94150Y717280D02*
Y720480D01*
G01X100350Y717280D02*
X94150D01*
G01Y720480D02*
X100350D01*
G01X112315Y732644D02*
X86725D01*
G01Y1301870D02*
Y722850D01*
G01X112315Y1299574D02*
X86725D01*
G01X91330Y1338361D02*
Y1306561D01*
G01X82615Y1316182D02*
Y1329212D01*
G01X86725Y1329390D02*
Y1316670D01*
G01X112315Y1335007D02*
X93880D01*
G01X90500Y1368989D02*
X84200D01*
Y1370555D01*
X84515Y1371182D01*
X84935Y1371652D01*
X85565Y1372044D01*
X86300Y1372357D01*
X87350Y1372435D01*
X88400Y1372357D01*
X89135Y1372044D01*
X89765Y1371652D01*
X90185Y1371182D01*
X90500Y1370555D01*
Y1368989D01*
G01X89240Y1375289D02*
X89975Y1375759D01*
X90395Y1376385D01*
X90500Y1377090D01*
X90395Y1377717D01*
X89870Y1378344D01*
X89240Y1378735D01*
X88610Y1378814D01*
X87875Y1378657D01*
X87350Y1378109D01*
X87140Y1377560D01*
Y1376855D01*
G01Y1377560D02*
X86825Y1378030D01*
X86300Y1378422D01*
X85670Y1378579D01*
X85040Y1378422D01*
X84515Y1378030D01*
X84200Y1377325D01*
X84305Y1376620D01*
X84725Y1375915D01*
G01X96140Y1371339D02*
X95825Y1371652D01*
X95300Y1371887D01*
X94565Y1372044D01*
X93935Y1371887D01*
X93515Y1371574D01*
X93200Y1371025D01*
Y1368910D01*
X99500D01*
Y1371495D01*
X99080Y1372044D01*
X98450Y1372357D01*
X97715Y1372514D01*
X96980Y1372357D01*
X96350Y1371887D01*
X96140Y1371339D01*
Y1368910D01*
G01X94250Y1375524D02*
X93620Y1375994D01*
X93305Y1376542D01*
X93200Y1377169D01*
X93410Y1377952D01*
X93935Y1378500D01*
X94565Y1378657D01*
X95195Y1378579D01*
X95720Y1378265D01*
X96770Y1376699D01*
X97505Y1375994D01*
X98555Y1375524D01*
X99500Y1375367D01*
Y1378657D01*
G01X92000Y1366962D02*
X82800D01*
G01X92000Y1380462D02*
Y1366962D01*
G01X101200D02*
X92000D01*
G01X82800Y1380462D02*
X92000D01*
G01D02*
X101200D01*
G01X82252Y1519111D02*
Y1512911D01*
G01X79052D02*
Y1516090D01*
G01X82252Y1522261D02*
Y1516061D01*
X79052D01*
G01X86074Y1524694D02*
Y1518494D01*
G01X82874D02*
Y1524694D01*
G01X86074Y1518494D02*
X82874D01*
G01X91971Y1512562D02*
Y1515520D01*
G01Y1518762D02*
X95171D01*
Y1512562D01*
G01Y1521912D02*
Y1515712D01*
X91971D01*
G01Y1518820D02*
Y1521912D01*
G01X86826Y1512562D02*
Y1518762D01*
X90026D01*
G01Y1515640D02*
Y1512562D01*
G01Y1521912D02*
Y1518810D01*
G01Y1515712D02*
X86826D01*
Y1521912D01*
G01X79052Y1519111D02*
X82252D01*
G01X79052Y1519100D02*
Y1522261D01*
G01X93374Y1531394D02*
Y1528194D01*
G01X85474Y1531444D02*
Y1529944D01*
G01X82874Y1524694D02*
X86074D01*
G01X79174Y1544744D02*
Y1546244D01*
G01X87074Y1547994D02*
Y1544794D01*
G01X85900Y1566194D02*
X89100D01*
G01X85900Y1559994D02*
Y1566194D01*
G01X89100Y1559994D02*
X85900D01*
G01X89100Y1566194D02*
Y1559994D01*
G01X89900Y1566194D02*
X93100D01*
G01X89900Y1559994D02*
Y1566194D01*
G01X93100Y1559994D02*
X89900D01*
G01X93100Y1566194D02*
Y1559994D01*
G01X85648Y1569861D02*
X82448D01*
G01X85648Y1576061D02*
Y1569861D01*
G01X82448Y1576061D02*
X85648D01*
G01X82448Y1569861D02*
Y1576061D01*
G01X89648D02*
Y1569861D01*
G01D02*
X86448D01*
G01Y1576061D02*
X89648D01*
G01X86448Y1569861D02*
Y1576061D01*
G01X91588Y1580252D02*
Y1583452D01*
G01X97788Y1580252D02*
X91588D01*
G01Y1583452D02*
X97788D01*
G01X93851Y1569861D02*
X90651D01*
G01X93851Y1576061D02*
Y1569861D01*
G01X90651Y1576061D02*
X93851D01*
G01X90651Y1569861D02*
Y1576061D01*
G01X91588Y1595467D02*
X97788D01*
G01X91588Y1592267D02*
Y1595467D01*
G01X97788Y1592267D02*
X91588D01*
G01Y1587452D02*
X97788D01*
G01X91588Y1584252D02*
Y1587452D01*
G01X97788Y1584252D02*
X91588D01*
G01Y1596267D02*
Y1599467D01*
G01X97788Y1596267D02*
X91588D01*
G01Y1599467D02*
X97788D01*
G01X91663Y1600267D02*
Y1603467D01*
G01X97863Y1600267D02*
X91663D01*
G01X91588Y1591452D02*
X97788D01*
G01X91588Y1588252D02*
Y1591452D01*
G01X97788Y1588252D02*
X91588D01*
G01X88738Y1591472D02*
Y1588272D01*
G01X82538D02*
Y1591472D01*
G01X88738Y1588272D02*
X82538D01*
G01Y1591472D02*
X88738D01*
G01X91663Y1613421D02*
X97863D01*
G01X91663Y1610221D02*
Y1613421D01*
G01X97863Y1610221D02*
X91663D01*
G01Y1603467D02*
X97863D01*
G01X91663Y1607467D02*
X97863D01*
G01X91663Y1604267D02*
Y1607467D01*
G01X97863Y1604267D02*
X91663D01*
G01Y1614221D02*
Y1617421D01*
G01X97863Y1614221D02*
X91663D01*
G01X80300Y1614200D02*
Y1620400D01*
X83500D01*
Y1614200D01*
X80300D01*
G01X84200D02*
Y1620400D01*
X87400D01*
Y1614200D01*
X84200D01*
G01X91573Y1632762D02*
Y1635962D01*
G01X97773Y1632762D02*
X91573D01*
G01X91663Y1625421D02*
X97863D01*
G01X91663Y1622221D02*
Y1625421D01*
G01X97863Y1622221D02*
X91663D01*
G01Y1618221D02*
Y1621421D01*
G01X97863Y1618221D02*
X91663D01*
G01Y1621421D02*
X97863D01*
G01X91663Y1617421D02*
X97863D01*
G01X91573Y1628762D02*
Y1631962D01*
G01X97773Y1628762D02*
X91573D01*
G01Y1631962D02*
X97773D01*
G01X83720Y1634271D02*
Y1650787D01*
G01X91573Y1635962D02*
X97773D01*
G01X91573Y1640762D02*
Y1643962D01*
G01X97773Y1640762D02*
X91573D01*
G01Y1643962D02*
X97773D01*
G01X91573Y1639962D02*
X97773D01*
G01X91573Y1636762D02*
Y1639962D01*
G01X97773Y1636762D02*
X91573D01*
G01X79433Y1670934D02*
Y1664734D01*
G01X80233D02*
Y1670934D01*
G01X83433Y1664734D02*
X80233D01*
G01X83433Y1670934D02*
Y1664734D01*
G01X88697Y1664780D02*
Y1670980D01*
G01X91897Y1664780D02*
X88697D01*
G01X91897Y1670980D02*
Y1664780D01*
G01X84233Y1664734D02*
Y1670934D01*
G01X87433Y1664734D02*
X84233D01*
G01X87433Y1670934D02*
Y1664734D01*
G01X87145Y1681471D02*
Y1684671D01*
G01X93345Y1681471D02*
X87145D01*
G01X93345Y1684671D02*
Y1681471D01*
G01X80233Y1670934D02*
X83433D01*
G01X88697Y1670980D02*
X91897D01*
G01X84233Y1670934D02*
X87433D01*
G01X87145Y1684671D02*
X93345D01*
G01X87120Y1692762D02*
Y1695962D01*
G01X93320Y1692762D02*
X87120D01*
G01X93320Y1695962D02*
Y1692762D01*
G01X87120Y1695962D02*
X93320D01*
G01Y1691962D02*
Y1688762D01*
G01X87120Y1691962D02*
X93320D01*
G01X87120Y1688762D02*
Y1691962D01*
G01X93320Y1688762D02*
X87120D01*
G01X79433Y1688234D02*
Y1682034D01*
G01X83433D02*
X80233D01*
G01X83433Y1688234D02*
Y1682034D01*
G01X80233Y1688234D02*
X83433D01*
G01X80233Y1682034D02*
Y1688234D01*
G01X87130Y1688222D02*
X93330D01*
Y1685022D01*
X87130D01*
Y1688222D01*
G01X110350Y51139D02*
X106360D01*
G01X103460D02*
X99610D01*
G01X109110Y79632D02*
X116110D01*
G01X109110D02*
Y126632D01*
G01X102110Y79632D02*
X109110D01*
G01X102110Y126632D02*
Y79632D01*
G01X106610Y81345D02*
X104110D01*
Y81879D01*
X104235Y82092D01*
X104402Y82252D01*
X104652Y82385D01*
X104943Y82492D01*
X105360Y82519D01*
X105777Y82492D01*
X106068Y82385D01*
X106318Y82252D01*
X106485Y82092D01*
X106610Y81879D01*
Y81345D01*
G01Y84079D02*
X106068Y84132D01*
X105610Y84212D01*
X105193Y84319D01*
X104735Y84452D01*
X104110Y84665D01*
Y83599D01*
G01X104527Y85825D02*
X104277Y85985D01*
X104152Y86172D01*
X104110Y86385D01*
X104193Y86652D01*
X104402Y86839D01*
X104652Y86892D01*
X104902Y86865D01*
X105110Y86759D01*
X105527Y86225D01*
X105818Y85985D01*
X106235Y85825D01*
X106610Y85772D01*
Y86892D01*
G01Y90899D02*
X104110D01*
Y91565D01*
X104235Y91779D01*
X104402Y91912D01*
X104735Y91965D01*
X105068Y91912D01*
X105277Y91752D01*
X105402Y91565D01*
Y90899D01*
G01Y91565D02*
X106610Y91965D01*
G01X106277Y93072D02*
X106485Y93285D01*
X106610Y93525D01*
Y93739D01*
X106485Y93952D01*
X106277Y94112D01*
X105985Y94192D01*
X105693Y94139D01*
X105443Y94005D01*
X105277Y93765D01*
X105193Y93445D01*
X105027Y93259D01*
X104735Y93179D01*
X104443Y93232D01*
X104235Y93365D01*
X104110Y93552D01*
Y93739D01*
X104193Y93925D01*
X104402Y94085D01*
G01X104110Y95832D02*
X106610D01*
G01X104110Y95219D02*
Y96445D01*
G01X107443Y97232D02*
Y98832D01*
G01X104318Y100819D02*
X104193Y100659D01*
X104110Y100472D01*
Y100259D01*
X104235Y100019D01*
X104443Y99832D01*
X104693Y99699D01*
X105110Y99592D01*
X105485Y99565D01*
X105860Y99619D01*
X106110Y99699D01*
X106360Y99859D01*
X106527Y100045D01*
X106610Y100232D01*
Y100419D01*
X106527Y100605D01*
X106402Y100765D01*
X106235Y100899D01*
G01X106610Y101899D02*
X104110D01*
Y102539D01*
X104235Y102752D01*
X104527Y102912D01*
X104860Y102965D01*
X105193Y102912D01*
X105443Y102779D01*
X105568Y102539D01*
Y101899D01*
G01X104110Y104045D02*
X105902D01*
X106277Y104152D01*
X106527Y104365D01*
X106610Y104632D01*
X106527Y104899D01*
X106277Y105112D01*
X105902Y105219D01*
X104110D01*
G01X106610Y106832D02*
X104110D01*
X104610Y106512D01*
G01X106610D02*
Y107152D01*
G01X107443Y108232D02*
Y109832D01*
G01X106610Y110645D02*
X104110D01*
Y111179D01*
X104235Y111392D01*
X104402Y111552D01*
X104652Y111685D01*
X104943Y111792D01*
X105360Y111819D01*
X105777Y111792D01*
X106068Y111685D01*
X106318Y111552D01*
X106485Y111392D01*
X106610Y111179D01*
Y110645D01*
G01Y112899D02*
X104110D01*
Y113565D01*
X104235Y113779D01*
X104402Y113912D01*
X104735Y113965D01*
X105068Y113912D01*
X105277Y113752D01*
X105402Y113565D01*
Y112899D01*
G01Y113565D02*
X106610Y113965D01*
G01Y114965D02*
X104110Y115632D01*
X106610Y116299D01*
G01X105735Y116059D02*
Y115205D01*
G01X106610Y117139D02*
X104110D01*
X106193Y117832D01*
X104110Y118525D01*
X106610D01*
G01X107443Y119232D02*
Y120832D01*
G01X105360Y122392D02*
Y122925D01*
X106110D01*
X106360Y122765D01*
X106527Y122579D01*
X106610Y122312D01*
X106527Y122045D01*
X106360Y121859D01*
X106110Y121699D01*
X105818Y121592D01*
X105485Y121539D01*
X105193D01*
X104943Y121592D01*
X104652Y121699D01*
X104402Y121859D01*
X104235Y122019D01*
X104110Y122232D01*
Y122419D01*
X104193Y122632D01*
X104360Y122792D01*
G01X106610Y123872D02*
X104110D01*
G01Y124992D02*
X106610D01*
G01X105360D02*
Y123872D01*
G01X102110Y88890D02*
X221110D01*
G01X102110Y126632D02*
Y183632D01*
G01X109110Y126632D02*
X102110D01*
G01X109110Y183632D02*
Y126632D01*
G01D02*
X116110D01*
G01X106610Y140899D02*
X104110D01*
Y141539D01*
X104235Y141752D01*
X104527Y141912D01*
X104860Y141965D01*
X105193Y141912D01*
X105443Y141779D01*
X105568Y141539D01*
Y140899D01*
G01X104110Y142965D02*
X106610Y143632D01*
X104110Y144299D01*
G01X104318Y146419D02*
X104193Y146259D01*
X104110Y146072D01*
Y145859D01*
X104235Y145619D01*
X104443Y145432D01*
X104693Y145299D01*
X105110Y145192D01*
X105485Y145165D01*
X105860Y145219D01*
X106110Y145299D01*
X106360Y145459D01*
X106527Y145645D01*
X106610Y145832D01*
Y146019D01*
X106527Y146205D01*
X106402Y146365D01*
X106235Y146499D01*
G01X104318Y148619D02*
X104193Y148459D01*
X104110Y148272D01*
Y148059D01*
X104235Y147819D01*
X104443Y147632D01*
X104693Y147499D01*
X105110Y147392D01*
X105485Y147365D01*
X105860Y147419D01*
X106110Y147499D01*
X106360Y147659D01*
X106527Y147845D01*
X106610Y148032D01*
Y148219D01*
X106527Y148405D01*
X106402Y148565D01*
X106235Y148699D01*
G01X104110Y149912D02*
Y150552D01*
G01Y150232D02*
X106610D01*
G01Y149912D02*
Y150552D01*
G01Y151819D02*
X104110D01*
X106610Y153045D01*
X104110D01*
G01X106610Y154125D02*
X104110D01*
Y155139D01*
G01X105318Y154765D02*
Y154125D01*
G01X106610Y156165D02*
X104110Y156832D01*
X106610Y157499D01*
G01X105735Y157259D02*
Y156405D01*
G01X106610Y159032D02*
X106568Y158819D01*
X106402Y158632D01*
X106152Y158472D01*
X105860Y158365D01*
X105527Y158312D01*
X105193D01*
X104860Y158365D01*
X104568Y158472D01*
X104318Y158632D01*
X104152Y158819D01*
X104110Y159032D01*
X104152Y159245D01*
X104318Y159432D01*
X104568Y159592D01*
X104860Y159699D01*
X105193Y159752D01*
X105527D01*
X105860Y159699D01*
X106152Y159592D01*
X106402Y159432D01*
X106568Y159245D01*
X106610Y159032D01*
G01Y160619D02*
X104110D01*
X106610Y161845D01*
X104110D01*
G01X107443Y162632D02*
Y164232D01*
G01X104318Y166219D02*
X104193Y166059D01*
X104110Y165872D01*
Y165659D01*
X104235Y165419D01*
X104443Y165232D01*
X104693Y165099D01*
X105110Y164992D01*
X105485Y164965D01*
X105860Y165019D01*
X106110Y165099D01*
X106360Y165259D01*
X106527Y165445D01*
X106610Y165632D01*
Y165819D01*
X106527Y166005D01*
X106402Y166165D01*
X106235Y166299D01*
G01X106610Y167299D02*
X104110D01*
Y167939D01*
X104235Y168152D01*
X104527Y168312D01*
X104860Y168365D01*
X105193Y168312D01*
X105443Y168179D01*
X105568Y167939D01*
Y167299D01*
G01X104110Y169445D02*
X105902D01*
X106277Y169552D01*
X106527Y169765D01*
X106610Y170032D01*
X106527Y170299D01*
X106277Y170512D01*
X105902Y170619D01*
X104110D01*
G01Y172232D02*
X104193Y172019D01*
X104402Y171859D01*
X104652Y171752D01*
X104985Y171672D01*
X105360Y171645D01*
X105735Y171672D01*
X106068Y171752D01*
X106318Y171859D01*
X106527Y172019D01*
X106610Y172232D01*
X106527Y172445D01*
X106318Y172605D01*
X106068Y172712D01*
X105735Y172792D01*
X105360Y172819D01*
X104985Y172792D01*
X104652Y172712D01*
X104402Y172605D01*
X104193Y172445D01*
X104110Y172232D01*
G01X101255Y170863D02*
Y167663D01*
G01X95055D02*
Y170863D01*
G01X101255Y167663D02*
X95055D01*
G01X102110Y183632D02*
X109110D01*
G01X116110D02*
X109110D01*
G01X102110Y174685D02*
X165110D01*
G01X106610Y176345D02*
X104110D01*
Y176879D01*
X104235Y177092D01*
X104402Y177252D01*
X104652Y177385D01*
X104943Y177492D01*
X105360Y177519D01*
X105777Y177492D01*
X106068Y177385D01*
X106318Y177252D01*
X106485Y177092D01*
X106610Y176879D01*
Y176345D01*
G01Y179079D02*
X106068Y179132D01*
X105610Y179212D01*
X105193Y179319D01*
X104735Y179452D01*
X104110Y179665D01*
Y178599D01*
G01X106610Y181279D02*
X106068Y181332D01*
X105610Y181412D01*
X105193Y181519D01*
X104735Y181652D01*
X104110Y181865D01*
Y180799D01*
G01X95055Y170863D02*
X101255D01*
G01X113675Y184762D02*
X107475D01*
G01D02*
Y187962D01*
G01D02*
X113675D01*
G01X106415Y214996D02*
Y218196D01*
G01X112615Y214996D02*
X106415D01*
G01X106325Y233728D02*
X112525D01*
G01X106325Y230528D02*
Y233728D01*
G01X112525Y230528D02*
X106325D01*
G01X106415Y218196D02*
X112615D01*
G01X102580Y278431D02*
Y287093D01*
G01X109412Y281395D02*
Y284595D01*
G01X115612Y281395D02*
X109412D01*
G01Y277275D02*
Y280475D01*
G01X115612Y277275D02*
X109412D01*
G01Y280475D02*
X115612D01*
G01X109412Y276400D02*
X115612D01*
Y273200D01*
X109412D01*
Y276400D01*
G01X99471Y287093D02*
X97140Y284762D01*
G01X102580Y287093D02*
X99471D01*
G01X97140Y284762D02*
X94809Y287093D01*
G01X102580Y295931D02*
Y304593D01*
G01X109412Y284595D02*
X115612D01*
G01X109412Y298754D02*
Y301954D01*
G01X115612Y298754D02*
X109412D01*
G01X99471Y304593D02*
X97140Y302262D01*
G01X102580Y304593D02*
X99471D01*
G01X97140Y302262D02*
X94809Y304593D01*
G01X109412Y301954D02*
X115612D01*
G01X109412Y304636D02*
Y307836D01*
G01X115612Y304636D02*
X109412D01*
G01Y307836D02*
X115612D01*
G01X109232Y389671D02*
X115432D01*
Y386471D01*
X109232D01*
Y389671D01*
G01Y393671D02*
X115432D01*
Y390471D01*
X109232D01*
Y393671D01*
G01X112482Y402071D02*
X100482D01*
G01Y408071D02*
X112482D01*
G01X100482Y402071D02*
Y408071D01*
G01X109633Y420408D02*
X124349D01*
G01X109633Y440486D02*
Y420408D01*
G01X112952Y440486D02*
X109633D01*
G01X104388Y451074D02*
Y448852D01*
X104541Y448387D01*
X104848Y448077D01*
X105231Y447974D01*
X105614Y448077D01*
X105921Y448387D01*
X106074Y448852D01*
Y451074D01*
G01X107603Y450557D02*
X107833Y450867D01*
X108101Y451022D01*
X108408Y451074D01*
X108791Y450971D01*
X109059Y450712D01*
X109136Y450402D01*
X109098Y450092D01*
X108944Y449834D01*
X108178Y449317D01*
X107833Y448956D01*
X107603Y448439D01*
X107526Y447974D01*
X109136D01*
G01X110703Y449266D02*
X110971Y449627D01*
X111201Y449834D01*
X111508Y449937D01*
X111776Y449834D01*
X111968Y449627D01*
X112121Y449317D01*
X112159Y448956D01*
X112121Y448646D01*
X111968Y448336D01*
X111738Y448077D01*
X111469Y447974D01*
X111163Y448077D01*
X110894Y448387D01*
X110741Y448852D01*
X110703Y449369D01*
X110779Y450041D01*
X110894Y450402D01*
X111086Y450764D01*
X111354Y451022D01*
X111623Y451074D01*
X111891Y450971D01*
X112083Y450712D01*
G01X113879Y448336D02*
X114148Y448077D01*
X114454Y447974D01*
X114761Y448077D01*
X115029Y448387D01*
X115221Y448852D01*
X115298Y449317D01*
Y449886D01*
X115221Y450351D01*
X115029Y450764D01*
X114799Y450971D01*
X114531Y451074D01*
X114224Y450971D01*
X113994Y450764D01*
X113841Y450454D01*
X113764Y450041D01*
X113841Y449679D01*
X114033Y449317D01*
X114263Y449111D01*
X114531Y449059D01*
X114838Y449162D01*
X115068Y449421D01*
X115298Y449886D01*
G01X109520Y491978D02*
X103320D01*
Y495178D01*
X109520D01*
Y491978D01*
G01X103756Y481539D02*
Y484639D01*
X104676D01*
X104983Y484484D01*
X105213Y484122D01*
X105290Y483709D01*
X105213Y483296D01*
X105021Y482986D01*
X104676Y482831D01*
X103756D01*
G01X106780Y484639D02*
Y482417D01*
X106933Y481952D01*
X107240Y481642D01*
X107623Y481539D01*
X108006Y481642D01*
X108313Y481952D01*
X108466Y482417D01*
Y484639D01*
G01X109995Y484122D02*
X110225Y484432D01*
X110493Y484587D01*
X110800Y484639D01*
X111183Y484536D01*
X111451Y484277D01*
X111528Y483967D01*
X111490Y483657D01*
X111336Y483399D01*
X110570Y482882D01*
X110225Y482521D01*
X109995Y482004D01*
X109918Y481539D01*
X111528D01*
G01X113095Y484122D02*
X113325Y484432D01*
X113593Y484587D01*
X113900Y484639D01*
X114283Y484536D01*
X114551Y484277D01*
X114628Y483967D01*
X114590Y483657D01*
X114436Y483399D01*
X113670Y482882D01*
X113325Y482521D01*
X113095Y482004D01*
X113018Y481539D01*
X114628D01*
G01X109550Y498974D02*
Y495774D01*
G01X103350Y498974D02*
X109550D01*
G01X103350Y495774D02*
Y498974D01*
G01X109550Y495774D02*
X103350D01*
G01X109550Y502974D02*
Y499774D01*
G01X103350Y502974D02*
X109550D01*
G01X103350Y499774D02*
Y502974D01*
G01X109550Y499774D02*
X103350D01*
G01X109550Y506974D02*
Y503774D01*
G01X103350Y506974D02*
X109550D01*
G01X103350Y503774D02*
Y506974D01*
G01X109550Y503774D02*
X103350D01*
G01X109550Y510974D02*
Y507774D01*
G01X103350D02*
Y510974D01*
G01X109550Y507774D02*
X103350D01*
G01X109550Y514974D02*
Y511774D01*
G01X103350Y514974D02*
X109550D01*
G01X103350Y511774D02*
Y514974D01*
G01X109550Y511774D02*
X103350D01*
G01Y510974D02*
X109550D01*
G01X110323Y519080D02*
X110483Y518788D01*
X110697Y518622D01*
X110937Y518580D01*
X111150Y518622D01*
X111363Y518830D01*
X111497Y519080D01*
X111523Y519330D01*
X111470Y519622D01*
X111283Y519830D01*
X111097Y519913D01*
X110857D01*
G01X111097D02*
X111257Y520038D01*
X111390Y520247D01*
X111443Y520497D01*
X111390Y520747D01*
X111257Y520955D01*
X111017Y521080D01*
X110777Y521038D01*
X110537Y520872D01*
G01X113110Y518580D02*
Y521080D01*
X112790Y520580D01*
G01Y518580D02*
X113430D01*
G01X103350Y516325D02*
Y519525D01*
G01X109550Y516325D02*
X103350D01*
G01X109550Y519525D02*
Y516325D01*
G01X103350Y519525D02*
X109550D01*
G01X100614Y514470D02*
Y511270D01*
G01X94414Y514470D02*
X100614D01*
G01X94414Y511270D02*
Y514470D01*
G01X100614Y511270D02*
X94414D01*
G01X110243Y528417D02*
Y522217D01*
G01D02*
X107043D01*
G01D02*
Y528417D01*
G01X109387Y540115D02*
Y546315D01*
G01X112587Y540115D02*
X109387D01*
G01X107043Y528417D02*
X110243D01*
G01X109387Y546315D02*
X112587D01*
G01X140832Y605380D02*
G03I-22900J0D01*
G01X98193Y632125D02*
X98353Y632375D01*
X98540Y632500D01*
X98753Y632542D01*
X99020Y632459D01*
X99207Y632250D01*
X99260Y632000D01*
X99233Y631750D01*
X99127Y631542D01*
X98593Y631125D01*
X98353Y630834D01*
X98193Y630417D01*
X98140Y630042D01*
X99260D01*
G01X100900D02*
Y632542D01*
X100580Y632042D01*
G01Y630042D02*
X101220D01*
G01X97753Y636483D02*
X97913Y636733D01*
X98100Y636858D01*
X98313Y636900D01*
X98580Y636817D01*
X98767Y636608D01*
X98820Y636358D01*
X98793Y636108D01*
X98687Y635900D01*
X98153Y635483D01*
X97913Y635192D01*
X97753Y634775D01*
X97700Y634400D01*
X98820D01*
G01X100460Y636900D02*
X100247Y636817D01*
X100087Y636608D01*
X99980Y636358D01*
X99900Y636025D01*
X99873Y635650D01*
X99900Y635275D01*
X99980Y634942D01*
X100087Y634692D01*
X100247Y634483D01*
X100460Y634400D01*
X100673Y634483D01*
X100833Y634692D01*
X100940Y634942D01*
X101020Y635275D01*
X101047Y635650D01*
X101020Y636025D01*
X100940Y636358D01*
X100833Y636608D01*
X100673Y636817D01*
X100460Y636900D01*
G01X99066Y639083D02*
Y640989D01*
G01X100972Y639083D02*
X99066D01*
G01X108109Y637576D02*
Y636076D01*
G01X94609Y641926D02*
X97609D01*
G01X97559Y649726D02*
X96059D01*
G01X97970Y666322D02*
Y668822D01*
X97650Y668322D01*
G01Y666322D02*
X98290D01*
G01X100170Y668822D02*
X99957Y668739D01*
X99797Y668530D01*
X99690Y668280D01*
X99610Y667947D01*
X99583Y667572D01*
X99610Y667197D01*
X99690Y666864D01*
X99797Y666614D01*
X99957Y666405D01*
X100170Y666322D01*
X100383Y666405D01*
X100543Y666614D01*
X100650Y666864D01*
X100730Y667197D01*
X100757Y667572D01*
X100730Y667947D01*
X100650Y668280D01*
X100543Y668530D01*
X100383Y668739D01*
X100170Y668822D01*
G01X99066Y658769D02*
X100962D01*
G01X99066Y656863D02*
Y658769D01*
G01X101809Y663326D02*
Y660326D01*
G01X109609Y661776D02*
Y660276D01*
G01X95147Y690245D02*
Y684045D01*
G01X95949Y683965D02*
Y690165D01*
X99149D01*
Y683965D01*
X95949D01*
G01X105495Y687090D02*
X111695D01*
Y683890D01*
X105495D01*
Y687090D01*
G01X106753Y693850D02*
Y699839D01*
G01X135493Y693850D02*
X106753D01*
G01X101520Y697211D02*
X104260D01*
G01X100420Y697862D02*
Y694662D01*
G01X94220Y697862D02*
X100420D01*
G01X94220Y694662D02*
Y697862D01*
G01X100420Y694662D02*
X94220D01*
G01X95099Y703442D02*
Y702277D01*
G01X102531Y700677D02*
X99331D01*
G01X102531Y706877D02*
Y700677D01*
G01X99331D02*
Y706877D01*
G01X106753Y714139D02*
Y720228D01*
G01X106723D02*
X135493D01*
G01X102514Y707647D02*
X99314D01*
G01X102514Y713847D02*
Y707647D01*
G01X99314Y713847D02*
X102514D01*
G01X99314Y707647D02*
Y713847D01*
G01X95099Y714481D02*
Y713316D01*
G01X100350Y720480D02*
Y717280D01*
G01X99331Y706877D02*
X102531D01*
G01X98620Y1337465D02*
X98812Y1337155D01*
X99042Y1336948D01*
X99310Y1336845D01*
X99617Y1336948D01*
X99847Y1337155D01*
X100077Y1337465D01*
X100154Y1337878D01*
Y1339945D01*
G01X101759Y1339428D02*
X101989Y1339738D01*
X102257Y1339893D01*
X102564Y1339945D01*
X102947Y1339842D01*
X103215Y1339583D01*
X103292Y1339273D01*
X103254Y1338963D01*
X103100Y1338705D01*
X102334Y1338188D01*
X101989Y1337827D01*
X101759Y1337310D01*
X101682Y1336845D01*
X103292D01*
G01X105587D02*
Y1339945D01*
X105127Y1339325D01*
G01Y1336845D02*
X106047D01*
G01X100127Y1357862D02*
Y1364162D01*
X101693D01*
X102320Y1363847D01*
X102790Y1363427D01*
X103182Y1362797D01*
X103495Y1362062D01*
X103573Y1361012D01*
X103495Y1359962D01*
X103182Y1359227D01*
X102790Y1358597D01*
X102320Y1358177D01*
X101693Y1357862D01*
X100127D01*
G01X107210Y1364162D02*
X109090D01*
G01X108150D02*
Y1357862D01*
G01X107210D02*
X109090D01*
G01X112413D02*
Y1364162D01*
X114450Y1358912D01*
X116487Y1364162D01*
Y1357862D01*
G01X118713D02*
Y1364162D01*
X120750Y1358912D01*
X122787Y1364162D01*
Y1357862D01*
G01X109000Y1368989D02*
X102700D01*
Y1370555D01*
X103015Y1371182D01*
X103435Y1371652D01*
X104065Y1372044D01*
X104800Y1372357D01*
X105850Y1372435D01*
X106900Y1372357D01*
X107635Y1372044D01*
X108265Y1371652D01*
X108685Y1371182D01*
X109000Y1370555D01*
Y1368989D01*
G01X103750Y1375524D02*
X103120Y1375994D01*
X102805Y1376542D01*
X102700Y1377169D01*
X102910Y1377952D01*
X103435Y1378500D01*
X104065Y1378657D01*
X104695Y1378579D01*
X105220Y1378265D01*
X106270Y1376699D01*
X107005Y1375994D01*
X108055Y1375524D01*
X109000Y1375367D01*
Y1378657D01*
G01X101200Y1380462D02*
Y1366962D01*
G01X110400D02*
X101200D01*
G01X110400Y1380462D02*
Y1366962D01*
G01X119600D02*
X110400D01*
G01X101200Y1380462D02*
X110400D01*
G01D02*
X119600D01*
G01X109043Y1408902D02*
Y1412002D01*
X109963D01*
X110270Y1411847D01*
X110500Y1411485D01*
X110577Y1411072D01*
X110500Y1410659D01*
X110308Y1410349D01*
X109963Y1410194D01*
X109043D01*
G01X112067Y1412002D02*
Y1409780D01*
X112220Y1409315D01*
X112527Y1409005D01*
X112910Y1408902D01*
X113293Y1409005D01*
X113600Y1409315D01*
X113753Y1409780D01*
Y1412002D01*
G01X115933Y1408902D02*
X116010Y1409574D01*
X116125Y1410142D01*
X116278Y1410659D01*
X116470Y1411227D01*
X116777Y1412002D01*
X115243D01*
G01X119110Y1408902D02*
X119378Y1408954D01*
X119685Y1409109D01*
X119877Y1409367D01*
X119953Y1409729D01*
X119877Y1410090D01*
X119647Y1410400D01*
X119302Y1410555D01*
X118918D01*
X118688Y1410659D01*
X118497Y1410917D01*
X118420Y1411279D01*
X118535Y1411640D01*
X118803Y1411899D01*
X119110Y1412002D01*
X119417Y1411899D01*
X119685Y1411640D01*
X119800Y1411279D01*
X119723Y1410917D01*
X119532Y1410659D01*
X119302Y1410555D01*
X118918D01*
X118573Y1410400D01*
X118343Y1410090D01*
X118267Y1409729D01*
X118343Y1409367D01*
X118535Y1409109D01*
X118842Y1408954D01*
X119110Y1408902D01*
G01X121060Y1407869D02*
X123360D01*
G01X124543Y1408902D02*
Y1412002D01*
X125463D01*
X125770Y1411847D01*
X126000Y1411485D01*
X126077Y1411072D01*
X126000Y1410659D01*
X125808Y1410349D01*
X125463Y1410194D01*
X124543D01*
G01X128410Y1408902D02*
Y1412002D01*
X127950Y1411382D01*
G01Y1408902D02*
X128870D01*
G01X130360Y1407869D02*
X132660D01*
G01X135070Y1408902D02*
Y1412002D01*
X133652Y1409780D01*
X135568D01*
G01X96414Y1519501D02*
Y1522001D01*
X96094Y1521501D01*
G01Y1519501D02*
X96734D01*
G01X98614Y1522001D02*
X98401Y1521918D01*
X98241Y1521709D01*
X98134Y1521459D01*
X98054Y1521126D01*
X98027Y1520751D01*
X98054Y1520376D01*
X98134Y1520043D01*
X98241Y1519793D01*
X98401Y1519584D01*
X98614Y1519501D01*
X98827Y1519584D01*
X98987Y1519793D01*
X99094Y1520043D01*
X99174Y1520376D01*
X99201Y1520751D01*
X99174Y1521126D01*
X99094Y1521459D01*
X98987Y1521709D01*
X98827Y1521918D01*
X98614Y1522001D01*
G01X108770Y1515642D02*
X105570D01*
G01X108770Y1521842D02*
Y1515642D01*
G01X105570D02*
Y1521842D01*
G01X101140Y1530092D02*
Y1532592D01*
X100820Y1532092D01*
G01Y1530092D02*
X101460D01*
G01X103340D02*
Y1532592D01*
X103020Y1532092D01*
G01Y1530092D02*
X103660D01*
G01X94211Y1532976D02*
X95329D01*
Y1534094D01*
G01X95174Y1530694D02*
X98374D01*
G01X95174Y1524494D02*
Y1530694D01*
G01X98374Y1524494D02*
X95174D01*
G01X98374Y1530694D02*
Y1524494D01*
G01X105570Y1521842D02*
X108770D01*
G01X105674Y1522994D02*
Y1526194D01*
G01X111874Y1522994D02*
X105674D01*
G01Y1526194D02*
X111874D01*
G01X105674Y1530194D02*
X111874D01*
G01X105674Y1526994D02*
Y1530194D01*
G01X111874Y1526994D02*
X105674D01*
G01Y1534994D02*
Y1538194D01*
G01X111874Y1534994D02*
X105674D01*
G01Y1534294D02*
X111874D01*
G01X105674Y1531094D02*
Y1534294D01*
G01X111874Y1531094D02*
X105674D01*
G01X101202Y1542835D02*
Y1545335D01*
X100882Y1544835D01*
G01Y1542835D02*
X101522D01*
G01X102815Y1543210D02*
X102975Y1543002D01*
X103162Y1542877D01*
X103402Y1542835D01*
X103642Y1542918D01*
X103829Y1543085D01*
X103962Y1543377D01*
X103989Y1543710D01*
X103935Y1544043D01*
X103802Y1544252D01*
X103615Y1544418D01*
X103429Y1544460D01*
X103242Y1544418D01*
X103002Y1544252D01*
X103082Y1545335D01*
X103802D01*
G01X96944Y1544871D02*
Y1547371D01*
X96624Y1546871D01*
G01Y1544871D02*
X97264D01*
G01X98637Y1545913D02*
X98824Y1546204D01*
X98984Y1546371D01*
X99197Y1546454D01*
X99384Y1546371D01*
X99517Y1546204D01*
X99624Y1545954D01*
X99651Y1545663D01*
X99624Y1545413D01*
X99517Y1545163D01*
X99357Y1544954D01*
X99171Y1544871D01*
X98957Y1544954D01*
X98771Y1545204D01*
X98664Y1545579D01*
X98637Y1545996D01*
X98691Y1546538D01*
X98771Y1546829D01*
X98904Y1547121D01*
X99091Y1547329D01*
X99277Y1547371D01*
X99464Y1547288D01*
X99597Y1547079D01*
G01X98424Y1541194D02*
X96924D01*
G01X95329Y1542094D02*
Y1543212D01*
X94211D01*
G01X105674Y1542994D02*
Y1546194D01*
G01X111874Y1542994D02*
X105674D01*
G01Y1546194D02*
X111874D01*
G01X105674Y1550994D02*
Y1554194D01*
G01X111874Y1550994D02*
X105674D01*
G01Y1546994D02*
Y1550194D01*
G01X111874Y1546994D02*
X105674D01*
G01Y1550194D02*
X111874D01*
G01X105674Y1538194D02*
X111874D01*
G01X105674Y1538994D02*
Y1542194D01*
G01X111874Y1538994D02*
X105674D01*
G01Y1542194D02*
X111874D01*
G01X103850Y1565653D02*
Y1559453D01*
G01X100650D02*
Y1562540D01*
G01Y1565653D02*
X103850D01*
G01Y1568803D02*
Y1562603D01*
X100650D01*
G01Y1565650D02*
Y1568803D01*
G01X95583Y1562598D02*
Y1568798D01*
G01X98783D02*
Y1565690D01*
G01Y1562598D02*
X95583D01*
G01Y1559448D02*
Y1565648D01*
X98783D01*
G01Y1562480D02*
Y1559448D01*
G01X105674Y1554194D02*
X111874D01*
G01X105674Y1558194D02*
X111874D01*
G01X105674Y1554994D02*
Y1558194D01*
G01X111874Y1554994D02*
X105674D01*
G01Y1558994D02*
Y1562194D01*
G01X111874Y1558994D02*
X105674D01*
G01Y1562194D02*
X111874D01*
G01X105674Y1562994D02*
Y1566194D01*
G01X111874Y1562994D02*
X105674D01*
G01Y1566194D02*
X111874D01*
G01X97851Y1576061D02*
Y1569861D01*
G01D02*
X94651D01*
G01Y1576061D02*
X97851D01*
G01X94651Y1569861D02*
Y1576061D01*
G01X97788Y1583452D02*
Y1580252D01*
G01X110558Y1591483D02*
X112458Y1593683D01*
G01X108658D02*
X110558Y1591483D01*
G01X105311Y1593683D02*
X108658D01*
G01X105311Y1585021D02*
Y1593683D01*
G01X115805Y1585021D02*
X105311D01*
G01Y1596800D02*
Y1605462D01*
G01X115805Y1596800D02*
X105311D01*
G01X97788Y1595467D02*
Y1592267D01*
G01Y1587452D02*
Y1584252D01*
G01Y1599467D02*
Y1596267D01*
G01X97863Y1603467D02*
Y1600267D01*
G01X97788Y1591452D02*
Y1588252D01*
G01X105311Y1615490D02*
Y1624152D01*
G01X115805Y1615490D02*
X105311D01*
G01X110558Y1603262D02*
X112458Y1605462D01*
G01X108658D02*
X110558Y1603262D01*
G01X105311Y1605462D02*
X108658D01*
G01X97863Y1613421D02*
Y1610221D01*
G01X107200Y1613500D02*
X110400D01*
G01X107200Y1607300D02*
Y1613500D01*
G01X110400Y1607300D02*
X107200D01*
G01X110400Y1613500D02*
Y1607300D01*
G01X97863Y1607467D02*
Y1604267D01*
G01Y1617421D02*
Y1614221D01*
G01X103300Y1613500D02*
X106500D01*
G01Y1607300D02*
X103300D01*
G01X106500Y1613500D02*
Y1607300D01*
G01X103300D02*
Y1613500D01*
G01X110558Y1621952D02*
X112458Y1624152D01*
G01X108658D02*
X110558Y1621952D01*
G01X105311Y1624152D02*
X108658D01*
G01X97773Y1635962D02*
Y1632762D01*
G01X97863Y1625421D02*
Y1622221D01*
G01Y1621421D02*
Y1618221D01*
G01X97773Y1631962D02*
Y1628762D01*
G01X105311Y1642193D02*
X108658D01*
G01D02*
X110558Y1639993D01*
G01D02*
X112458Y1642193D01*
G01X115805Y1633531D02*
X105311D01*
G01D02*
Y1642193D01*
G01X97773Y1643962D02*
Y1640762D01*
G01Y1639962D02*
Y1636762D01*
G01X101100Y1654200D02*
X94900D01*
Y1657400D01*
X101100D01*
Y1654200D01*
G01Y1650200D02*
X94900D01*
Y1653400D01*
X101100D01*
Y1650200D01*
G01X96437Y1679262D02*
Y1677040D01*
X96590Y1676575D01*
X96897Y1676265D01*
X97280Y1676162D01*
X97663Y1676265D01*
X97970Y1676575D01*
X98123Y1677040D01*
Y1679262D01*
G01X99652Y1678745D02*
X99882Y1679055D01*
X100150Y1679210D01*
X100457Y1679262D01*
X100840Y1679159D01*
X101108Y1678900D01*
X101185Y1678590D01*
X101147Y1678280D01*
X100993Y1678022D01*
X100227Y1677505D01*
X99882Y1677144D01*
X99652Y1676627D01*
X99575Y1676162D01*
X101185D01*
G01X102637Y1676627D02*
X102867Y1676369D01*
X103135Y1676214D01*
X103480Y1676162D01*
X103825Y1676265D01*
X104093Y1676472D01*
X104285Y1676834D01*
X104323Y1677247D01*
X104247Y1677660D01*
X104055Y1677919D01*
X103787Y1678125D01*
X103518Y1678177D01*
X103250Y1678125D01*
X102905Y1677919D01*
X103020Y1679262D01*
X104055D01*
G01X105852Y1678745D02*
X106082Y1679055D01*
X106350Y1679210D01*
X106657Y1679262D01*
X107040Y1679159D01*
X107308Y1678900D01*
X107385Y1678590D01*
X107347Y1678280D01*
X107193Y1678022D01*
X106427Y1677505D01*
X106082Y1677144D01*
X105852Y1676627D01*
X105775Y1676162D01*
X107385D01*
G01X100920Y1681031D02*
Y1689693D01*
G01X111520Y1681031D02*
X100920D01*
G01X108858Y1689693D02*
X111520D01*
G01X106220Y1686862D02*
X108858Y1689693D01*
G01X103582D02*
X106220Y1686862D01*
G01X100920Y1689693D02*
X103582D01*
G01X106220Y1697862D02*
X108858Y1700693D01*
G01X103582D02*
X106220Y1697862D01*
G01X100920Y1692031D02*
Y1700693D01*
G01X111520Y1692031D02*
X100920D01*
G01X98827Y1705852D02*
Y1703630D01*
X98980Y1703165D01*
X99287Y1702855D01*
X99670Y1702752D01*
X100053Y1702855D01*
X100360Y1703165D01*
X100513Y1703630D01*
Y1705852D01*
G01X102042Y1705335D02*
X102272Y1705645D01*
X102540Y1705800D01*
X102847Y1705852D01*
X103230Y1705749D01*
X103498Y1705490D01*
X103575Y1705180D01*
X103537Y1704870D01*
X103383Y1704612D01*
X102617Y1704095D01*
X102272Y1703734D01*
X102042Y1703217D01*
X101965Y1702752D01*
X103575D01*
G01X105027Y1703217D02*
X105257Y1702959D01*
X105525Y1702804D01*
X105870Y1702752D01*
X106215Y1702855D01*
X106483Y1703062D01*
X106675Y1703424D01*
X106713Y1703837D01*
X106637Y1704250D01*
X106445Y1704509D01*
X106177Y1704715D01*
X105908Y1704767D01*
X105640Y1704715D01*
X105295Y1704509D01*
X105410Y1705852D01*
X106445D01*
G01X108242Y1704044D02*
X108510Y1704405D01*
X108740Y1704612D01*
X109047Y1704715D01*
X109315Y1704612D01*
X109507Y1704405D01*
X109660Y1704095D01*
X109698Y1703734D01*
X109660Y1703424D01*
X109507Y1703114D01*
X109277Y1702855D01*
X109008Y1702752D01*
X108702Y1702855D01*
X108433Y1703165D01*
X108280Y1703630D01*
X108242Y1704147D01*
X108318Y1704819D01*
X108433Y1705180D01*
X108625Y1705542D01*
X108893Y1705800D01*
X109162Y1705852D01*
X109430Y1705749D01*
X109622Y1705490D01*
G01X108858Y1700693D02*
X111520D01*
G01X100920D02*
X103582D01*
G01X125700Y51139D02*
X121870D01*
G01X118010D02*
X113450D01*
G01X123110Y79632D02*
X130110D01*
G01X123110D02*
Y126632D01*
G01X116110Y79632D02*
Y126632D01*
G01Y79632D02*
X123110D01*
G01X113610Y81345D02*
X111110D01*
Y81879D01*
X111235Y82092D01*
X111402Y82252D01*
X111652Y82385D01*
X111943Y82492D01*
X112360Y82519D01*
X112777Y82492D01*
X113068Y82385D01*
X113318Y82252D01*
X113485Y82092D01*
X113610Y81879D01*
Y81345D01*
G01Y84079D02*
X113068Y84132D01*
X112610Y84212D01*
X112193Y84319D01*
X111735Y84452D01*
X111110Y84665D01*
Y83599D01*
G01X113610Y86332D02*
X111110D01*
X111610Y86012D01*
G01X113610D02*
Y86652D01*
G01X120610Y81345D02*
X118110D01*
Y81879D01*
X118235Y82092D01*
X118402Y82252D01*
X118652Y82385D01*
X118943Y82492D01*
X119360Y82519D01*
X119777Y82492D01*
X120068Y82385D01*
X120318Y82252D01*
X120485Y82092D01*
X120610Y81879D01*
Y81345D01*
G01Y84079D02*
X120068Y84132D01*
X119610Y84212D01*
X119193Y84319D01*
X118735Y84452D01*
X118110Y84665D01*
Y83599D01*
G01Y86332D02*
X118193Y86119D01*
X118402Y85959D01*
X118652Y85852D01*
X118985Y85772D01*
X119360Y85745D01*
X119735Y85772D01*
X120068Y85852D01*
X120318Y85959D01*
X120527Y86119D01*
X120610Y86332D01*
X120527Y86545D01*
X120318Y86705D01*
X120068Y86812D01*
X119735Y86892D01*
X119360Y86919D01*
X118985Y86892D01*
X118652Y86812D01*
X118402Y86705D01*
X118193Y86545D01*
X118110Y86332D01*
G01X127610Y81345D02*
X125110D01*
Y81879D01*
X125235Y82092D01*
X125402Y82252D01*
X125652Y82385D01*
X125943Y82492D01*
X126360Y82519D01*
X126777Y82492D01*
X127068Y82385D01*
X127318Y82252D01*
X127485Y82092D01*
X127610Y81879D01*
Y81345D01*
G01X126568Y83625D02*
X126277Y83812D01*
X126110Y83972D01*
X126027Y84185D01*
X126110Y84372D01*
X126277Y84505D01*
X126527Y84612D01*
X126818Y84639D01*
X127068Y84612D01*
X127318Y84505D01*
X127527Y84345D01*
X127610Y84159D01*
X127527Y83945D01*
X127277Y83759D01*
X126902Y83652D01*
X126485Y83625D01*
X125943Y83679D01*
X125652Y83759D01*
X125360Y83892D01*
X125152Y84079D01*
X125110Y84265D01*
X125193Y84452D01*
X125402Y84585D01*
G01X127318Y85879D02*
X127527Y86065D01*
X127610Y86279D01*
X127527Y86492D01*
X127277Y86679D01*
X126902Y86812D01*
X126527Y86865D01*
X126068D01*
X125693Y86812D01*
X125360Y86679D01*
X125193Y86519D01*
X125110Y86332D01*
X125193Y86119D01*
X125360Y85959D01*
X125610Y85852D01*
X125943Y85799D01*
X126235Y85852D01*
X126527Y85985D01*
X126693Y86145D01*
X126735Y86332D01*
X126652Y86545D01*
X126443Y86705D01*
X126068Y86865D01*
G01X127610Y90399D02*
X125110D01*
Y91065D01*
X125235Y91279D01*
X125402Y91412D01*
X125735Y91465D01*
X126068Y91412D01*
X126277Y91252D01*
X126402Y91065D01*
Y90399D01*
G01Y91065D02*
X127610Y91465D01*
G01X127277Y92572D02*
X127485Y92785D01*
X127610Y93025D01*
Y93239D01*
X127485Y93452D01*
X127277Y93612D01*
X126985Y93692D01*
X126693Y93639D01*
X126443Y93505D01*
X126277Y93265D01*
X126193Y92945D01*
X126027Y92759D01*
X125735Y92679D01*
X125443Y92732D01*
X125235Y92865D01*
X125110Y93052D01*
Y93239D01*
X125193Y93425D01*
X125402Y93585D01*
G01X125110Y95332D02*
X127610D01*
G01X125110Y94719D02*
Y95945D01*
G01X128443Y96732D02*
Y98332D01*
G01X125318Y100319D02*
X125193Y100159D01*
X125110Y99972D01*
Y99759D01*
X125235Y99519D01*
X125443Y99332D01*
X125693Y99199D01*
X126110Y99092D01*
X126485Y99065D01*
X126860Y99119D01*
X127110Y99199D01*
X127360Y99359D01*
X127527Y99545D01*
X127610Y99732D01*
Y99919D01*
X127527Y100105D01*
X127402Y100265D01*
X127235Y100399D01*
G01X127610Y101399D02*
X125110D01*
Y102039D01*
X125235Y102252D01*
X125527Y102412D01*
X125860Y102465D01*
X126193Y102412D01*
X126443Y102279D01*
X126568Y102039D01*
Y101399D01*
G01X125110Y103545D02*
X126902D01*
X127277Y103652D01*
X127527Y103865D01*
X127610Y104132D01*
X127527Y104399D01*
X127277Y104612D01*
X126902Y104719D01*
X125110D01*
G01X127610Y106332D02*
X125110D01*
X125610Y106012D01*
G01X127610D02*
Y106652D01*
G01X128443Y107732D02*
Y109332D01*
G01X127610Y110145D02*
X125110D01*
Y110679D01*
X125235Y110892D01*
X125402Y111052D01*
X125652Y111185D01*
X125943Y111292D01*
X126360Y111319D01*
X126777Y111292D01*
X127068Y111185D01*
X127318Y111052D01*
X127485Y110892D01*
X127610Y110679D01*
Y110145D01*
G01Y112399D02*
X125110D01*
Y113065D01*
X125235Y113279D01*
X125402Y113412D01*
X125735Y113465D01*
X126068Y113412D01*
X126277Y113252D01*
X126402Y113065D01*
Y112399D01*
G01Y113065D02*
X127610Y113465D01*
G01Y114465D02*
X125110Y115132D01*
X127610Y115799D01*
G01X126735Y115559D02*
Y114705D01*
G01X127610Y116639D02*
X125110D01*
X127193Y117332D01*
X125110Y118025D01*
X127610D01*
G01X128443Y118732D02*
Y120332D01*
G01X127610Y121065D02*
X125110Y121732D01*
X127610Y122399D01*
G01X126735Y122159D02*
Y121305D01*
G01X126277Y124145D02*
X126152Y124252D01*
X125943Y124332D01*
X125652Y124385D01*
X125402Y124332D01*
X125235Y124225D01*
X125110Y124039D01*
Y123319D01*
X127610D01*
Y124199D01*
X127443Y124385D01*
X127193Y124492D01*
X126902Y124545D01*
X126610Y124492D01*
X126360Y124332D01*
X126277Y124145D01*
Y123319D01*
G01X120610Y90899D02*
X118110D01*
Y91565D01*
X118235Y91779D01*
X118402Y91912D01*
X118735Y91965D01*
X119068Y91912D01*
X119277Y91752D01*
X119402Y91565D01*
Y90899D01*
G01Y91565D02*
X120610Y91965D01*
G01X120277Y93072D02*
X120485Y93285D01*
X120610Y93525D01*
Y93739D01*
X120485Y93952D01*
X120277Y94112D01*
X119985Y94192D01*
X119693Y94139D01*
X119443Y94005D01*
X119277Y93765D01*
X119193Y93445D01*
X119027Y93259D01*
X118735Y93179D01*
X118443Y93232D01*
X118235Y93365D01*
X118110Y93552D01*
Y93739D01*
X118193Y93925D01*
X118402Y94085D01*
G01X118110Y95832D02*
X120610D01*
G01X118110Y95219D02*
Y96445D01*
G01X121443Y97232D02*
Y98832D01*
G01X118318Y100819D02*
X118193Y100659D01*
X118110Y100472D01*
Y100259D01*
X118235Y100019D01*
X118443Y99832D01*
X118693Y99699D01*
X119110Y99592D01*
X119485Y99565D01*
X119860Y99619D01*
X120110Y99699D01*
X120360Y99859D01*
X120527Y100045D01*
X120610Y100232D01*
Y100419D01*
X120527Y100605D01*
X120402Y100765D01*
X120235Y100899D01*
G01X120610Y101899D02*
X118110D01*
Y102539D01*
X118235Y102752D01*
X118527Y102912D01*
X118860Y102965D01*
X119193Y102912D01*
X119443Y102779D01*
X119568Y102539D01*
Y101899D01*
G01X118110Y104045D02*
X119902D01*
X120277Y104152D01*
X120527Y104365D01*
X120610Y104632D01*
X120527Y104899D01*
X120277Y105112D01*
X119902Y105219D01*
X118110D01*
G01X120610Y106832D02*
X118110D01*
X118610Y106512D01*
G01X120610D02*
Y107152D01*
G01X121443Y108232D02*
Y109832D01*
G01X120610Y110645D02*
X118110D01*
Y111179D01*
X118235Y111392D01*
X118402Y111552D01*
X118652Y111685D01*
X118943Y111792D01*
X119360Y111819D01*
X119777Y111792D01*
X120068Y111685D01*
X120318Y111552D01*
X120485Y111392D01*
X120610Y111179D01*
Y110645D01*
G01Y112899D02*
X118110D01*
Y113565D01*
X118235Y113779D01*
X118402Y113912D01*
X118735Y113965D01*
X119068Y113912D01*
X119277Y113752D01*
X119402Y113565D01*
Y112899D01*
G01Y113565D02*
X120610Y113965D01*
G01Y114965D02*
X118110Y115632D01*
X120610Y116299D01*
G01X119735Y116059D02*
Y115205D01*
G01X120610Y117139D02*
X118110D01*
X120193Y117832D01*
X118110Y118525D01*
X120610D01*
G01X121443Y119232D02*
Y120832D01*
G01X118318Y122819D02*
X118193Y122659D01*
X118110Y122472D01*
Y122259D01*
X118235Y122019D01*
X118443Y121832D01*
X118693Y121699D01*
X119110Y121592D01*
X119485Y121565D01*
X119860Y121619D01*
X120110Y121699D01*
X120360Y121859D01*
X120527Y122045D01*
X120610Y122232D01*
Y122419D01*
X120527Y122605D01*
X120402Y122765D01*
X120235Y122899D01*
G01X120610Y123845D02*
X118110D01*
Y124379D01*
X118235Y124592D01*
X118402Y124752D01*
X118652Y124885D01*
X118943Y124992D01*
X119360Y125019D01*
X119777Y124992D01*
X120068Y124885D01*
X120318Y124752D01*
X120485Y124592D01*
X120610Y124379D01*
Y123845D01*
G01X113610Y90899D02*
X111110D01*
Y91565D01*
X111235Y91779D01*
X111402Y91912D01*
X111735Y91965D01*
X112068Y91912D01*
X112277Y91752D01*
X112402Y91565D01*
Y90899D01*
G01Y91565D02*
X113610Y91965D01*
G01X113277Y93072D02*
X113485Y93285D01*
X113610Y93525D01*
Y93739D01*
X113485Y93952D01*
X113277Y94112D01*
X112985Y94192D01*
X112693Y94139D01*
X112443Y94005D01*
X112277Y93765D01*
X112193Y93445D01*
X112027Y93259D01*
X111735Y93179D01*
X111443Y93232D01*
X111235Y93365D01*
X111110Y93552D01*
Y93739D01*
X111193Y93925D01*
X111402Y94085D01*
G01X111110Y95832D02*
X113610D01*
G01X111110Y95219D02*
Y96445D01*
G01X114443Y97232D02*
Y98832D01*
G01X111318Y100819D02*
X111193Y100659D01*
X111110Y100472D01*
Y100259D01*
X111235Y100019D01*
X111443Y99832D01*
X111693Y99699D01*
X112110Y99592D01*
X112485Y99565D01*
X112860Y99619D01*
X113110Y99699D01*
X113360Y99859D01*
X113527Y100045D01*
X113610Y100232D01*
Y100419D01*
X113527Y100605D01*
X113402Y100765D01*
X113235Y100899D01*
G01X113610Y101899D02*
X111110D01*
Y102539D01*
X111235Y102752D01*
X111527Y102912D01*
X111860Y102965D01*
X112193Y102912D01*
X112443Y102779D01*
X112568Y102539D01*
Y101899D01*
G01X111110Y104045D02*
X112902D01*
X113277Y104152D01*
X113527Y104365D01*
X113610Y104632D01*
X113527Y104899D01*
X113277Y105112D01*
X112902Y105219D01*
X111110D01*
G01X113610Y106832D02*
X111110D01*
X111610Y106512D01*
G01X113610D02*
Y107152D01*
G01X114443Y108232D02*
Y109832D01*
G01X113610Y110645D02*
X111110D01*
Y111179D01*
X111235Y111392D01*
X111402Y111552D01*
X111652Y111685D01*
X111943Y111792D01*
X112360Y111819D01*
X112777Y111792D01*
X113068Y111685D01*
X113318Y111552D01*
X113485Y111392D01*
X113610Y111179D01*
Y110645D01*
G01Y112899D02*
X111110D01*
Y113565D01*
X111235Y113779D01*
X111402Y113912D01*
X111735Y113965D01*
X112068Y113912D01*
X112277Y113752D01*
X112402Y113565D01*
Y112899D01*
G01Y113565D02*
X113610Y113965D01*
G01Y114965D02*
X111110Y115632D01*
X113610Y116299D01*
G01X112735Y116059D02*
Y115205D01*
G01X113610Y117139D02*
X111110D01*
X113193Y117832D01*
X111110Y118525D01*
X113610D01*
G01X114443Y119232D02*
Y120832D01*
G01X113610Y122765D02*
Y121699D01*
X111110D01*
Y122765D01*
G01X112318Y122339D02*
Y121699D01*
G01X113610Y123925D02*
X111110D01*
Y124939D01*
G01X112318Y124565D02*
Y123925D01*
G01X120610Y127899D02*
X118110D01*
Y128539D01*
X118235Y128752D01*
X118527Y128912D01*
X118860Y128965D01*
X119193Y128912D01*
X119443Y128779D01*
X119568Y128539D01*
Y127899D01*
G01X118110Y129965D02*
X120610Y130632D01*
X118110Y131299D01*
G01X118318Y133419D02*
X118193Y133259D01*
X118110Y133072D01*
Y132859D01*
X118235Y132619D01*
X118443Y132432D01*
X118693Y132299D01*
X119110Y132192D01*
X119485Y132165D01*
X119860Y132219D01*
X120110Y132299D01*
X120360Y132459D01*
X120527Y132645D01*
X120610Y132832D01*
Y133019D01*
X120527Y133205D01*
X120402Y133365D01*
X120235Y133499D01*
G01X118318Y135619D02*
X118193Y135459D01*
X118110Y135272D01*
Y135059D01*
X118235Y134819D01*
X118443Y134632D01*
X118693Y134499D01*
X119110Y134392D01*
X119485Y134365D01*
X119860Y134419D01*
X120110Y134499D01*
X120360Y134659D01*
X120527Y134845D01*
X120610Y135032D01*
Y135219D01*
X120527Y135405D01*
X120402Y135565D01*
X120235Y135699D01*
G01X120610Y136725D02*
X118110D01*
Y137739D01*
G01X119318Y137365D02*
Y136725D01*
G01X120610Y138765D02*
X118110Y139432D01*
X120610Y140099D01*
G01X119735Y139859D02*
Y139005D01*
G01X121443Y140832D02*
Y142432D01*
G01X120610Y144365D02*
Y143299D01*
X118110D01*
Y144365D01*
G01X119318Y143939D02*
Y143299D01*
G01X120610Y145472D02*
X118110D01*
G01Y146592D02*
X120610D01*
G01X119360D02*
Y145472D01*
G01X118110Y147565D02*
X120610Y148232D01*
X118110Y148899D01*
G01X121443Y149632D02*
Y151232D01*
G01X120610Y152125D02*
X118110D01*
Y153139D01*
G01X119318Y152765D02*
Y152125D01*
G01X118110Y154512D02*
Y155152D01*
G01Y154832D02*
X120610D01*
G01Y154512D02*
Y155152D01*
G01X118110Y156365D02*
X120610Y157032D01*
X118110Y157699D01*
G01X120610Y158699D02*
X118110D01*
Y159365D01*
X118235Y159579D01*
X118402Y159712D01*
X118735Y159765D01*
X119068Y159712D01*
X119277Y159552D01*
X119402Y159365D01*
Y158699D01*
G01Y159365D02*
X120610Y159765D01*
G01Y160765D02*
X118110Y161432D01*
X120610Y162099D01*
G01X119735Y161859D02*
Y161005D01*
G01X121443Y162832D02*
Y164432D01*
G01X118318Y166419D02*
X118193Y166259D01*
X118110Y166072D01*
Y165859D01*
X118235Y165619D01*
X118443Y165432D01*
X118693Y165299D01*
X119110Y165192D01*
X119485Y165165D01*
X119860Y165219D01*
X120110Y165299D01*
X120360Y165459D01*
X120527Y165645D01*
X120610Y165832D01*
Y166019D01*
X120527Y166205D01*
X120402Y166365D01*
X120235Y166499D01*
G01X120610Y167499D02*
X118110D01*
Y168139D01*
X118235Y168352D01*
X118527Y168512D01*
X118860Y168565D01*
X119193Y168512D01*
X119443Y168379D01*
X119568Y168139D01*
Y167499D01*
G01X118110Y169645D02*
X119902D01*
X120277Y169752D01*
X120527Y169965D01*
X120610Y170232D01*
X120527Y170499D01*
X120277Y170712D01*
X119902Y170819D01*
X118110D01*
G01Y172432D02*
X118193Y172219D01*
X118402Y172059D01*
X118652Y171952D01*
X118985Y171872D01*
X119360Y171845D01*
X119735Y171872D01*
X120068Y171952D01*
X120318Y172059D01*
X120527Y172219D01*
X120610Y172432D01*
X120527Y172645D01*
X120318Y172805D01*
X120068Y172912D01*
X119735Y172992D01*
X119360Y173019D01*
X118985Y172992D01*
X118652Y172912D01*
X118402Y172805D01*
X118193Y172645D01*
X118110Y172432D01*
G01X113610Y127899D02*
X111110D01*
Y128539D01*
X111235Y128752D01*
X111527Y128912D01*
X111860Y128965D01*
X112193Y128912D01*
X112443Y128779D01*
X112568Y128539D01*
Y127899D01*
G01X111110Y129965D02*
X113610Y130632D01*
X111110Y131299D01*
G01X111318Y133419D02*
X111193Y133259D01*
X111110Y133072D01*
Y132859D01*
X111235Y132619D01*
X111443Y132432D01*
X111693Y132299D01*
X112110Y132192D01*
X112485Y132165D01*
X112860Y132219D01*
X113110Y132299D01*
X113360Y132459D01*
X113527Y132645D01*
X113610Y132832D01*
Y133019D01*
X113527Y133205D01*
X113402Y133365D01*
X113235Y133499D01*
G01X111318Y135619D02*
X111193Y135459D01*
X111110Y135272D01*
Y135059D01*
X111235Y134819D01*
X111443Y134632D01*
X111693Y134499D01*
X112110Y134392D01*
X112485Y134365D01*
X112860Y134419D01*
X113110Y134499D01*
X113360Y134659D01*
X113527Y134845D01*
X113610Y135032D01*
Y135219D01*
X113527Y135405D01*
X113402Y135565D01*
X113235Y135699D01*
G01X113610Y136725D02*
X111110D01*
Y137739D01*
G01X112318Y137365D02*
Y136725D01*
G01X113610Y138765D02*
X111110Y139432D01*
X113610Y140099D01*
G01X112735Y139859D02*
Y139005D01*
G01X114443Y140832D02*
Y142432D01*
G01X113610Y144365D02*
Y143299D01*
X111110D01*
Y144365D01*
G01X112318Y143939D02*
Y143299D01*
G01X113610Y145472D02*
X111110D01*
G01Y146592D02*
X113610D01*
G01X112360D02*
Y145472D01*
G01X111110Y147565D02*
X113610Y148232D01*
X111110Y148899D01*
G01X114443Y149632D02*
Y151232D01*
G01X113610Y152125D02*
X111110D01*
Y153139D01*
G01X112318Y152765D02*
Y152125D01*
G01X111110Y154512D02*
Y155152D01*
G01Y154832D02*
X113610D01*
G01Y154512D02*
Y155152D01*
G01X111110Y156365D02*
X113610Y157032D01*
X111110Y157699D01*
G01X113610Y158699D02*
X111110D01*
Y159365D01*
X111235Y159579D01*
X111402Y159712D01*
X111735Y159765D01*
X112068Y159712D01*
X112277Y159552D01*
X112402Y159365D01*
Y158699D01*
G01Y159365D02*
X113610Y159765D01*
G01Y160765D02*
X111110Y161432D01*
X113610Y162099D01*
G01X112735Y161859D02*
Y161005D01*
G01X114443Y162832D02*
Y164432D01*
G01X111318Y166419D02*
X111193Y166259D01*
X111110Y166072D01*
Y165859D01*
X111235Y165619D01*
X111443Y165432D01*
X111693Y165299D01*
X112110Y165192D01*
X112485Y165165D01*
X112860Y165219D01*
X113110Y165299D01*
X113360Y165459D01*
X113527Y165645D01*
X113610Y165832D01*
Y166019D01*
X113527Y166205D01*
X113402Y166365D01*
X113235Y166499D01*
G01X113610Y167499D02*
X111110D01*
Y168139D01*
X111235Y168352D01*
X111527Y168512D01*
X111860Y168565D01*
X112193Y168512D01*
X112443Y168379D01*
X112568Y168139D01*
Y167499D01*
G01X111110Y169645D02*
X112902D01*
X113277Y169752D01*
X113527Y169965D01*
X113610Y170232D01*
X113527Y170499D01*
X113277Y170712D01*
X112902Y170819D01*
X111110D01*
G01X113610Y172432D02*
X111110D01*
X111610Y172112D01*
G01X113610D02*
Y172752D01*
G01X130110Y126632D02*
X123110D01*
G01Y183632D02*
Y126632D01*
G01X116110D02*
X123110D01*
G01X116110D02*
Y183632D01*
G01X127610Y141399D02*
X125110D01*
Y142039D01*
X125235Y142252D01*
X125527Y142412D01*
X125860Y142465D01*
X126193Y142412D01*
X126443Y142279D01*
X126568Y142039D01*
Y141399D01*
G01X125110Y143465D02*
X127610Y144132D01*
X125110Y144799D01*
G01X125318Y146919D02*
X125193Y146759D01*
X125110Y146572D01*
Y146359D01*
X125235Y146119D01*
X125443Y145932D01*
X125693Y145799D01*
X126110Y145692D01*
X126485Y145665D01*
X126860Y145719D01*
X127110Y145799D01*
X127360Y145959D01*
X127527Y146145D01*
X127610Y146332D01*
Y146519D01*
X127527Y146705D01*
X127402Y146865D01*
X127235Y146999D01*
G01X125318Y149119D02*
X125193Y148959D01*
X125110Y148772D01*
Y148559D01*
X125235Y148319D01*
X125443Y148132D01*
X125693Y147999D01*
X126110Y147892D01*
X126485Y147865D01*
X126860Y147919D01*
X127110Y147999D01*
X127360Y148159D01*
X127527Y148345D01*
X127610Y148532D01*
Y148719D01*
X127527Y148905D01*
X127402Y149065D01*
X127235Y149199D01*
G01X127610Y150225D02*
X125110D01*
Y151239D01*
G01X126318Y150865D02*
Y150225D01*
G01X127610Y152265D02*
X125110Y152932D01*
X127610Y153599D01*
G01X126735Y153359D02*
Y152505D01*
G01X128443Y154332D02*
Y155932D01*
G01X127610Y157865D02*
Y156799D01*
X125110D01*
Y157865D01*
G01X126318Y157439D02*
Y156799D01*
G01X127610Y158972D02*
X125110D01*
G01Y160092D02*
X127610D01*
G01X126360D02*
Y158972D01*
G01X125110Y161065D02*
X127610Y161732D01*
X125110Y162399D01*
G01X128443Y163132D02*
Y164732D01*
G01X125318Y166719D02*
X125193Y166559D01*
X125110Y166372D01*
Y166159D01*
X125235Y165919D01*
X125443Y165732D01*
X125693Y165599D01*
X126110Y165492D01*
X126485Y165465D01*
X126860Y165519D01*
X127110Y165599D01*
X127360Y165759D01*
X127527Y165945D01*
X127610Y166132D01*
Y166319D01*
X127527Y166505D01*
X127402Y166665D01*
X127235Y166799D01*
G01X127610Y167799D02*
X125110D01*
Y168439D01*
X125235Y168652D01*
X125527Y168812D01*
X125860Y168865D01*
X126193Y168812D01*
X126443Y168679D01*
X126568Y168439D01*
Y167799D01*
G01X125110Y169945D02*
X126902D01*
X127277Y170052D01*
X127527Y170265D01*
X127610Y170532D01*
X127527Y170799D01*
X127277Y171012D01*
X126902Y171119D01*
X125110D01*
G01X127610Y172732D02*
X125110D01*
X125610Y172412D01*
G01X127610D02*
Y173052D01*
G01X123110Y183632D02*
X130110D01*
G01X116110D02*
X123110D01*
G01X127404Y176384D02*
X124904D01*
Y176918D01*
X125029Y177131D01*
X125196Y177291D01*
X125446Y177424D01*
X125737Y177531D01*
X126154Y177558D01*
X126571Y177531D01*
X126862Y177424D01*
X127112Y177291D01*
X127279Y177131D01*
X127404Y176918D01*
Y176384D01*
G01Y179171D02*
X127362Y179358D01*
X127237Y179571D01*
X127029Y179704D01*
X126737Y179758D01*
X126446Y179704D01*
X126196Y179544D01*
X126071Y179304D01*
Y179038D01*
X125987Y178878D01*
X125779Y178744D01*
X125487Y178691D01*
X125196Y178771D01*
X124987Y178958D01*
X124904Y179171D01*
X124987Y179384D01*
X125196Y179571D01*
X125487Y179651D01*
X125779Y179598D01*
X125987Y179464D01*
X126071Y179304D01*
Y179038D01*
X126196Y178798D01*
X126446Y178638D01*
X126737Y178584D01*
X127029Y178638D01*
X127237Y178771D01*
X127362Y178984D01*
X127404Y179171D01*
G01X125321Y180864D02*
X125071Y181024D01*
X124946Y181211D01*
X124904Y181424D01*
X124987Y181691D01*
X125196Y181878D01*
X125446Y181931D01*
X125696Y181904D01*
X125904Y181798D01*
X126321Y181264D01*
X126612Y181024D01*
X127029Y180864D01*
X127404Y180811D01*
Y181931D01*
G01X113610Y176345D02*
X111110D01*
Y176879D01*
X111235Y177092D01*
X111402Y177252D01*
X111652Y177385D01*
X111943Y177492D01*
X112360Y177519D01*
X112777Y177492D01*
X113068Y177385D01*
X113318Y177252D01*
X113485Y177092D01*
X113610Y176879D01*
Y176345D01*
G01Y179132D02*
X113568Y179319D01*
X113443Y179532D01*
X113235Y179665D01*
X112943Y179719D01*
X112652Y179665D01*
X112402Y179505D01*
X112277Y179265D01*
Y178999D01*
X112193Y178839D01*
X111985Y178705D01*
X111693Y178652D01*
X111402Y178732D01*
X111193Y178919D01*
X111110Y179132D01*
X111193Y179345D01*
X111402Y179532D01*
X111693Y179612D01*
X111985Y179559D01*
X112193Y179425D01*
X112277Y179265D01*
Y178999D01*
X112402Y178759D01*
X112652Y178599D01*
X112943Y178545D01*
X113235Y178599D01*
X113443Y178732D01*
X113568Y178945D01*
X113610Y179132D01*
G01X113110Y180745D02*
X113402Y180905D01*
X113568Y181119D01*
X113610Y181359D01*
X113568Y181572D01*
X113360Y181785D01*
X113110Y181919D01*
X112860Y181945D01*
X112568Y181892D01*
X112360Y181705D01*
X112277Y181519D01*
Y181279D01*
G01Y181519D02*
X112152Y181679D01*
X111943Y181812D01*
X111693Y181865D01*
X111443Y181812D01*
X111235Y181679D01*
X111110Y181439D01*
X111152Y181199D01*
X111318Y180959D01*
G01X120610Y176345D02*
X118110D01*
Y176879D01*
X118235Y177092D01*
X118402Y177252D01*
X118652Y177385D01*
X118943Y177492D01*
X119360Y177519D01*
X119777Y177492D01*
X120068Y177385D01*
X120318Y177252D01*
X120485Y177092D01*
X120610Y176879D01*
Y176345D01*
G01Y179079D02*
X120068Y179132D01*
X119610Y179212D01*
X119193Y179319D01*
X118735Y179452D01*
X118110Y179665D01*
Y178599D01*
G01X119568Y180825D02*
X119277Y181012D01*
X119110Y181172D01*
X119027Y181385D01*
X119110Y181572D01*
X119277Y181705D01*
X119527Y181812D01*
X119818Y181839D01*
X120068Y181812D01*
X120318Y181705D01*
X120527Y181545D01*
X120610Y181359D01*
X120527Y181145D01*
X120277Y180959D01*
X119902Y180852D01*
X119485Y180825D01*
X118943Y180879D01*
X118652Y180959D01*
X118360Y181092D01*
X118152Y181279D01*
X118110Y181465D01*
X118193Y181652D01*
X118402Y181785D01*
G01X113675Y187962D02*
Y184762D01*
G01X226400Y266102D02*
Y222442D01*
X119780D01*
Y185190D01*
G01D02*
X122780Y188190D01*
G01D02*
X116780D01*
G01D02*
X119780Y185190D01*
G01X125269Y202094D02*
X126016Y201469D01*
X126856Y201094D01*
X127602D01*
X128349Y201469D01*
X128909Y202094D01*
X129189Y202969D01*
X129002Y203844D01*
X128536Y204594D01*
X127696Y205094D01*
X126576Y205344D01*
X125922Y205844D01*
X125642Y206719D01*
X125829Y207594D01*
X126296Y208219D01*
X126949Y208594D01*
X127602D01*
X128256Y208344D01*
X128816Y207719D01*
G01X133049Y200844D02*
X136409Y208594D01*
G01X140082Y201094D02*
Y208594D01*
X144376Y201094D01*
Y208594D01*
G01X124029Y192557D02*
Y186557D01*
G01D02*
X130029D01*
G01X112615Y218196D02*
Y214996D01*
G01X130029Y210179D02*
X124029D01*
Y204179D01*
G01X112525Y233728D02*
Y230528D01*
G01X115612Y284595D02*
Y281395D01*
G01X122319Y280475D02*
X128519D01*
G01X122319Y277275D02*
Y280475D01*
G01X128519Y277275D02*
X122319D01*
G01X115612Y280475D02*
Y277275D01*
G01X128500Y273200D02*
X122300D01*
Y276400D01*
X128500D01*
Y273200D01*
G01X115612Y301954D02*
Y298754D01*
G01X122319Y307836D02*
X128519D01*
G01X122319Y304636D02*
Y307836D01*
G01X128519Y304636D02*
X122319D01*
G01X115612Y307836D02*
Y304636D01*
G01X118582Y386471D02*
X112382D01*
Y389671D01*
X118582D01*
Y386471D01*
G01Y390471D02*
X112382D01*
Y393671D01*
X118582D01*
Y390471D01*
G01X125882Y394471D02*
Y397671D01*
G01X132082Y394471D02*
X125882D01*
G01Y389671D02*
X132082D01*
G01X125882Y386471D02*
Y389671D01*
G01X132082Y386471D02*
X125882D01*
G01Y393671D02*
X132082D01*
G01X125882Y390471D02*
Y393671D01*
G01X132082Y390471D02*
X125882D01*
G01Y385671D02*
X132082D01*
G01X125882Y382471D02*
Y385671D01*
G01X132082Y382471D02*
X125882D01*
G01X112482Y408071D02*
Y402071D01*
G01X125882Y397671D02*
X132082D01*
G01X121582Y406171D02*
Y402971D01*
G01X115382Y406171D02*
X121582D01*
G01X115382Y402971D02*
Y406171D01*
G01X121582Y402971D02*
X115382D01*
G01X125882D02*
Y406171D01*
G01X132082Y402971D02*
X125882D01*
G01Y406171D02*
X132082D01*
G01X124349Y420408D02*
Y440486D01*
G01X121030D02*
X116991Y436447D01*
G01X124349Y440486D02*
X121030D01*
G01X116991Y436447D02*
X112952Y440486D01*
G01X115997Y489791D02*
Y495991D01*
G01X119197Y489791D02*
X115997D01*
G01X119197Y495991D02*
Y489791D01*
G01X111997D02*
Y495991D01*
G01X115197Y489791D02*
X111997D01*
G01X115197Y495991D02*
Y489791D01*
G01X125770Y478713D02*
X122570D01*
G01X125770Y484913D02*
Y478713D01*
G01X122570Y484913D02*
X125770D01*
G01X122570Y478713D02*
Y484913D01*
G01X121660Y478713D02*
X118460D01*
G01X121660Y484913D02*
Y478713D01*
G01X118460Y484913D02*
X121660D01*
G01X118460Y478713D02*
Y484913D01*
G01X115997Y495991D02*
X119197D01*
G01X111997D02*
X115197D01*
G01X112470Y498912D02*
Y501412D01*
X111483Y499620D01*
X112817D01*
G01X114350Y501412D02*
X114137Y501329D01*
X113977Y501120D01*
X113870Y500870D01*
X113790Y500537D01*
X113763Y500162D01*
X113790Y499787D01*
X113870Y499454D01*
X113977Y499204D01*
X114137Y498995D01*
X114350Y498912D01*
X114563Y498995D01*
X114723Y499204D01*
X114830Y499454D01*
X114910Y499787D01*
X114937Y500162D01*
X114910Y500537D01*
X114830Y500870D01*
X114723Y501120D01*
X114563Y501329D01*
X114350Y501412D01*
G01X118288Y500525D02*
X116382D01*
G01X114925Y503268D02*
X111925D01*
G01X116382Y500525D02*
Y502431D01*
G01X125525Y497518D02*
Y499018D01*
G01X117414Y525385D02*
Y522185D01*
G01X111214D02*
Y525385D01*
G01X117414Y522185D02*
X111214D01*
G01Y525385D02*
X117414D01*
G01X120913Y524992D02*
X121073Y524700D01*
X121287Y524534D01*
X121527Y524492D01*
X121740Y524534D01*
X121953Y524742D01*
X122087Y524992D01*
X122113Y525242D01*
X122060Y525534D01*
X121873Y525742D01*
X121687Y525825D01*
X121447D01*
G01X121687D02*
X121847Y525950D01*
X121980Y526159D01*
X122033Y526409D01*
X121980Y526659D01*
X121847Y526867D01*
X121607Y526992D01*
X121367Y526950D01*
X121127Y526784D01*
G01X123700Y526992D02*
X123487Y526909D01*
X123327Y526700D01*
X123220Y526450D01*
X123140Y526117D01*
X123113Y525742D01*
X123140Y525367D01*
X123220Y525034D01*
X123327Y524784D01*
X123487Y524575D01*
X123700Y524492D01*
X123913Y524575D01*
X124073Y524784D01*
X124180Y525034D01*
X124260Y525367D01*
X124287Y525742D01*
X124260Y526117D01*
X124180Y526450D01*
X124073Y526700D01*
X123913Y526909D01*
X123700Y526992D01*
G01X116382Y520211D02*
X118288D01*
G01X116382Y518305D02*
Y520211D01*
G01X119225Y521668D02*
Y524668D01*
G01X113475Y511068D02*
X114975D01*
G01X125783Y530285D02*
X125943Y530535D01*
X126130Y530660D01*
X126343Y530702D01*
X126610Y530619D01*
X126797Y530410D01*
X126850Y530160D01*
X126823Y529910D01*
X126717Y529702D01*
X126183Y529285D01*
X125943Y528994D01*
X125783Y528577D01*
X125730Y528202D01*
X126850D01*
G01X128490D02*
Y530702D01*
X128170Y530202D01*
G01Y528202D02*
X128810D01*
G01X113460Y540122D02*
Y546322D01*
G01X116660D02*
Y540122D01*
G01D02*
X113460D01*
G01X125777Y540355D02*
Y546555D01*
G01X128977Y540355D02*
X125777D01*
G01X121657Y540285D02*
Y546485D01*
G01X124857D02*
Y540285D01*
G01D02*
X121657D01*
G01X117487Y540195D02*
Y546395D01*
G01X120687D02*
Y540195D01*
G01D02*
X117487D01*
G01X112587Y546315D02*
Y540115D01*
G01X113460Y546322D02*
X116660D01*
G01X125777Y546555D02*
X128977D01*
G01X121657Y546485D02*
X124857D01*
G01X117487Y546395D02*
X120687D01*
G01X115133Y630662D02*
X115293Y630370D01*
X115507Y630204D01*
X115747Y630162D01*
X115960Y630204D01*
X116173Y630412D01*
X116307Y630662D01*
X116333Y630912D01*
X116280Y631204D01*
X116093Y631412D01*
X115907Y631495D01*
X115667D01*
G01X115907D02*
X116067Y631620D01*
X116200Y631829D01*
X116253Y632079D01*
X116200Y632329D01*
X116067Y632537D01*
X115827Y632662D01*
X115587Y632620D01*
X115347Y632454D01*
G01X117920Y632662D02*
X117707Y632579D01*
X117547Y632370D01*
X117440Y632120D01*
X117360Y631787D01*
X117333Y631412D01*
X117360Y631037D01*
X117440Y630704D01*
X117547Y630454D01*
X117707Y630245D01*
X117920Y630162D01*
X118133Y630245D01*
X118293Y630454D01*
X118400Y630704D01*
X118480Y631037D01*
X118507Y631412D01*
X118480Y631787D01*
X118400Y632120D01*
X118293Y632370D01*
X118133Y632579D01*
X117920Y632662D01*
G01X118133Y635762D02*
X118293Y635470D01*
X118507Y635304D01*
X118747Y635262D01*
X118960Y635304D01*
X119173Y635512D01*
X119307Y635762D01*
X119333Y636012D01*
X119280Y636304D01*
X119093Y636512D01*
X118907Y636595D01*
X118667D01*
G01X118907D02*
X119067Y636720D01*
X119200Y636929D01*
X119253Y637179D01*
X119200Y637429D01*
X119067Y637637D01*
X118827Y637762D01*
X118587Y637720D01*
X118347Y637554D01*
G01X120920Y635262D02*
Y637762D01*
X120600Y637262D01*
G01Y635262D02*
X121240D01*
G01X118752Y639083D02*
X116846D01*
G01X118752Y640989D02*
Y639083D01*
G01X115909Y637626D02*
Y634626D01*
G01X122638Y637753D02*
X128838D01*
G01X122638Y634553D02*
Y637753D01*
G01X128838Y634553D02*
X122638D01*
G01Y638503D02*
Y641703D01*
G01X128838Y638503D02*
X122638D01*
G01X123638Y655003D02*
Y658203D01*
G01X129838Y655003D02*
X123638D01*
G01X122638Y645503D02*
Y648703D01*
G01X128838Y645503D02*
X122638D01*
G01Y648703D02*
X128838D01*
G01X123638Y651003D02*
Y654203D01*
G01X129838Y651003D02*
X123638D01*
G01Y654203D02*
X129838D01*
G01X120209Y656026D02*
X123209D01*
G01X121659Y648226D02*
X120159D01*
G01X122638Y641703D02*
X128838D01*
G01X121074Y663915D02*
Y667115D01*
G01X127274Y663915D02*
X121074D01*
G01Y667115D02*
X127274D01*
G01X121074Y659915D02*
Y663115D01*
G01X127274Y659915D02*
X121074D01*
G01Y663115D02*
X127274D01*
G01X115621Y662257D02*
X112421D01*
G01X115621Y668457D02*
Y662257D01*
G01X112421Y668457D02*
X115621D01*
G01X112421Y662257D02*
Y668457D01*
G01X119621Y662257D02*
X116421D01*
G01X119621Y668457D02*
Y662257D01*
G01X116421Y668457D02*
X119621D01*
G01X116421Y662257D02*
Y668457D01*
G01X123638Y658203D02*
X129838D01*
G01X121050Y671000D02*
X127250D01*
Y667800D01*
X121050D01*
Y671000D01*
G01X116846Y658769D02*
X118752D01*
G01D02*
Y656863D01*
G01X114128Y684814D02*
Y687914D01*
X115048D01*
X115355Y687759D01*
X115585Y687397D01*
X115662Y686984D01*
X115585Y686571D01*
X115393Y686261D01*
X115048Y686106D01*
X114128D01*
G01X117228Y687914D02*
Y684814D01*
X118762D01*
G01X121095D02*
Y687914D01*
X120635Y687294D01*
G01Y684814D02*
X121555D01*
G01X123467Y687397D02*
X123697Y687707D01*
X123965Y687862D01*
X124272Y687914D01*
X124655Y687811D01*
X124923Y687552D01*
X125000Y687242D01*
X124962Y686932D01*
X124808Y686674D01*
X124042Y686157D01*
X123697Y685796D01*
X123467Y685279D01*
X123390Y684814D01*
X125000D01*
G01X127295D02*
Y687914D01*
X126835Y687294D01*
G01Y684814D02*
X127755D01*
G01X116425Y1335007D02*
Y697211D01*
G01D02*
X133980D01*
G01X142015Y732644D02*
X116425D01*
G01X112315Y723430D02*
Y1335007D01*
G01X142015Y1299574D02*
X116425D01*
G01X124010Y1337825D02*
X124202Y1337515D01*
X124432Y1337308D01*
X124700Y1337205D01*
X125007Y1337308D01*
X125237Y1337515D01*
X125467Y1337825D01*
X125544Y1338238D01*
Y1340305D01*
G01X127149Y1339788D02*
X127379Y1340098D01*
X127647Y1340253D01*
X127954Y1340305D01*
X128337Y1340202D01*
X128605Y1339943D01*
X128682Y1339633D01*
X128644Y1339323D01*
X128490Y1339065D01*
X127724Y1338548D01*
X127379Y1338187D01*
X127149Y1337670D01*
X127072Y1337205D01*
X128682D01*
G01X130249Y1339788D02*
X130479Y1340098D01*
X130747Y1340253D01*
X131054Y1340305D01*
X131437Y1340202D01*
X131705Y1339943D01*
X131782Y1339633D01*
X131744Y1339323D01*
X131590Y1339065D01*
X130824Y1338548D01*
X130479Y1338187D01*
X130249Y1337670D01*
X130172Y1337205D01*
X131782D01*
G01X142015Y1335007D02*
X116425D01*
G01X127500Y1368989D02*
X121200D01*
Y1370555D01*
X121515Y1371182D01*
X121935Y1371652D01*
X122565Y1372044D01*
X123300Y1372357D01*
X124350Y1372435D01*
X125400Y1372357D01*
X126135Y1372044D01*
X126765Y1371652D01*
X127185Y1371182D01*
X127500Y1370555D01*
Y1368989D01*
G01Y1377012D02*
X121200D01*
X122460Y1376072D01*
G01X127500D02*
Y1377952D01*
G01X114640Y1371339D02*
X114325Y1371652D01*
X113800Y1371887D01*
X113065Y1372044D01*
X112435Y1371887D01*
X112015Y1371574D01*
X111700Y1371025D01*
Y1368910D01*
X118000D01*
Y1371495D01*
X117580Y1372044D01*
X116950Y1372357D01*
X116215Y1372514D01*
X115480Y1372357D01*
X114850Y1371887D01*
X114640Y1371339D01*
Y1368910D01*
G01X118000Y1377012D02*
X111700D01*
X112960Y1376072D01*
G01X118000D02*
Y1377952D01*
G01X119600Y1380462D02*
Y1366962D01*
G01X128800D02*
X119600D01*
G01Y1380462D02*
X128800D01*
G01X111874Y1526194D02*
Y1522994D01*
G01Y1530194D02*
Y1526994D01*
G01Y1538194D02*
Y1534994D01*
G01X114633Y1534167D02*
Y1537367D01*
G01X120833Y1534167D02*
X114633D01*
G01X120833Y1537367D02*
Y1534167D01*
G01X111874Y1534294D02*
Y1531094D01*
G01Y1546194D02*
Y1542994D01*
G01Y1554194D02*
Y1550994D01*
G01Y1550194D02*
Y1546994D01*
G01X114735Y1540335D02*
Y1543535D01*
G01X120935Y1540335D02*
X114735D01*
G01X120935Y1543535D02*
Y1540335D01*
G01X114735Y1543535D02*
X120935D01*
G01X114633Y1537367D02*
X120833D01*
G01X111874Y1542194D02*
Y1538994D01*
G01X114806Y1549627D02*
X121006D01*
Y1546427D01*
X114806D01*
Y1549627D01*
G01X111874Y1558194D02*
Y1554994D01*
G01Y1562194D02*
Y1558994D01*
G01Y1566194D02*
Y1562994D01*
G01X119478Y1581579D02*
X119171Y1581631D01*
X118903Y1581837D01*
X118673Y1582147D01*
X118520Y1582509D01*
X118443Y1582922D01*
Y1583336D01*
X118520Y1583749D01*
X118673Y1584111D01*
X118903Y1584421D01*
X119171Y1584627D01*
X119478Y1584679D01*
X119785Y1584627D01*
X120053Y1584421D01*
X120283Y1584111D01*
X120436Y1583749D01*
X120513Y1583336D01*
Y1582922D01*
X120436Y1582509D01*
X120283Y1582147D01*
X120053Y1581837D01*
X119785Y1581631D01*
X119478Y1581579D01*
G01X119785Y1582406D02*
X120245Y1581579D01*
G01X121926Y1581941D02*
X122195Y1581682D01*
X122501Y1581579D01*
X122808Y1581682D01*
X123076Y1581992D01*
X123268Y1582457D01*
X123345Y1582922D01*
Y1583491D01*
X123268Y1583956D01*
X123076Y1584369D01*
X122846Y1584576D01*
X122578Y1584679D01*
X122271Y1584576D01*
X122041Y1584369D01*
X121888Y1584059D01*
X121811Y1583646D01*
X121888Y1583284D01*
X122080Y1582922D01*
X122310Y1582716D01*
X122578Y1582664D01*
X122885Y1582767D01*
X123115Y1583026D01*
X123345Y1583491D01*
G01X124950Y1582871D02*
X125218Y1583232D01*
X125448Y1583439D01*
X125755Y1583542D01*
X126023Y1583439D01*
X126215Y1583232D01*
X126368Y1582922D01*
X126406Y1582561D01*
X126368Y1582251D01*
X126215Y1581941D01*
X125985Y1581682D01*
X125716Y1581579D01*
X125410Y1581682D01*
X125141Y1581992D01*
X124988Y1582457D01*
X124950Y1582974D01*
X125026Y1583646D01*
X125141Y1584007D01*
X125333Y1584369D01*
X125601Y1584627D01*
X125870Y1584679D01*
X126138Y1584576D01*
X126330Y1584317D01*
G01X112458Y1593683D02*
X115805D01*
G01D02*
Y1585021D01*
G01Y1605462D02*
Y1596800D01*
G01X117958Y1590952D02*
X124158D01*
G01D02*
Y1587752D01*
G01X117958D02*
Y1590952D01*
G01X124158Y1587752D02*
X117958D01*
G01X115805Y1624152D02*
Y1615490D01*
G01X113318Y1607758D02*
X113011Y1607810D01*
X112743Y1608016D01*
X112513Y1608326D01*
X112360Y1608688D01*
X112283Y1609101D01*
Y1609515D01*
X112360Y1609928D01*
X112513Y1610290D01*
X112743Y1610600D01*
X113011Y1610806D01*
X113318Y1610858D01*
X113625Y1610806D01*
X113893Y1610600D01*
X114123Y1610290D01*
X114276Y1609928D01*
X114353Y1609515D01*
Y1609101D01*
X114276Y1608688D01*
X114123Y1608326D01*
X113893Y1608016D01*
X113625Y1607810D01*
X113318Y1607758D01*
G01X113625Y1608585D02*
X114085Y1607758D01*
G01X116418D02*
Y1610858D01*
X115958Y1610238D01*
G01Y1607758D02*
X116878D01*
G01X119518Y1610858D02*
X119211Y1610755D01*
X118981Y1610496D01*
X118828Y1610186D01*
X118713Y1609773D01*
X118675Y1609308D01*
X118713Y1608843D01*
X118828Y1608430D01*
X118981Y1608120D01*
X119211Y1607861D01*
X119518Y1607758D01*
X119825Y1607861D01*
X120055Y1608120D01*
X120208Y1608430D01*
X120323Y1608843D01*
X120361Y1609308D01*
X120323Y1609773D01*
X120208Y1610186D01*
X120055Y1610496D01*
X119825Y1610755D01*
X119518Y1610858D01*
G01X122618Y1607758D02*
Y1610858D01*
X122158Y1610238D01*
G01Y1607758D02*
X123078D01*
G01X112458Y1605462D02*
X115805D01*
G01X122738Y1605967D02*
X128938D01*
G01X122738Y1602767D02*
Y1605967D01*
G01X128938Y1602767D02*
X122738D01*
G01X111908Y1627508D02*
X111601Y1627560D01*
X111333Y1627766D01*
X111103Y1628076D01*
X110950Y1628438D01*
X110873Y1628851D01*
Y1629265D01*
X110950Y1629678D01*
X111103Y1630040D01*
X111333Y1630350D01*
X111601Y1630556D01*
X111908Y1630608D01*
X112215Y1630556D01*
X112483Y1630350D01*
X112713Y1630040D01*
X112866Y1629678D01*
X112943Y1629265D01*
Y1628851D01*
X112866Y1628438D01*
X112713Y1628076D01*
X112483Y1627766D01*
X112215Y1627560D01*
X111908Y1627508D01*
G01X112215Y1628335D02*
X112675Y1627508D01*
G01X115008D02*
Y1630608D01*
X114548Y1629988D01*
G01Y1627508D02*
X115468D01*
G01X118108Y1630608D02*
X117801Y1630505D01*
X117571Y1630246D01*
X117418Y1629936D01*
X117303Y1629523D01*
X117265Y1629058D01*
X117303Y1628593D01*
X117418Y1628180D01*
X117571Y1627870D01*
X117801Y1627611D01*
X118108Y1627508D01*
X118415Y1627611D01*
X118645Y1627870D01*
X118798Y1628180D01*
X118913Y1628593D01*
X118951Y1629058D01*
X118913Y1629523D01*
X118798Y1629936D01*
X118645Y1630246D01*
X118415Y1630505D01*
X118108Y1630608D01*
G01X121131Y1627508D02*
X121208Y1628180D01*
X121323Y1628748D01*
X121476Y1629265D01*
X121668Y1629833D01*
X121975Y1630608D01*
X120441D01*
G01X112458Y1624152D02*
X115805D01*
G01X123458Y1623921D02*
X129658D01*
G01X123458Y1620721D02*
Y1623921D01*
G01X129658Y1620721D02*
X123458D01*
G01X112608Y1644019D02*
X112301Y1644071D01*
X112033Y1644277D01*
X111803Y1644587D01*
X111650Y1644949D01*
X111573Y1645362D01*
Y1645776D01*
X111650Y1646189D01*
X111803Y1646551D01*
X112033Y1646861D01*
X112301Y1647067D01*
X112608Y1647119D01*
X112915Y1647067D01*
X113183Y1646861D01*
X113413Y1646551D01*
X113566Y1646189D01*
X113643Y1645776D01*
Y1645362D01*
X113566Y1644949D01*
X113413Y1644587D01*
X113183Y1644277D01*
X112915Y1644071D01*
X112608Y1644019D01*
G01X112915Y1644846D02*
X113375Y1644019D01*
G01X115631D02*
X115708Y1644691D01*
X115823Y1645259D01*
X115976Y1645776D01*
X116168Y1646344D01*
X116475Y1647119D01*
X114941D01*
G01X118080Y1646602D02*
X118310Y1646912D01*
X118578Y1647067D01*
X118885Y1647119D01*
X119268Y1647016D01*
X119536Y1646757D01*
X119613Y1646447D01*
X119575Y1646137D01*
X119421Y1645879D01*
X118655Y1645362D01*
X118310Y1645001D01*
X118080Y1644484D01*
X118003Y1644019D01*
X119613D01*
G01X112458Y1642193D02*
X115805D01*
G01D02*
Y1633531D01*
G01X122458Y1639462D02*
X128658D01*
G01X122458Y1636262D02*
Y1639462D01*
G01X128658Y1636262D02*
X122458D01*
G01X111520Y1689693D02*
Y1681031D01*
G01X113120Y1678762D02*
Y1684962D01*
G01X116320Y1678762D02*
X113120D01*
G01X116320Y1684962D02*
Y1678762D01*
G01X120120Y1676762D02*
Y1679962D01*
G01X126320Y1676762D02*
X120120D01*
G01X126320Y1679962D02*
Y1676762D01*
G01X120120Y1679962D02*
X126320D01*
G01X120120Y1668762D02*
Y1671962D01*
G01X126320Y1668762D02*
X120120D01*
G01X126320Y1671962D02*
Y1668762D01*
G01X120120Y1671962D02*
X126320D01*
G01X120120Y1672762D02*
Y1675962D01*
G01X126320Y1672762D02*
X120120D01*
G01X126320Y1675962D02*
Y1672762D01*
G01X120120Y1675962D02*
X126320D01*
G01X111520Y1700693D02*
Y1692031D01*
G01X113120Y1694762D02*
Y1697962D01*
G01X119320Y1694762D02*
X113120D01*
G01X119320Y1697962D02*
Y1694762D01*
G01X113120Y1684962D02*
X116320D01*
G01X126320Y1697962D02*
Y1694762D01*
G01X120120D02*
Y1697962D01*
G01X126320Y1694762D02*
X120120D01*
G01Y1690762D02*
Y1693962D01*
G01X126320Y1690762D02*
X120120D01*
G01X126320Y1693962D02*
Y1690762D01*
G01X120120Y1693962D02*
X126320D01*
G01X120120Y1686762D02*
Y1689962D01*
G01X126320Y1686762D02*
X120120D01*
G01X126320Y1689962D02*
Y1686762D01*
G01X120120Y1689962D02*
X126320D01*
G01X113120Y1697962D02*
X119320D01*
G01X120120Y1706762D02*
Y1709962D01*
G01X126320Y1706762D02*
X120120D01*
G01X126320Y1709962D02*
Y1706762D01*
G01X120120Y1709962D02*
X126320D01*
G01X120120Y1698762D02*
Y1701962D01*
G01X126320Y1698762D02*
X120120D01*
G01X126320Y1701962D02*
Y1698762D01*
G01X120120Y1701962D02*
X126320D01*
G01X120120Y1697962D02*
X126320D01*
G01X120120Y1702762D02*
Y1705962D01*
G01X126320Y1702762D02*
X120120D01*
G01X126320Y1705962D02*
Y1702762D01*
G01X120120Y1705962D02*
X126320D01*
G01X119310Y1728147D02*
X122510D01*
G01X119310Y1721947D02*
Y1728147D01*
G01X122510Y1721947D02*
X119310D01*
G01X122510Y1728147D02*
Y1721947D01*
G01X125957Y1724782D02*
X132157D01*
G01X125957Y1721582D02*
Y1724782D01*
G01X132157Y1721582D02*
X125957D01*
G01Y1725582D02*
Y1728782D01*
G01X132157Y1725582D02*
X125957D01*
G01Y1728782D02*
X132157D01*
G01X125957Y1729582D02*
Y1732782D01*
G01X132157Y1729582D02*
X125957D01*
G01Y1732782D02*
X132157D01*
G01X153290Y51139D02*
X130140D01*
G01X147722Y43779D02*
X130982D01*
G01X137110Y79632D02*
X144110D01*
G01X130110D02*
X137110D01*
G01D02*
Y126632D01*
G01X130110Y79632D02*
Y126632D01*
G01X141610Y81345D02*
X139110D01*
Y81879D01*
X139235Y82092D01*
X139402Y82252D01*
X139652Y82385D01*
X139943Y82492D01*
X140360Y82519D01*
X140777Y82492D01*
X141068Y82385D01*
X141318Y82252D01*
X141485Y82092D01*
X141610Y81879D01*
Y81345D01*
G01X140568Y83625D02*
X140277Y83812D01*
X140110Y83972D01*
X140027Y84185D01*
X140110Y84372D01*
X140277Y84505D01*
X140527Y84612D01*
X140818Y84639D01*
X141068Y84612D01*
X141318Y84505D01*
X141527Y84345D01*
X141610Y84159D01*
X141527Y83945D01*
X141277Y83759D01*
X140902Y83652D01*
X140485Y83625D01*
X139943Y83679D01*
X139652Y83759D01*
X139360Y83892D01*
X139152Y84079D01*
X139110Y84265D01*
X139193Y84452D01*
X139402Y84585D01*
G01X141610Y86279D02*
X141068Y86332D01*
X140610Y86412D01*
X140193Y86519D01*
X139735Y86652D01*
X139110Y86865D01*
Y85799D01*
G01X134610Y81345D02*
X132110D01*
Y81879D01*
X132235Y82092D01*
X132402Y82252D01*
X132652Y82385D01*
X132943Y82492D01*
X133360Y82519D01*
X133777Y82492D01*
X134068Y82385D01*
X134318Y82252D01*
X134485Y82092D01*
X134610Y81879D01*
Y81345D01*
G01X133568Y83625D02*
X133277Y83812D01*
X133110Y83972D01*
X133027Y84185D01*
X133110Y84372D01*
X133277Y84505D01*
X133527Y84612D01*
X133818Y84639D01*
X134068Y84612D01*
X134318Y84505D01*
X134527Y84345D01*
X134610Y84159D01*
X134527Y83945D01*
X134277Y83759D01*
X133902Y83652D01*
X133485Y83625D01*
X132943Y83679D01*
X132652Y83759D01*
X132360Y83892D01*
X132152Y84079D01*
X132110Y84265D01*
X132193Y84452D01*
X132402Y84585D01*
G01X134610Y86332D02*
X134568Y86519D01*
X134443Y86732D01*
X134235Y86865D01*
X133943Y86919D01*
X133652Y86865D01*
X133402Y86705D01*
X133277Y86465D01*
Y86199D01*
X133193Y86039D01*
X132985Y85905D01*
X132693Y85852D01*
X132402Y85932D01*
X132193Y86119D01*
X132110Y86332D01*
X132193Y86545D01*
X132402Y86732D01*
X132693Y86812D01*
X132985Y86759D01*
X133193Y86625D01*
X133277Y86465D01*
Y86199D01*
X133402Y85959D01*
X133652Y85799D01*
X133943Y85745D01*
X134235Y85799D01*
X134443Y85932D01*
X134568Y86145D01*
X134610Y86332D01*
G01X141610Y90399D02*
X139110D01*
Y91065D01*
X139235Y91279D01*
X139402Y91412D01*
X139735Y91465D01*
X140068Y91412D01*
X140277Y91252D01*
X140402Y91065D01*
Y90399D01*
G01Y91065D02*
X141610Y91465D01*
G01X141277Y92572D02*
X141485Y92785D01*
X141610Y93025D01*
Y93239D01*
X141485Y93452D01*
X141277Y93612D01*
X140985Y93692D01*
X140693Y93639D01*
X140443Y93505D01*
X140277Y93265D01*
X140193Y92945D01*
X140027Y92759D01*
X139735Y92679D01*
X139443Y92732D01*
X139235Y92865D01*
X139110Y93052D01*
Y93239D01*
X139193Y93425D01*
X139402Y93585D01*
G01X139110Y95332D02*
X141610D01*
G01X139110Y94719D02*
Y95945D01*
G01X142443Y96732D02*
Y98332D01*
G01X139318Y100319D02*
X139193Y100159D01*
X139110Y99972D01*
Y99759D01*
X139235Y99519D01*
X139443Y99332D01*
X139693Y99199D01*
X140110Y99092D01*
X140485Y99065D01*
X140860Y99119D01*
X141110Y99199D01*
X141360Y99359D01*
X141527Y99545D01*
X141610Y99732D01*
Y99919D01*
X141527Y100105D01*
X141402Y100265D01*
X141235Y100399D01*
G01X141610Y101399D02*
X139110D01*
Y102039D01*
X139235Y102252D01*
X139527Y102412D01*
X139860Y102465D01*
X140193Y102412D01*
X140443Y102279D01*
X140568Y102039D01*
Y101399D01*
G01X139110Y103545D02*
X140902D01*
X141277Y103652D01*
X141527Y103865D01*
X141610Y104132D01*
X141527Y104399D01*
X141277Y104612D01*
X140902Y104719D01*
X139110D01*
G01Y106332D02*
X139193Y106119D01*
X139402Y105959D01*
X139652Y105852D01*
X139985Y105772D01*
X140360Y105745D01*
X140735Y105772D01*
X141068Y105852D01*
X141318Y105959D01*
X141527Y106119D01*
X141610Y106332D01*
X141527Y106545D01*
X141318Y106705D01*
X141068Y106812D01*
X140735Y106892D01*
X140360Y106919D01*
X139985Y106892D01*
X139652Y106812D01*
X139402Y106705D01*
X139193Y106545D01*
X139110Y106332D01*
G01X142443Y107732D02*
Y109332D01*
G01X141610Y110145D02*
X139110D01*
Y110679D01*
X139235Y110892D01*
X139402Y111052D01*
X139652Y111185D01*
X139943Y111292D01*
X140360Y111319D01*
X140777Y111292D01*
X141068Y111185D01*
X141318Y111052D01*
X141485Y110892D01*
X141610Y110679D01*
Y110145D01*
G01Y112399D02*
X139110D01*
Y113065D01*
X139235Y113279D01*
X139402Y113412D01*
X139735Y113465D01*
X140068Y113412D01*
X140277Y113252D01*
X140402Y113065D01*
Y112399D01*
G01Y113065D02*
X141610Y113465D01*
G01Y114465D02*
X139110Y115132D01*
X141610Y115799D01*
G01X140735Y115559D02*
Y114705D01*
G01X141610Y116639D02*
X139110D01*
X141193Y117332D01*
X139110Y118025D01*
X141610D01*
G01X142443Y118732D02*
Y120332D01*
G01X141610Y122265D02*
Y121199D01*
X139110D01*
Y122265D01*
G01X140318Y121839D02*
Y121199D01*
G01X141610Y123425D02*
X139110D01*
Y124439D01*
G01X140318Y124065D02*
Y123425D01*
G01X134610Y90399D02*
X132110D01*
Y91065D01*
X132235Y91279D01*
X132402Y91412D01*
X132735Y91465D01*
X133068Y91412D01*
X133277Y91252D01*
X133402Y91065D01*
Y90399D01*
G01Y91065D02*
X134610Y91465D01*
G01X134277Y92572D02*
X134485Y92785D01*
X134610Y93025D01*
Y93239D01*
X134485Y93452D01*
X134277Y93612D01*
X133985Y93692D01*
X133693Y93639D01*
X133443Y93505D01*
X133277Y93265D01*
X133193Y92945D01*
X133027Y92759D01*
X132735Y92679D01*
X132443Y92732D01*
X132235Y92865D01*
X132110Y93052D01*
Y93239D01*
X132193Y93425D01*
X132402Y93585D01*
G01X132110Y95332D02*
X134610D01*
G01X132110Y94719D02*
Y95945D01*
G01X135443Y96732D02*
Y98332D01*
G01X132318Y100319D02*
X132193Y100159D01*
X132110Y99972D01*
Y99759D01*
X132235Y99519D01*
X132443Y99332D01*
X132693Y99199D01*
X133110Y99092D01*
X133485Y99065D01*
X133860Y99119D01*
X134110Y99199D01*
X134360Y99359D01*
X134527Y99545D01*
X134610Y99732D01*
Y99919D01*
X134527Y100105D01*
X134402Y100265D01*
X134235Y100399D01*
G01X134610Y101399D02*
X132110D01*
Y102039D01*
X132235Y102252D01*
X132527Y102412D01*
X132860Y102465D01*
X133193Y102412D01*
X133443Y102279D01*
X133568Y102039D01*
Y101399D01*
G01X132110Y103545D02*
X133902D01*
X134277Y103652D01*
X134527Y103865D01*
X134610Y104132D01*
X134527Y104399D01*
X134277Y104612D01*
X133902Y104719D01*
X132110D01*
G01Y106332D02*
X132193Y106119D01*
X132402Y105959D01*
X132652Y105852D01*
X132985Y105772D01*
X133360Y105745D01*
X133735Y105772D01*
X134068Y105852D01*
X134318Y105959D01*
X134527Y106119D01*
X134610Y106332D01*
X134527Y106545D01*
X134318Y106705D01*
X134068Y106812D01*
X133735Y106892D01*
X133360Y106919D01*
X132985Y106892D01*
X132652Y106812D01*
X132402Y106705D01*
X132193Y106545D01*
X132110Y106332D01*
G01X135443Y107732D02*
Y109332D01*
G01X134610Y110145D02*
X132110D01*
Y110679D01*
X132235Y110892D01*
X132402Y111052D01*
X132652Y111185D01*
X132943Y111292D01*
X133360Y111319D01*
X133777Y111292D01*
X134068Y111185D01*
X134318Y111052D01*
X134485Y110892D01*
X134610Y110679D01*
Y110145D01*
G01Y112399D02*
X132110D01*
Y113065D01*
X132235Y113279D01*
X132402Y113412D01*
X132735Y113465D01*
X133068Y113412D01*
X133277Y113252D01*
X133402Y113065D01*
Y112399D01*
G01Y113065D02*
X134610Y113465D01*
G01Y114465D02*
X132110Y115132D01*
X134610Y115799D01*
G01X133735Y115559D02*
Y114705D01*
G01X134610Y116639D02*
X132110D01*
X134193Y117332D01*
X132110Y118025D01*
X134610D01*
G01X135443Y118732D02*
Y120332D01*
G01X133360Y121892D02*
Y122425D01*
X134110D01*
X134360Y122265D01*
X134527Y122079D01*
X134610Y121812D01*
X134527Y121545D01*
X134360Y121359D01*
X134110Y121199D01*
X133818Y121092D01*
X133485Y121039D01*
X133193D01*
X132943Y121092D01*
X132652Y121199D01*
X132402Y121359D01*
X132235Y121519D01*
X132110Y121732D01*
Y121919D01*
X132193Y122132D01*
X132360Y122292D01*
G01X134610Y123372D02*
X132110D01*
G01Y124492D02*
X134610D01*
G01X133360D02*
Y123372D01*
G01X144110Y126632D02*
X137110D01*
G01Y183632D02*
Y126632D01*
G01D02*
X130110D01*
G01Y183632D02*
Y126632D01*
G01X141610Y145399D02*
X139110D01*
Y146039D01*
X139235Y146252D01*
X139527Y146412D01*
X139860Y146465D01*
X140193Y146412D01*
X140443Y146279D01*
X140568Y146039D01*
Y145399D01*
G01X139110Y147465D02*
X141610Y148132D01*
X139110Y148799D01*
G01X141610Y149799D02*
X139110D01*
Y150439D01*
X139235Y150652D01*
X139527Y150812D01*
X139860Y150865D01*
X140193Y150812D01*
X140443Y150679D01*
X140568Y150439D01*
Y149799D01*
G01X141610Y151999D02*
X139110D01*
Y152639D01*
X139235Y152852D01*
X139527Y153012D01*
X139860Y153065D01*
X140193Y153012D01*
X140443Y152879D01*
X140568Y152639D01*
Y151999D01*
G01X142443Y153932D02*
Y155532D01*
G01X141610Y156372D02*
X139110D01*
G01Y157492D02*
X141610D01*
G01X140360D02*
Y156372D01*
G01X140277Y159345D02*
X140152Y159452D01*
X139943Y159532D01*
X139652Y159585D01*
X139402Y159532D01*
X139235Y159425D01*
X139110Y159239D01*
Y158519D01*
X141610D01*
Y159399D01*
X141443Y159585D01*
X141193Y159692D01*
X140902Y159745D01*
X140610Y159692D01*
X140360Y159532D01*
X140277Y159345D01*
Y158519D01*
G01X141610Y160639D02*
X139110D01*
X141193Y161332D01*
X139110Y162025D01*
X141610D01*
G01X142443Y162732D02*
Y164332D01*
G01X139318Y166319D02*
X139193Y166159D01*
X139110Y165972D01*
Y165759D01*
X139235Y165519D01*
X139443Y165332D01*
X139693Y165199D01*
X140110Y165092D01*
X140485Y165065D01*
X140860Y165119D01*
X141110Y165199D01*
X141360Y165359D01*
X141527Y165545D01*
X141610Y165732D01*
Y165919D01*
X141527Y166105D01*
X141402Y166265D01*
X141235Y166399D01*
G01X141610Y167399D02*
X139110D01*
Y168039D01*
X139235Y168252D01*
X139527Y168412D01*
X139860Y168465D01*
X140193Y168412D01*
X140443Y168279D01*
X140568Y168039D01*
Y167399D01*
G01X139110Y169545D02*
X140902D01*
X141277Y169652D01*
X141527Y169865D01*
X141610Y170132D01*
X141527Y170399D01*
X141277Y170612D01*
X140902Y170719D01*
X139110D01*
G01X141610Y172332D02*
X139110D01*
X139610Y172012D01*
G01X141610D02*
Y172652D01*
G01X134610Y140899D02*
X132110D01*
Y141539D01*
X132235Y141752D01*
X132527Y141912D01*
X132860Y141965D01*
X133193Y141912D01*
X133443Y141779D01*
X133568Y141539D01*
Y140899D01*
G01X132110Y142965D02*
X134610Y143632D01*
X132110Y144299D01*
G01X132318Y146419D02*
X132193Y146259D01*
X132110Y146072D01*
Y145859D01*
X132235Y145619D01*
X132443Y145432D01*
X132693Y145299D01*
X133110Y145192D01*
X133485Y145165D01*
X133860Y145219D01*
X134110Y145299D01*
X134360Y145459D01*
X134527Y145645D01*
X134610Y145832D01*
Y146019D01*
X134527Y146205D01*
X134402Y146365D01*
X134235Y146499D01*
G01X132318Y148619D02*
X132193Y148459D01*
X132110Y148272D01*
Y148059D01*
X132235Y147819D01*
X132443Y147632D01*
X132693Y147499D01*
X133110Y147392D01*
X133485Y147365D01*
X133860Y147419D01*
X134110Y147499D01*
X134360Y147659D01*
X134527Y147845D01*
X134610Y148032D01*
Y148219D01*
X134527Y148405D01*
X134402Y148565D01*
X134235Y148699D01*
G01X134610Y149725D02*
X132110D01*
Y150739D01*
G01X133318Y150365D02*
Y149725D01*
G01X134610Y151765D02*
X132110Y152432D01*
X134610Y153099D01*
G01X133735Y152859D02*
Y152005D01*
G01X135443Y153832D02*
Y155432D01*
G01X134610Y157365D02*
Y156299D01*
X132110D01*
Y157365D01*
G01X133318Y156939D02*
Y156299D01*
G01X134610Y158472D02*
X132110D01*
G01Y159592D02*
X134610D01*
G01X133360D02*
Y158472D01*
G01X132110Y160565D02*
X134610Y161232D01*
X132110Y161899D01*
G01X135443Y162632D02*
Y164232D01*
G01X132318Y166219D02*
X132193Y166059D01*
X132110Y165872D01*
Y165659D01*
X132235Y165419D01*
X132443Y165232D01*
X132693Y165099D01*
X133110Y164992D01*
X133485Y164965D01*
X133860Y165019D01*
X134110Y165099D01*
X134360Y165259D01*
X134527Y165445D01*
X134610Y165632D01*
Y165819D01*
X134527Y166005D01*
X134402Y166165D01*
X134235Y166299D01*
G01X134610Y167299D02*
X132110D01*
Y167939D01*
X132235Y168152D01*
X132527Y168312D01*
X132860Y168365D01*
X133193Y168312D01*
X133443Y168179D01*
X133568Y167939D01*
Y167299D01*
G01X132110Y169445D02*
X133902D01*
X134277Y169552D01*
X134527Y169765D01*
X134610Y170032D01*
X134527Y170299D01*
X134277Y170512D01*
X133902Y170619D01*
X132110D01*
G01Y172232D02*
X132193Y172019D01*
X132402Y171859D01*
X132652Y171752D01*
X132985Y171672D01*
X133360Y171645D01*
X133735Y171672D01*
X134068Y171752D01*
X134318Y171859D01*
X134527Y172019D01*
X134610Y172232D01*
X134527Y172445D01*
X134318Y172605D01*
X134068Y172712D01*
X133735Y172792D01*
X133360Y172819D01*
X132985Y172792D01*
X132652Y172712D01*
X132402Y172605D01*
X132193Y172445D01*
X132110Y172232D01*
G01X137110Y183632D02*
X144110D01*
G01X130110D02*
X137110D01*
G01X141604Y176384D02*
X139104D01*
Y176918D01*
X139229Y177131D01*
X139396Y177291D01*
X139646Y177424D01*
X139937Y177531D01*
X140354Y177558D01*
X140771Y177531D01*
X141062Y177424D01*
X141312Y177291D01*
X141479Y177131D01*
X141604Y176918D01*
Y176384D01*
G01Y179171D02*
X141562Y179358D01*
X141437Y179571D01*
X141229Y179704D01*
X140937Y179758D01*
X140646Y179704D01*
X140396Y179544D01*
X140271Y179304D01*
Y179038D01*
X140187Y178878D01*
X139979Y178744D01*
X139687Y178691D01*
X139396Y178771D01*
X139187Y178958D01*
X139104Y179171D01*
X139187Y179384D01*
X139396Y179571D01*
X139687Y179651D01*
X139979Y179598D01*
X140187Y179464D01*
X140271Y179304D01*
Y179038D01*
X140396Y178798D01*
X140646Y178638D01*
X140937Y178584D01*
X141229Y178638D01*
X141437Y178771D01*
X141562Y178984D01*
X141604Y179171D01*
G01Y181371D02*
X139104D01*
X139604Y181051D01*
G01X141604D02*
Y181691D01*
G01X134504Y176384D02*
X132004D01*
Y176918D01*
X132129Y177131D01*
X132296Y177291D01*
X132546Y177424D01*
X132837Y177531D01*
X133254Y177558D01*
X133671Y177531D01*
X133962Y177424D01*
X134212Y177291D01*
X134379Y177131D01*
X134504Y176918D01*
Y176384D01*
G01Y179118D02*
X133962Y179171D01*
X133504Y179251D01*
X133087Y179358D01*
X132629Y179491D01*
X132004Y179704D01*
Y178638D01*
G01X134129Y180784D02*
X134337Y180944D01*
X134462Y181131D01*
X134504Y181371D01*
X134421Y181611D01*
X134254Y181798D01*
X133962Y181931D01*
X133629Y181958D01*
X133296Y181904D01*
X133087Y181771D01*
X132921Y181584D01*
X132879Y181398D01*
X132921Y181211D01*
X133087Y180971D01*
X132004Y181051D01*
Y181771D01*
G01X128519Y280475D02*
Y277275D01*
G01Y307836D02*
Y304636D01*
G01X132082Y397671D02*
Y394471D01*
G01Y389671D02*
Y386471D01*
G01Y393671D02*
Y390471D01*
G01Y385671D02*
Y382471D01*
G01Y406171D02*
Y402971D01*
G01X142296Y413462D02*
Y416662D01*
G01X148496Y413462D02*
X142296D01*
G01Y416662D02*
X148496D01*
G01X142296Y421783D02*
Y424983D01*
G01X148496Y421783D02*
X142296D01*
G01Y424983D02*
X148496D01*
G01X142296Y425783D02*
Y428983D01*
G01X148496Y425783D02*
X142296D01*
G01Y428983D02*
X148496D01*
G01X142296Y417783D02*
Y420983D01*
G01X148496Y417783D02*
X142296D01*
G01Y420983D02*
X148496D01*
G01X142296Y429783D02*
Y432983D01*
G01X148496Y429783D02*
X142296D01*
G01Y432983D02*
X148496D01*
G01X142296Y433783D02*
Y436983D01*
G01X148496Y433783D02*
X142296D01*
G01Y436983D02*
X148496D01*
G01X142296Y437783D02*
Y440983D01*
G01X148496Y437783D02*
X142296D01*
G01Y440983D02*
X148496D01*
G01X142296Y441783D02*
Y444983D01*
G01X148496Y441783D02*
X142296D01*
G01Y444983D02*
X148496D01*
G01X136606Y489015D02*
X133406D01*
G01X136606Y495215D02*
Y489015D01*
G01X133406D02*
Y495215D01*
G01X131606Y489015D02*
X128406D01*
G01X131606Y495215D02*
Y489015D01*
G01X128406D02*
Y495215D01*
G01X128717Y484913D02*
X131917D01*
G01X128717Y478713D02*
Y484913D01*
G01X131917Y478713D02*
X128717D01*
G01X131917Y484913D02*
Y478713D01*
G01X133717Y484913D02*
X136917D01*
G01X133717Y478713D02*
Y484913D01*
G01X136917Y478713D02*
X133717D01*
G01X136917Y484913D02*
Y478713D01*
G01X142703D02*
X139503D01*
G01X142703Y484913D02*
Y478713D01*
G01X139503Y484913D02*
X142703D01*
G01X139503Y478713D02*
Y484913D01*
G01X142397Y497210D02*
Y500410D01*
G01X148597Y497210D02*
X142397D01*
G01Y500410D02*
X148597D01*
G01X142397Y501210D02*
Y504410D01*
G01X148597Y501210D02*
X142397D01*
G01Y504410D02*
X148597D01*
G01X135640Y496782D02*
Y499282D01*
X135320Y498782D01*
G01Y496782D02*
X135960D01*
G01X137840Y499282D02*
X137627Y499199D01*
X137467Y498990D01*
X137360Y498740D01*
X137280Y498407D01*
X137253Y498032D01*
X137280Y497657D01*
X137360Y497324D01*
X137467Y497074D01*
X137627Y496865D01*
X137840Y496782D01*
X138053Y496865D01*
X138213Y497074D01*
X138320Y497324D01*
X138400Y497657D01*
X138427Y498032D01*
X138400Y498407D01*
X138320Y498740D01*
X138213Y498990D01*
X138053Y499199D01*
X137840Y499282D01*
G01X138280Y500712D02*
Y503212D01*
X137960Y502712D01*
G01Y500712D02*
X138600D01*
G01X140480D02*
Y503212D01*
X140160Y502712D01*
G01Y500712D02*
X140800D01*
G01X136068Y500525D02*
X134172D01*
G01X136068Y502431D02*
Y500525D01*
G01X133325Y495968D02*
Y498968D01*
G01X137575Y509568D02*
X139075D01*
G01X133406Y495215D02*
X136606D01*
G01X128406D02*
X131606D01*
G01X142397Y509210D02*
Y512410D01*
G01X148597Y509210D02*
X142397D01*
G01X142362Y504933D02*
Y508133D01*
G01X148562Y504933D02*
X142362D01*
G01Y508133D02*
X148562D01*
G01X142397Y521210D02*
Y524410D01*
G01X148597Y521210D02*
X142397D01*
G01Y524410D02*
X148597D01*
G01X136050Y523774D02*
X129850D01*
G01D02*
Y526974D01*
G01X136050D02*
Y523774D01*
G01X138043Y520293D02*
X138203Y520543D01*
X138390Y520668D01*
X138603Y520710D01*
X138870Y520627D01*
X139057Y520418D01*
X139110Y520168D01*
X139083Y519918D01*
X138977Y519710D01*
X138443Y519293D01*
X138203Y519002D01*
X138043Y518585D01*
X137990Y518210D01*
X139110D01*
G01X140750Y520710D02*
X140537Y520627D01*
X140377Y520418D01*
X140270Y520168D01*
X140190Y519835D01*
X140163Y519460D01*
X140190Y519085D01*
X140270Y518752D01*
X140377Y518502D01*
X140537Y518293D01*
X140750Y518210D01*
X140963Y518293D01*
X141123Y518502D01*
X141230Y518752D01*
X141310Y519085D01*
X141337Y519460D01*
X141310Y519835D01*
X141230Y520168D01*
X141123Y520418D01*
X140963Y520627D01*
X140750Y520710D01*
G01X136068Y520211D02*
Y518305D01*
G01X134162Y520211D02*
X136068D01*
G01X140525Y517368D02*
X137525D01*
G01X127025Y521718D02*
Y523218D01*
G01X142397Y512410D02*
X148597D01*
G01X142397Y516410D02*
X148597D01*
G01X142397Y513210D02*
Y516410D01*
G01X148597Y513210D02*
X142397D01*
G01Y520410D02*
X148597D01*
G01X142397Y517210D02*
Y520410D01*
G01X148597Y517210D02*
X142397D01*
G01Y525230D02*
Y528430D01*
G01X148597Y525230D02*
X142397D01*
G01X140089Y530049D02*
Y523849D01*
G01D02*
X136889D01*
G01D02*
Y530049D01*
G01X129850Y526974D02*
X136050D01*
G01X128977Y546555D02*
Y540355D01*
G01X142397Y528430D02*
X148597D01*
G01X136889Y530049D02*
X140089D01*
G01X128838Y637753D02*
Y634553D01*
G01Y641703D02*
Y638503D01*
G01X129838Y658203D02*
Y655003D01*
G01X128838Y648703D02*
Y645503D01*
G01X129838Y654203D02*
Y651003D01*
G01X135422Y650043D02*
Y653143D01*
X136342D01*
X136649Y652988D01*
X136879Y652626D01*
X136956Y652213D01*
X136879Y651800D01*
X136687Y651490D01*
X136342Y651335D01*
X135422D01*
G01X138446Y653143D02*
Y650921D01*
X138599Y650456D01*
X138906Y650146D01*
X139289Y650043D01*
X139672Y650146D01*
X139979Y650456D01*
X140132Y650921D01*
Y653143D01*
G01X142389Y650043D02*
Y653143D01*
X141929Y652523D01*
G01Y650043D02*
X142849D01*
G01X145489D02*
X145757Y650095D01*
X146064Y650250D01*
X146256Y650508D01*
X146332Y650870D01*
X146256Y651231D01*
X146026Y651541D01*
X145681Y651696D01*
X145297D01*
X145067Y651800D01*
X144876Y652058D01*
X144799Y652420D01*
X144914Y652781D01*
X145182Y653040D01*
X145489Y653143D01*
X145796Y653040D01*
X146064Y652781D01*
X146179Y652420D01*
X146102Y652058D01*
X145911Y651800D01*
X145681Y651696D01*
X145297D01*
X144952Y651541D01*
X144722Y651231D01*
X144646Y650870D01*
X144722Y650508D01*
X144914Y650250D01*
X145221Y650095D01*
X145489Y650043D01*
G01X127081Y645203D02*
X133281D01*
G01X127081Y642003D02*
Y645203D01*
G01X133281Y642003D02*
X127081D01*
G01X133281Y645203D02*
Y642003D01*
G01X127274Y667115D02*
Y663915D01*
G01Y663115D02*
Y659915D01*
G01X131540Y665462D02*
Y667962D01*
X130553Y666170D01*
X131887D01*
G01X133420Y667962D02*
X133207Y667879D01*
X133047Y667670D01*
X132940Y667420D01*
X132860Y667087D01*
X132833Y666712D01*
X132860Y666337D01*
X132940Y666004D01*
X133047Y665754D01*
X133207Y665545D01*
X133420Y665462D01*
X133633Y665545D01*
X133793Y665754D01*
X133900Y666004D01*
X133980Y666337D01*
X134007Y666712D01*
X133980Y667087D01*
X133900Y667420D01*
X133793Y667670D01*
X133633Y667879D01*
X133420Y667962D01*
G01X141945Y686607D02*
Y689807D01*
G01X148145Y686607D02*
X141945D01*
G01X139045Y697807D02*
X151045D01*
G01X139045Y691807D02*
Y697807D01*
G01X151045Y691807D02*
X139045D01*
G01X138839Y699835D02*
Y705835D01*
G01X150839Y699835D02*
X138839D01*
G01X135493Y699939D02*
Y693850D01*
G01X141945Y689807D02*
X148145D01*
G01X138863Y713840D02*
X150863D01*
G01X138863Y707840D02*
Y713840D01*
G01X150863Y707840D02*
X138863D01*
G01X138887Y720660D02*
X150887D01*
G01X138887Y714660D02*
Y720660D01*
G01X150887Y714660D02*
X138887D01*
G01X138839Y705835D02*
X150839D01*
G01X135493Y720228D02*
Y714139D01*
G01X142015Y722102D02*
Y1335007D01*
G01X138763Y1338052D02*
X138955Y1337742D01*
X139185Y1337535D01*
X139453Y1337432D01*
X139760Y1337535D01*
X139990Y1337742D01*
X140220Y1338052D01*
X140297Y1338465D01*
Y1340532D01*
G01X142630Y1337432D02*
Y1340532D01*
X142170Y1339912D01*
G01Y1337432D02*
X143090D01*
G01X145078Y1337794D02*
X145347Y1337535D01*
X145653Y1337432D01*
X145960Y1337535D01*
X146228Y1337845D01*
X146420Y1338310D01*
X146497Y1338775D01*
Y1339344D01*
X146420Y1339809D01*
X146228Y1340222D01*
X145998Y1340429D01*
X145730Y1340532D01*
X145423Y1340429D01*
X145193Y1340222D01*
X145040Y1339912D01*
X144963Y1339499D01*
X145040Y1339137D01*
X145232Y1338775D01*
X145462Y1338569D01*
X145730Y1338517D01*
X146037Y1338620D01*
X146267Y1338879D01*
X146497Y1339344D01*
G01X131673Y1347592D02*
Y1350692D01*
X132593D01*
X132900Y1350537D01*
X133130Y1350175D01*
X133207Y1349762D01*
X133130Y1349349D01*
X132938Y1349039D01*
X132593Y1348884D01*
X131673D01*
G01X134773Y1350692D02*
Y1347592D01*
X136307D01*
G01X138640D02*
Y1350692D01*
X138180Y1350072D01*
G01Y1347592D02*
X139100D01*
G01X141740D02*
Y1350692D01*
X141280Y1350072D01*
G01Y1347592D02*
X142200D01*
G01X143997Y1348212D02*
X144227Y1347850D01*
X144533Y1347644D01*
X144878Y1347592D01*
X145185Y1347644D01*
X145492Y1347902D01*
X145683Y1348212D01*
X145722Y1348522D01*
X145645Y1348884D01*
X145377Y1349142D01*
X145108Y1349245D01*
X144763D01*
G01X145108D02*
X145338Y1349400D01*
X145530Y1349659D01*
X145607Y1349969D01*
X145530Y1350279D01*
X145338Y1350537D01*
X144993Y1350692D01*
X144648Y1350640D01*
X144303Y1350434D01*
G01X133140Y1371339D02*
X132825Y1371652D01*
X132300Y1371887D01*
X131565Y1372044D01*
X130935Y1371887D01*
X130515Y1371574D01*
X130200Y1371025D01*
Y1368910D01*
X136500D01*
Y1371495D01*
X136080Y1372044D01*
X135450Y1372357D01*
X134715Y1372514D01*
X133980Y1372357D01*
X133350Y1371887D01*
X133140Y1371339D01*
Y1368910D01*
G01X130200Y1377012D02*
X130410Y1376385D01*
X130935Y1375915D01*
X131565Y1375602D01*
X132405Y1375367D01*
X133350Y1375289D01*
X134295Y1375367D01*
X135135Y1375602D01*
X135765Y1375915D01*
X136290Y1376385D01*
X136500Y1377012D01*
X136290Y1377639D01*
X135765Y1378109D01*
X135135Y1378422D01*
X134295Y1378657D01*
X133350Y1378735D01*
X132405Y1378657D01*
X131565Y1378422D01*
X130935Y1378109D01*
X130410Y1377639D01*
X130200Y1377012D01*
G01X146000Y1368989D02*
X139700D01*
Y1370555D01*
X140015Y1371182D01*
X140435Y1371652D01*
X141065Y1372044D01*
X141800Y1372357D01*
X142850Y1372435D01*
X143900Y1372357D01*
X144635Y1372044D01*
X145265Y1371652D01*
X145685Y1371182D01*
X146000Y1370555D01*
Y1368989D01*
G01X139700Y1377012D02*
X139910Y1376385D01*
X140435Y1375915D01*
X141065Y1375602D01*
X141905Y1375367D01*
X142850Y1375289D01*
X143795Y1375367D01*
X144635Y1375602D01*
X145265Y1375915D01*
X145790Y1376385D01*
X146000Y1377012D01*
X145790Y1377639D01*
X145265Y1378109D01*
X144635Y1378422D01*
X143795Y1378657D01*
X142850Y1378735D01*
X141905Y1378657D01*
X141065Y1378422D01*
X140435Y1378109D01*
X139910Y1377639D01*
X139700Y1377012D01*
G01X128800Y1380462D02*
Y1366962D01*
G01X138000D02*
X128800D01*
G01X138000Y1380462D02*
Y1366962D01*
G01X147200D02*
X138000D01*
G01X128800Y1380462D02*
X138000D01*
G01D02*
X147200D01*
G01X141017Y1394675D02*
Y1397875D01*
G01X147217Y1394675D02*
X141017D01*
G01Y1397875D02*
X147217D01*
G01X141017Y1391145D02*
Y1394345D01*
G01X147217Y1391145D02*
X141017D01*
G01Y1394345D02*
X147217D01*
G01X128437Y1534255D02*
Y1537455D01*
G01X134637D02*
Y1534255D01*
G01D02*
X128437D01*
G01X133724Y1530189D02*
Y1527967D01*
X133877Y1527502D01*
X134184Y1527192D01*
X134567Y1527089D01*
X134950Y1527192D01*
X135257Y1527502D01*
X135410Y1527967D01*
Y1530189D01*
G01X136824Y1527709D02*
X137054Y1527347D01*
X137360Y1527141D01*
X137705Y1527089D01*
X138012Y1527141D01*
X138319Y1527399D01*
X138510Y1527709D01*
X138549Y1528019D01*
X138472Y1528381D01*
X138204Y1528639D01*
X137935Y1528742D01*
X137590D01*
G01X137935D02*
X138165Y1528897D01*
X138357Y1529156D01*
X138434Y1529466D01*
X138357Y1529776D01*
X138165Y1530034D01*
X137820Y1530189D01*
X137475Y1530137D01*
X137130Y1529931D01*
G01X140039Y1529672D02*
X140269Y1529982D01*
X140537Y1530137D01*
X140844Y1530189D01*
X141227Y1530086D01*
X141495Y1529827D01*
X141572Y1529517D01*
X141534Y1529207D01*
X141380Y1528949D01*
X140614Y1528432D01*
X140269Y1528071D01*
X140039Y1527554D01*
X139962Y1527089D01*
X141572D01*
G01X143867D02*
X144135Y1527141D01*
X144442Y1527296D01*
X144634Y1527554D01*
X144710Y1527916D01*
X144634Y1528277D01*
X144404Y1528587D01*
X144059Y1528742D01*
X143675D01*
X143445Y1528846D01*
X143254Y1529104D01*
X143177Y1529466D01*
X143292Y1529827D01*
X143560Y1530086D01*
X143867Y1530189D01*
X144174Y1530086D01*
X144442Y1529827D01*
X144557Y1529466D01*
X144480Y1529104D01*
X144289Y1528846D01*
X144059Y1528742D01*
X143675D01*
X143330Y1528587D01*
X143100Y1528277D01*
X143024Y1527916D01*
X143100Y1527554D01*
X143292Y1527296D01*
X143599Y1527141D01*
X143867Y1527089D01*
G01X128437Y1537455D02*
X134637D01*
G01X134789Y1540274D02*
X128589D01*
Y1543474D01*
X134789D01*
Y1540274D01*
G01X134881Y1546335D02*
X128681D01*
Y1549535D01*
X134881D01*
Y1546335D01*
G01X128938Y1605967D02*
Y1602767D01*
G01X129658Y1623921D02*
Y1620721D01*
G01X128658Y1639462D02*
Y1636262D01*
G01X139220Y1709962D02*
X145420D01*
G01X139220Y1706762D02*
Y1709962D01*
G01X145420Y1706762D02*
X139220D01*
G01X136967Y1721692D02*
X143167D01*
G01X136967Y1718492D02*
Y1721692D01*
G01X143167Y1718492D02*
X136967D01*
G01X132157Y1724782D02*
Y1721582D01*
G01Y1728782D02*
Y1725582D01*
G01X132957Y1726582D02*
Y1732782D01*
G01X136157Y1726582D02*
X132957D01*
G01X136157Y1732782D02*
Y1726582D01*
G01X132157Y1732782D02*
Y1729582D01*
G01X132957Y1732782D02*
X136157D01*
G01X160510Y51139D02*
X156740D01*
G01X158110Y79632D02*
X165110D01*
G01X158110D02*
Y126632D01*
G01X151110Y79632D02*
X158110D01*
G01X144110D02*
X151110D01*
G01D02*
Y126632D01*
G01X144110Y79632D02*
Y126632D01*
G01X155610Y81345D02*
X153110D01*
Y81879D01*
X153235Y82092D01*
X153402Y82252D01*
X153652Y82385D01*
X153943Y82492D01*
X154360Y82519D01*
X154777Y82492D01*
X155068Y82385D01*
X155318Y82252D01*
X155485Y82092D01*
X155610Y81879D01*
Y81345D01*
G01X154568Y83625D02*
X154277Y83812D01*
X154110Y83972D01*
X154027Y84185D01*
X154110Y84372D01*
X154277Y84505D01*
X154527Y84612D01*
X154818Y84639D01*
X155068Y84612D01*
X155318Y84505D01*
X155527Y84345D01*
X155610Y84159D01*
X155527Y83945D01*
X155277Y83759D01*
X154902Y83652D01*
X154485Y83625D01*
X153943Y83679D01*
X153652Y83759D01*
X153360Y83892D01*
X153152Y84079D01*
X153110Y84265D01*
X153193Y84452D01*
X153402Y84585D01*
G01X155235Y85745D02*
X155443Y85905D01*
X155568Y86092D01*
X155610Y86332D01*
X155527Y86572D01*
X155360Y86759D01*
X155068Y86892D01*
X154735Y86919D01*
X154402Y86865D01*
X154193Y86732D01*
X154027Y86545D01*
X153985Y86359D01*
X154027Y86172D01*
X154193Y85932D01*
X153110Y86012D01*
Y86732D01*
G01X148610Y81345D02*
X146110D01*
Y81879D01*
X146235Y82092D01*
X146402Y82252D01*
X146652Y82385D01*
X146943Y82492D01*
X147360Y82519D01*
X147777Y82492D01*
X148068Y82385D01*
X148318Y82252D01*
X148485Y82092D01*
X148610Y81879D01*
Y81345D01*
G01X147568Y83625D02*
X147277Y83812D01*
X147110Y83972D01*
X147027Y84185D01*
X147110Y84372D01*
X147277Y84505D01*
X147527Y84612D01*
X147818Y84639D01*
X148068Y84612D01*
X148318Y84505D01*
X148527Y84345D01*
X148610Y84159D01*
X148527Y83945D01*
X148277Y83759D01*
X147902Y83652D01*
X147485Y83625D01*
X146943Y83679D01*
X146652Y83759D01*
X146360Y83892D01*
X146152Y84079D01*
X146110Y84265D01*
X146193Y84452D01*
X146402Y84585D01*
G01X147568Y85825D02*
X147277Y86012D01*
X147110Y86172D01*
X147027Y86385D01*
X147110Y86572D01*
X147277Y86705D01*
X147527Y86812D01*
X147818Y86839D01*
X148068Y86812D01*
X148318Y86705D01*
X148527Y86545D01*
X148610Y86359D01*
X148527Y86145D01*
X148277Y85959D01*
X147902Y85852D01*
X147485Y85825D01*
X146943Y85879D01*
X146652Y85959D01*
X146360Y86092D01*
X146152Y86279D01*
X146110Y86465D01*
X146193Y86652D01*
X146402Y86785D01*
G01X155610Y90399D02*
X153110D01*
Y91065D01*
X153235Y91279D01*
X153402Y91412D01*
X153735Y91465D01*
X154068Y91412D01*
X154277Y91252D01*
X154402Y91065D01*
Y90399D01*
G01Y91065D02*
X155610Y91465D01*
G01X155277Y92572D02*
X155485Y92785D01*
X155610Y93025D01*
Y93239D01*
X155485Y93452D01*
X155277Y93612D01*
X154985Y93692D01*
X154693Y93639D01*
X154443Y93505D01*
X154277Y93265D01*
X154193Y92945D01*
X154027Y92759D01*
X153735Y92679D01*
X153443Y92732D01*
X153235Y92865D01*
X153110Y93052D01*
Y93239D01*
X153193Y93425D01*
X153402Y93585D01*
G01X153110Y95332D02*
X155610D01*
G01X153110Y94719D02*
Y95945D01*
G01X156443Y96732D02*
Y98332D01*
G01X153318Y100319D02*
X153193Y100159D01*
X153110Y99972D01*
Y99759D01*
X153235Y99519D01*
X153443Y99332D01*
X153693Y99199D01*
X154110Y99092D01*
X154485Y99065D01*
X154860Y99119D01*
X155110Y99199D01*
X155360Y99359D01*
X155527Y99545D01*
X155610Y99732D01*
Y99919D01*
X155527Y100105D01*
X155402Y100265D01*
X155235Y100399D01*
G01X155610Y101399D02*
X153110D01*
Y102039D01*
X153235Y102252D01*
X153527Y102412D01*
X153860Y102465D01*
X154193Y102412D01*
X154443Y102279D01*
X154568Y102039D01*
Y101399D01*
G01X153110Y103545D02*
X154902D01*
X155277Y103652D01*
X155527Y103865D01*
X155610Y104132D01*
X155527Y104399D01*
X155277Y104612D01*
X154902Y104719D01*
X153110D01*
G01Y106332D02*
X153193Y106119D01*
X153402Y105959D01*
X153652Y105852D01*
X153985Y105772D01*
X154360Y105745D01*
X154735Y105772D01*
X155068Y105852D01*
X155318Y105959D01*
X155527Y106119D01*
X155610Y106332D01*
X155527Y106545D01*
X155318Y106705D01*
X155068Y106812D01*
X154735Y106892D01*
X154360Y106919D01*
X153985Y106892D01*
X153652Y106812D01*
X153402Y106705D01*
X153193Y106545D01*
X153110Y106332D01*
G01X156443Y107732D02*
Y109332D01*
G01X155610Y110145D02*
X153110D01*
Y110679D01*
X153235Y110892D01*
X153402Y111052D01*
X153652Y111185D01*
X153943Y111292D01*
X154360Y111319D01*
X154777Y111292D01*
X155068Y111185D01*
X155318Y111052D01*
X155485Y110892D01*
X155610Y110679D01*
Y110145D01*
G01Y112399D02*
X153110D01*
Y113065D01*
X153235Y113279D01*
X153402Y113412D01*
X153735Y113465D01*
X154068Y113412D01*
X154277Y113252D01*
X154402Y113065D01*
Y112399D01*
G01Y113065D02*
X155610Y113465D01*
G01Y114465D02*
X153110Y115132D01*
X155610Y115799D01*
G01X154735Y115559D02*
Y114705D01*
G01X155610Y116639D02*
X153110D01*
X155193Y117332D01*
X153110Y118025D01*
X155610D01*
G01X156443Y118732D02*
Y120332D01*
G01X155610Y121065D02*
X153110Y121732D01*
X155610Y122399D01*
G01X154735Y122159D02*
Y121305D01*
G01X154277Y124145D02*
X154152Y124252D01*
X153943Y124332D01*
X153652Y124385D01*
X153402Y124332D01*
X153235Y124225D01*
X153110Y124039D01*
Y123319D01*
X155610D01*
Y124199D01*
X155443Y124385D01*
X155193Y124492D01*
X154902Y124545D01*
X154610Y124492D01*
X154360Y124332D01*
X154277Y124145D01*
Y123319D01*
G01X148610Y90399D02*
X146110D01*
Y91065D01*
X146235Y91279D01*
X146402Y91412D01*
X146735Y91465D01*
X147068Y91412D01*
X147277Y91252D01*
X147402Y91065D01*
Y90399D01*
G01Y91065D02*
X148610Y91465D01*
G01X148277Y92572D02*
X148485Y92785D01*
X148610Y93025D01*
Y93239D01*
X148485Y93452D01*
X148277Y93612D01*
X147985Y93692D01*
X147693Y93639D01*
X147443Y93505D01*
X147277Y93265D01*
X147193Y92945D01*
X147027Y92759D01*
X146735Y92679D01*
X146443Y92732D01*
X146235Y92865D01*
X146110Y93052D01*
Y93239D01*
X146193Y93425D01*
X146402Y93585D01*
G01X146110Y95332D02*
X148610D01*
G01X146110Y94719D02*
Y95945D01*
G01X149443Y96732D02*
Y98332D01*
G01X146318Y100319D02*
X146193Y100159D01*
X146110Y99972D01*
Y99759D01*
X146235Y99519D01*
X146443Y99332D01*
X146693Y99199D01*
X147110Y99092D01*
X147485Y99065D01*
X147860Y99119D01*
X148110Y99199D01*
X148360Y99359D01*
X148527Y99545D01*
X148610Y99732D01*
Y99919D01*
X148527Y100105D01*
X148402Y100265D01*
X148235Y100399D01*
G01X148610Y101399D02*
X146110D01*
Y102039D01*
X146235Y102252D01*
X146527Y102412D01*
X146860Y102465D01*
X147193Y102412D01*
X147443Y102279D01*
X147568Y102039D01*
Y101399D01*
G01X146110Y103545D02*
X147902D01*
X148277Y103652D01*
X148527Y103865D01*
X148610Y104132D01*
X148527Y104399D01*
X148277Y104612D01*
X147902Y104719D01*
X146110D01*
G01Y106332D02*
X146193Y106119D01*
X146402Y105959D01*
X146652Y105852D01*
X146985Y105772D01*
X147360Y105745D01*
X147735Y105772D01*
X148068Y105852D01*
X148318Y105959D01*
X148527Y106119D01*
X148610Y106332D01*
X148527Y106545D01*
X148318Y106705D01*
X148068Y106812D01*
X147735Y106892D01*
X147360Y106919D01*
X146985Y106892D01*
X146652Y106812D01*
X146402Y106705D01*
X146193Y106545D01*
X146110Y106332D01*
G01X149443Y107732D02*
Y109332D01*
G01X148610Y110145D02*
X146110D01*
Y110679D01*
X146235Y110892D01*
X146402Y111052D01*
X146652Y111185D01*
X146943Y111292D01*
X147360Y111319D01*
X147777Y111292D01*
X148068Y111185D01*
X148318Y111052D01*
X148485Y110892D01*
X148610Y110679D01*
Y110145D01*
G01Y112399D02*
X146110D01*
Y113065D01*
X146235Y113279D01*
X146402Y113412D01*
X146735Y113465D01*
X147068Y113412D01*
X147277Y113252D01*
X147402Y113065D01*
Y112399D01*
G01Y113065D02*
X148610Y113465D01*
G01Y114465D02*
X146110Y115132D01*
X148610Y115799D01*
G01X147735Y115559D02*
Y114705D01*
G01X148610Y116639D02*
X146110D01*
X148193Y117332D01*
X146110Y118025D01*
X148610D01*
G01X149443Y118732D02*
Y120332D01*
G01X146318Y122319D02*
X146193Y122159D01*
X146110Y121972D01*
Y121759D01*
X146235Y121519D01*
X146443Y121332D01*
X146693Y121199D01*
X147110Y121092D01*
X147485Y121065D01*
X147860Y121119D01*
X148110Y121199D01*
X148360Y121359D01*
X148527Y121545D01*
X148610Y121732D01*
Y121919D01*
X148527Y122105D01*
X148402Y122265D01*
X148235Y122399D01*
G01X148610Y123345D02*
X146110D01*
Y123879D01*
X146235Y124092D01*
X146402Y124252D01*
X146652Y124385D01*
X146943Y124492D01*
X147360Y124519D01*
X147777Y124492D01*
X148068Y124385D01*
X148318Y124252D01*
X148485Y124092D01*
X148610Y123879D01*
Y123345D01*
G01X165110Y126632D02*
X158110D01*
G01Y183632D02*
Y126632D01*
G01D02*
X151110D01*
G01Y183632D02*
Y126632D01*
G01D02*
X144110D01*
G01Y183632D02*
Y126632D01*
G01X155610Y145399D02*
X153110D01*
Y146039D01*
X153235Y146252D01*
X153527Y146412D01*
X153860Y146465D01*
X154193Y146412D01*
X154443Y146279D01*
X154568Y146039D01*
Y145399D01*
G01X153110Y147465D02*
X155610Y148132D01*
X153110Y148799D01*
G01X153318Y150919D02*
X153193Y150759D01*
X153110Y150572D01*
Y150359D01*
X153235Y150119D01*
X153443Y149932D01*
X153693Y149799D01*
X154110Y149692D01*
X154485Y149665D01*
X154860Y149719D01*
X155110Y149799D01*
X155360Y149959D01*
X155527Y150145D01*
X155610Y150332D01*
Y150519D01*
X155527Y150705D01*
X155402Y150865D01*
X155235Y150999D01*
G01X153318Y153119D02*
X153193Y152959D01*
X153110Y152772D01*
Y152559D01*
X153235Y152319D01*
X153443Y152132D01*
X153693Y151999D01*
X154110Y151892D01*
X154485Y151865D01*
X154860Y151919D01*
X155110Y151999D01*
X155360Y152159D01*
X155527Y152345D01*
X155610Y152532D01*
Y152719D01*
X155527Y152905D01*
X155402Y153065D01*
X155235Y153199D01*
G01X155610Y154145D02*
X153110D01*
Y154679D01*
X153235Y154892D01*
X153402Y155052D01*
X153652Y155185D01*
X153943Y155292D01*
X154360Y155319D01*
X154777Y155292D01*
X155068Y155185D01*
X155318Y155052D01*
X155485Y154892D01*
X155610Y154679D01*
Y154145D01*
G01X156443Y156132D02*
Y157732D01*
G01X155610Y158572D02*
X153110D01*
G01Y159692D02*
X155610D01*
G01X154360D02*
Y158572D01*
G01X153110Y160665D02*
X155610Y161332D01*
X153110Y161999D01*
G01X156443Y162732D02*
Y164332D01*
G01X153318Y166319D02*
X153193Y166159D01*
X153110Y165972D01*
Y165759D01*
X153235Y165519D01*
X153443Y165332D01*
X153693Y165199D01*
X154110Y165092D01*
X154485Y165065D01*
X154860Y165119D01*
X155110Y165199D01*
X155360Y165359D01*
X155527Y165545D01*
X155610Y165732D01*
Y165919D01*
X155527Y166105D01*
X155402Y166265D01*
X155235Y166399D01*
G01X155610Y167399D02*
X153110D01*
Y168039D01*
X153235Y168252D01*
X153527Y168412D01*
X153860Y168465D01*
X154193Y168412D01*
X154443Y168279D01*
X154568Y168039D01*
Y167399D01*
G01X153110Y169545D02*
X154902D01*
X155277Y169652D01*
X155527Y169865D01*
X155610Y170132D01*
X155527Y170399D01*
X155277Y170612D01*
X154902Y170719D01*
X153110D01*
G01X155610Y172332D02*
X153110D01*
X153610Y172012D01*
G01X155610D02*
Y172652D01*
G01X148610Y145399D02*
X146110D01*
Y146039D01*
X146235Y146252D01*
X146527Y146412D01*
X146860Y146465D01*
X147193Y146412D01*
X147443Y146279D01*
X147568Y146039D01*
Y145399D01*
G01X146110Y147465D02*
X148610Y148132D01*
X146110Y148799D01*
G01X148610Y149799D02*
X146110D01*
Y150439D01*
X146235Y150652D01*
X146527Y150812D01*
X146860Y150865D01*
X147193Y150812D01*
X147443Y150679D01*
X147568Y150439D01*
Y149799D01*
G01X148610Y151999D02*
X146110D01*
Y152639D01*
X146235Y152852D01*
X146527Y153012D01*
X146860Y153065D01*
X147193Y153012D01*
X147443Y152879D01*
X147568Y152639D01*
Y151999D01*
G01X149443Y153932D02*
Y155532D01*
G01X148610Y156372D02*
X146110D01*
G01Y157492D02*
X148610D01*
G01X147360D02*
Y156372D01*
G01X147277Y159345D02*
X147152Y159452D01*
X146943Y159532D01*
X146652Y159585D01*
X146402Y159532D01*
X146235Y159425D01*
X146110Y159239D01*
Y158519D01*
X148610D01*
Y159399D01*
X148443Y159585D01*
X148193Y159692D01*
X147902Y159745D01*
X147610Y159692D01*
X147360Y159532D01*
X147277Y159345D01*
Y158519D01*
G01X148610Y160639D02*
X146110D01*
X148193Y161332D01*
X146110Y162025D01*
X148610D01*
G01X149443Y162732D02*
Y164332D01*
G01X146318Y166319D02*
X146193Y166159D01*
X146110Y165972D01*
Y165759D01*
X146235Y165519D01*
X146443Y165332D01*
X146693Y165199D01*
X147110Y165092D01*
X147485Y165065D01*
X147860Y165119D01*
X148110Y165199D01*
X148360Y165359D01*
X148527Y165545D01*
X148610Y165732D01*
Y165919D01*
X148527Y166105D01*
X148402Y166265D01*
X148235Y166399D01*
G01X148610Y167399D02*
X146110D01*
Y168039D01*
X146235Y168252D01*
X146527Y168412D01*
X146860Y168465D01*
X147193Y168412D01*
X147443Y168279D01*
X147568Y168039D01*
Y167399D01*
G01X146110Y169545D02*
X147902D01*
X148277Y169652D01*
X148527Y169865D01*
X148610Y170132D01*
X148527Y170399D01*
X148277Y170612D01*
X147902Y170719D01*
X146110D01*
G01Y172332D02*
X146193Y172119D01*
X146402Y171959D01*
X146652Y171852D01*
X146985Y171772D01*
X147360Y171745D01*
X147735Y171772D01*
X148068Y171852D01*
X148318Y171959D01*
X148527Y172119D01*
X148610Y172332D01*
X148527Y172545D01*
X148318Y172705D01*
X148068Y172812D01*
X147735Y172892D01*
X147360Y172919D01*
X146985Y172892D01*
X146652Y172812D01*
X146402Y172705D01*
X146193Y172545D01*
X146110Y172332D01*
G01X158110Y183632D02*
X165110D01*
G01X151110D02*
X158110D01*
G01X144110D02*
X151110D01*
G01X155804Y176384D02*
X153304D01*
Y176918D01*
X153429Y177131D01*
X153596Y177291D01*
X153846Y177424D01*
X154137Y177531D01*
X154554Y177558D01*
X154971Y177531D01*
X155262Y177424D01*
X155512Y177291D01*
X155679Y177131D01*
X155804Y176918D01*
Y176384D01*
G01Y179171D02*
X155762Y179358D01*
X155637Y179571D01*
X155429Y179704D01*
X155137Y179758D01*
X154846Y179704D01*
X154596Y179544D01*
X154471Y179304D01*
Y179038D01*
X154387Y178878D01*
X154179Y178744D01*
X153887Y178691D01*
X153596Y178771D01*
X153387Y178958D01*
X153304Y179171D01*
X153387Y179384D01*
X153596Y179571D01*
X153887Y179651D01*
X154179Y179598D01*
X154387Y179464D01*
X154471Y179304D01*
Y179038D01*
X154596Y178798D01*
X154846Y178638D01*
X155137Y178584D01*
X155429Y178638D01*
X155637Y178771D01*
X155762Y178984D01*
X155804Y179171D01*
G01X153304Y181371D02*
X153387Y181158D01*
X153596Y180998D01*
X153846Y180891D01*
X154179Y180811D01*
X154554Y180784D01*
X154929Y180811D01*
X155262Y180891D01*
X155512Y180998D01*
X155721Y181158D01*
X155804Y181371D01*
X155721Y181584D01*
X155512Y181744D01*
X155262Y181851D01*
X154929Y181931D01*
X154554Y181958D01*
X154179Y181931D01*
X153846Y181851D01*
X153596Y181744D01*
X153387Y181584D01*
X153304Y181371D01*
G01X148704Y176384D02*
X146204D01*
Y176918D01*
X146329Y177131D01*
X146496Y177291D01*
X146746Y177424D01*
X147037Y177531D01*
X147454Y177558D01*
X147871Y177531D01*
X148162Y177424D01*
X148412Y177291D01*
X148579Y177131D01*
X148704Y176918D01*
Y176384D01*
G01Y179118D02*
X148162Y179171D01*
X147704Y179251D01*
X147287Y179358D01*
X146829Y179491D01*
X146204Y179704D01*
Y178638D01*
G01X148704Y181691D02*
X146204D01*
X147996Y180704D01*
Y182038D01*
G01X149307Y383462D02*
Y381240D01*
X149460Y380775D01*
X149767Y380465D01*
X150150Y380362D01*
X150533Y380465D01*
X150840Y380775D01*
X150993Y381240D01*
Y383462D01*
G01X153250Y380362D02*
Y383462D01*
X152790Y382842D01*
G01Y380362D02*
X153710D01*
G01X155698Y380724D02*
X155967Y380465D01*
X156273Y380362D01*
X156580Y380465D01*
X156848Y380775D01*
X157040Y381240D01*
X157117Y381705D01*
Y382274D01*
X157040Y382739D01*
X156848Y383152D01*
X156618Y383359D01*
X156350Y383462D01*
X156043Y383359D01*
X155813Y383152D01*
X155660Y382842D01*
X155583Y382429D01*
X155660Y382067D01*
X155852Y381705D01*
X156082Y381499D01*
X156350Y381447D01*
X156657Y381550D01*
X156887Y381809D01*
X157117Y382274D01*
G01X158607Y380982D02*
X158837Y380620D01*
X159143Y380414D01*
X159488Y380362D01*
X159795Y380414D01*
X160102Y380672D01*
X160293Y380982D01*
X160332Y381292D01*
X160255Y381654D01*
X159987Y381912D01*
X159718Y382015D01*
X159373D01*
G01X159718D02*
X159948Y382170D01*
X160140Y382429D01*
X160217Y382739D01*
X160140Y383049D01*
X159948Y383307D01*
X159603Y383462D01*
X159258Y383410D01*
X158913Y383204D01*
G01X149323Y385832D02*
X162831D01*
G01X149323Y405438D02*
Y385832D01*
G01X160380Y405438D02*
X156077Y401135D01*
G01X151774Y405438D02*
X149323D01*
G01X156077Y401135D02*
X151774Y405438D01*
G01X163000Y411762D02*
X156800D01*
Y414962D01*
X163000D01*
Y411762D01*
G01X156800Y410962D02*
X163000D01*
Y407762D01*
X156800D01*
Y410962D01*
G01X159901Y423783D02*
X153701D01*
Y426983D01*
X159901D01*
Y423783D01*
G01X156851Y426983D02*
X163051D01*
Y423783D01*
X156851D01*
Y426983D01*
G01X159901Y419783D02*
X153701D01*
Y422983D01*
X159901D01*
Y419783D01*
G01X156851Y422983D02*
X163051D01*
Y419783D01*
X156851D01*
Y422983D01*
G01X159901Y415783D02*
X153701D01*
Y418983D01*
X159901D01*
Y415783D01*
G01X156851Y418983D02*
X163051D01*
Y415783D01*
X156851D01*
Y418983D01*
G01X148496Y416662D02*
Y413462D01*
G01Y424983D02*
Y421783D01*
G01Y428983D02*
Y425783D01*
G01Y420983D02*
Y417783D01*
G01X159901Y441719D02*
X153701D01*
Y444919D01*
X159901D01*
Y441719D01*
G01X156851Y444919D02*
X163051D01*
Y441719D01*
X156851D01*
Y444919D01*
G01X153701Y440997D02*
X159901D01*
Y437797D01*
X153701D01*
Y440997D01*
G01X163051Y437797D02*
X156851D01*
Y440997D01*
X163051D01*
Y437797D01*
G01X153701Y436983D02*
X159901D01*
Y433783D01*
X153701D01*
Y436983D01*
G01X163051Y433783D02*
X156851D01*
Y436983D01*
X163051D01*
Y433783D01*
G01X159901Y429283D02*
X153701D01*
Y432483D01*
X159901D01*
Y429283D01*
G01X156851Y432483D02*
X163051D01*
Y429283D01*
X156851D01*
Y432483D01*
G01X148496Y432983D02*
Y429783D01*
G01Y436983D02*
Y433783D01*
G01Y440983D02*
Y437783D01*
G01Y444983D02*
Y441783D01*
G01X147574Y478713D02*
Y484913D01*
G01D02*
X150774D01*
G01Y478713D02*
X147574D01*
G01X150774Y484913D02*
Y478713D01*
G01X146813D02*
X143613D01*
G01X146813Y484913D02*
Y478713D01*
G01X143613Y484913D02*
X146813D01*
G01X143613Y478713D02*
Y484913D01*
G01X148597Y500410D02*
Y497210D01*
G01Y504410D02*
Y501210D01*
G01Y512410D02*
Y509210D01*
G01X148562Y508133D02*
Y504933D01*
G01X150870Y507463D02*
X154070D01*
G01X150870Y501263D02*
Y507463D01*
G01X154070Y501263D02*
X150870D01*
G01X154070Y507463D02*
Y501263D01*
G01X148597Y524410D02*
Y521210D01*
G01Y516410D02*
Y513210D01*
G01Y520410D02*
Y517210D01*
G01Y528430D02*
Y525230D01*
G01X157408Y520881D02*
Y517681D01*
G01X151208Y520881D02*
X157408D01*
G01X151208Y517681D02*
Y520881D01*
G01X157408Y517681D02*
X151208D01*
G01X146642Y538119D02*
Y541219D01*
X147562D01*
X147869Y541064D01*
X148099Y540702D01*
X148176Y540289D01*
X148099Y539876D01*
X147907Y539566D01*
X147562Y539411D01*
X146642D01*
G01X149742Y538739D02*
X149934Y538429D01*
X150164Y538222D01*
X150432Y538119D01*
X150739Y538222D01*
X150969Y538429D01*
X151199Y538739D01*
X151276Y539152D01*
Y541219D01*
G01X152766Y538584D02*
X152996Y538326D01*
X153264Y538171D01*
X153609Y538119D01*
X153954Y538222D01*
X154222Y538429D01*
X154414Y538791D01*
X154452Y539204D01*
X154376Y539617D01*
X154184Y539876D01*
X153916Y540082D01*
X153647Y540134D01*
X153379Y540082D01*
X153034Y539876D01*
X153149Y541219D01*
X154184D01*
G01X156709D02*
X156402Y541116D01*
X156172Y540857D01*
X156019Y540547D01*
X155904Y540134D01*
X155866Y539669D01*
X155904Y539204D01*
X156019Y538791D01*
X156172Y538481D01*
X156402Y538222D01*
X156709Y538119D01*
X157016Y538222D01*
X157246Y538481D01*
X157399Y538791D01*
X157514Y539204D01*
X157552Y539669D01*
X157514Y540134D01*
X157399Y540547D01*
X157246Y540857D01*
X157016Y541116D01*
X156709Y541219D01*
G01X157553Y584952D02*
Y588052D01*
X158473D01*
X158780Y587897D01*
X159010Y587535D01*
X159087Y587122D01*
X159010Y586709D01*
X158818Y586399D01*
X158473Y586244D01*
X157553D01*
G01X160653Y588052D02*
Y584952D01*
X162187D01*
G01X163792Y587535D02*
X164022Y587845D01*
X164290Y588000D01*
X164597Y588052D01*
X164980Y587949D01*
X165248Y587690D01*
X165325Y587380D01*
X165287Y587070D01*
X165133Y586812D01*
X164367Y586295D01*
X164022Y585934D01*
X163792Y585417D01*
X163715Y584952D01*
X165325D01*
G01X166777Y585572D02*
X167007Y585210D01*
X167313Y585004D01*
X167658Y584952D01*
X167965Y585004D01*
X168272Y585262D01*
X168463Y585572D01*
X168502Y585882D01*
X168425Y586244D01*
X168157Y586502D01*
X167888Y586605D01*
X167543D01*
G01X167888D02*
X168118Y586760D01*
X168310Y587019D01*
X168387Y587329D01*
X168310Y587639D01*
X168118Y587897D01*
X167773Y588052D01*
X167428Y588000D01*
X167083Y587794D01*
G01X148145Y689807D02*
Y686607D01*
G01X151045Y697807D02*
Y691807D01*
G01X150839Y705835D02*
Y699835D01*
G01X152960Y697211D02*
X171715D01*
G01X164687Y714660D02*
X152687D01*
G01Y720660D02*
X164687D01*
G01X152687Y714660D02*
Y720660D01*
G01X164663Y707840D02*
X152663D01*
G01Y713840D02*
X164663D01*
G01X152663Y707840D02*
Y713840D01*
G01X150863D02*
Y707840D01*
G01X150887Y720660D02*
Y714660D01*
G01X171715Y732644D02*
X146125D01*
G01Y1335007D02*
Y722432D01*
G01X171715Y1299574D02*
X146125D01*
G01X170301Y1324690D02*
G03I-10827J0D01*
G01X148913Y1337690D02*
Y1357375D01*
G01X154877Y1337690D02*
X148913D01*
G01X153960Y1335007D02*
X146125D01*
G01X170301Y1324690D02*
X148647D01*
G01X147200Y1357262D02*
Y1380462D01*
G01X148913Y1357375D02*
Y1377060D01*
G01X153799Y1380110D02*
Y1382710D01*
G01X154592Y1380110D02*
X153799D01*
G01X148913Y1377060D02*
X154827D01*
G01X147968Y1388070D02*
Y1394270D01*
G01X151168Y1388070D02*
X147968D01*
G01X151168Y1394270D02*
Y1388070D01*
G01X153799Y1403732D02*
X154807D01*
G01X153799Y1401878D02*
Y1403732D01*
G01Y1389321D02*
Y1391019D01*
G01X151168Y1398570D02*
X147968D01*
G01X151168Y1404770D02*
Y1398570D01*
G01X147968Y1404770D02*
X151168D01*
G01X147968Y1398570D02*
Y1404770D01*
G01Y1394270D02*
X151168D01*
G01X147217Y1397875D02*
Y1394675D01*
G01Y1394345D02*
Y1391145D01*
G01X151206Y1413059D02*
X154406D01*
G01X151206Y1406859D02*
Y1413059D01*
G01X154406Y1406859D02*
X151206D01*
G01X154406Y1413059D02*
Y1406859D01*
G01X155458Y1410573D02*
Y1413773D01*
G01X161658Y1410573D02*
X155458D01*
G01Y1413773D02*
X161658D01*
G01X160170Y1528105D02*
Y1521905D01*
X156970D01*
Y1528105D01*
X160170D01*
G01X156181Y1528064D02*
Y1521864D01*
X152981D01*
Y1528064D01*
X156181D01*
G01X149252Y1551001D02*
Y1553072D01*
X151323D01*
G01Y1536930D02*
X149252D01*
G01D02*
Y1539001D01*
G01X153498Y1561565D02*
Y1567765D01*
X156698D01*
Y1561565D01*
X153498D01*
G01X157507Y1561493D02*
Y1567693D01*
X160707D01*
Y1561493D01*
X157507D01*
G01X160614Y1578509D02*
Y1572309D01*
X157414D01*
Y1578509D01*
X160614D01*
G01X156180D02*
Y1572309D01*
X152980D01*
Y1578509D01*
X156180D01*
G01X145420Y1709962D02*
Y1706762D01*
G01X146620D02*
Y1709962D01*
G01X152820Y1706762D02*
X146620D01*
G01X152820Y1709962D02*
Y1706762D01*
G01X146620Y1709962D02*
X152820D01*
G01X146620Y1710762D02*
Y1713962D01*
G01X152820Y1710762D02*
X146620D01*
G01X152820Y1713962D02*
Y1710762D01*
G01X146620Y1713962D02*
X152820D01*
G01X159718Y1706917D02*
X156518D01*
G01Y1713117D02*
X159718D01*
G01X156518Y1706917D02*
Y1713117D01*
G01X153375Y1722176D02*
Y1719954D01*
X153528Y1719489D01*
X153835Y1719179D01*
X154218Y1719076D01*
X154601Y1719179D01*
X154908Y1719489D01*
X155061Y1719954D01*
Y1722176D01*
G01X156590Y1721659D02*
X156820Y1721969D01*
X157088Y1722124D01*
X157395Y1722176D01*
X157778Y1722073D01*
X158046Y1721814D01*
X158123Y1721504D01*
X158085Y1721194D01*
X157931Y1720936D01*
X157165Y1720419D01*
X156820Y1720058D01*
X156590Y1719541D01*
X156513Y1719076D01*
X158123D01*
G01X160418Y1722176D02*
X160111Y1722073D01*
X159881Y1721814D01*
X159728Y1721504D01*
X159613Y1721091D01*
X159575Y1720626D01*
X159613Y1720161D01*
X159728Y1719748D01*
X159881Y1719438D01*
X160111Y1719179D01*
X160418Y1719076D01*
X160725Y1719179D01*
X160955Y1719438D01*
X161108Y1719748D01*
X161223Y1720161D01*
X161261Y1720626D01*
X161223Y1721091D01*
X161108Y1721504D01*
X160955Y1721814D01*
X160725Y1722073D01*
X160418Y1722176D01*
G01X163518D02*
X163211Y1722073D01*
X162981Y1721814D01*
X162828Y1721504D01*
X162713Y1721091D01*
X162675Y1720626D01*
X162713Y1720161D01*
X162828Y1719748D01*
X162981Y1719438D01*
X163211Y1719179D01*
X163518Y1719076D01*
X163825Y1719179D01*
X164055Y1719438D01*
X164208Y1719748D01*
X164323Y1720161D01*
X164361Y1720626D01*
X164323Y1721091D01*
X164208Y1721504D01*
X164055Y1721814D01*
X163825Y1722073D01*
X163518Y1722176D01*
G01X151672Y1723128D02*
X148272D01*
G01X153672Y1725128D02*
X151672Y1723128D01*
G01X155672D02*
X153672Y1725128D01*
G01X159072Y1723128D02*
X155672D01*
G01X159072Y1735128D02*
Y1723128D01*
G01X148272D02*
Y1735128D01*
G01X143167Y1721692D02*
Y1718492D01*
G01X153620Y1714762D02*
Y1717962D01*
G01X159820Y1714762D02*
X153620D01*
G01Y1717962D02*
X159820D01*
G01X152820D02*
Y1714762D01*
G01X146620Y1717962D02*
X152820D01*
G01X146620Y1714762D02*
Y1717962D01*
G01X152820Y1714762D02*
X146620D01*
G01X148272Y1735128D02*
X159072D01*
G01X174720Y51139D02*
X170570D01*
G01X167280D02*
X163700D01*
G01X172110Y79632D02*
X179110D01*
G01X172110D02*
Y126632D01*
G01X165110Y79632D02*
X172110D01*
G01X165110D02*
Y126632D01*
G01X162610Y81345D02*
X160110D01*
Y81879D01*
X160235Y82092D01*
X160402Y82252D01*
X160652Y82385D01*
X160943Y82492D01*
X161360Y82519D01*
X161777Y82492D01*
X162068Y82385D01*
X162318Y82252D01*
X162485Y82092D01*
X162610Y81879D01*
Y81345D01*
G01X162318Y83679D02*
X162527Y83865D01*
X162610Y84079D01*
X162527Y84292D01*
X162277Y84479D01*
X161902Y84612D01*
X161527Y84665D01*
X161068D01*
X160693Y84612D01*
X160360Y84479D01*
X160193Y84319D01*
X160110Y84132D01*
X160193Y83919D01*
X160360Y83759D01*
X160610Y83652D01*
X160943Y83599D01*
X161235Y83652D01*
X161527Y83785D01*
X161693Y83945D01*
X161735Y84132D01*
X161652Y84345D01*
X161443Y84505D01*
X161068Y84665D01*
G01X160110Y86332D02*
X160193Y86119D01*
X160402Y85959D01*
X160652Y85852D01*
X160985Y85772D01*
X161360Y85745D01*
X161735Y85772D01*
X162068Y85852D01*
X162318Y85959D01*
X162527Y86119D01*
X162610Y86332D01*
X162527Y86545D01*
X162318Y86705D01*
X162068Y86812D01*
X161735Y86892D01*
X161360Y86919D01*
X160985Y86892D01*
X160652Y86812D01*
X160402Y86705D01*
X160193Y86545D01*
X160110Y86332D01*
G01X169610Y81345D02*
X167110D01*
Y81879D01*
X167235Y82092D01*
X167402Y82252D01*
X167652Y82385D01*
X167943Y82492D01*
X168360Y82519D01*
X168777Y82492D01*
X169068Y82385D01*
X169318Y82252D01*
X169485Y82092D01*
X169610Y81879D01*
Y81345D01*
G01Y84132D02*
X169568Y84319D01*
X169443Y84532D01*
X169235Y84665D01*
X168943Y84719D01*
X168652Y84665D01*
X168402Y84505D01*
X168277Y84265D01*
Y83999D01*
X168193Y83839D01*
X167985Y83705D01*
X167693Y83652D01*
X167402Y83732D01*
X167193Y83919D01*
X167110Y84132D01*
X167193Y84345D01*
X167402Y84532D01*
X167693Y84612D01*
X167985Y84559D01*
X168193Y84425D01*
X168277Y84265D01*
Y83999D01*
X168402Y83759D01*
X168652Y83599D01*
X168943Y83545D01*
X169235Y83599D01*
X169443Y83732D01*
X169568Y83945D01*
X169610Y84132D01*
G01X169318Y85879D02*
X169527Y86065D01*
X169610Y86279D01*
X169527Y86492D01*
X169277Y86679D01*
X168902Y86812D01*
X168527Y86865D01*
X168068D01*
X167693Y86812D01*
X167360Y86679D01*
X167193Y86519D01*
X167110Y86332D01*
X167193Y86119D01*
X167360Y85959D01*
X167610Y85852D01*
X167943Y85799D01*
X168235Y85852D01*
X168527Y85985D01*
X168693Y86145D01*
X168735Y86332D01*
X168652Y86545D01*
X168443Y86705D01*
X168068Y86865D01*
G01X176610Y81345D02*
X174110D01*
Y81879D01*
X174235Y82092D01*
X174402Y82252D01*
X174652Y82385D01*
X174943Y82492D01*
X175360Y82519D01*
X175777Y82492D01*
X176068Y82385D01*
X176318Y82252D01*
X176485Y82092D01*
X176610Y81879D01*
Y81345D01*
G01Y84132D02*
X176568Y84319D01*
X176443Y84532D01*
X176235Y84665D01*
X175943Y84719D01*
X175652Y84665D01*
X175402Y84505D01*
X175277Y84265D01*
Y83999D01*
X175193Y83839D01*
X174985Y83705D01*
X174693Y83652D01*
X174402Y83732D01*
X174193Y83919D01*
X174110Y84132D01*
X174193Y84345D01*
X174402Y84532D01*
X174693Y84612D01*
X174985Y84559D01*
X175193Y84425D01*
X175277Y84265D01*
Y83999D01*
X175402Y83759D01*
X175652Y83599D01*
X175943Y83545D01*
X176235Y83599D01*
X176443Y83732D01*
X176568Y83945D01*
X176610Y84132D01*
G01Y86332D02*
X176568Y86519D01*
X176443Y86732D01*
X176235Y86865D01*
X175943Y86919D01*
X175652Y86865D01*
X175402Y86705D01*
X175277Y86465D01*
Y86199D01*
X175193Y86039D01*
X174985Y85905D01*
X174693Y85852D01*
X174402Y85932D01*
X174193Y86119D01*
X174110Y86332D01*
X174193Y86545D01*
X174402Y86732D01*
X174693Y86812D01*
X174985Y86759D01*
X175193Y86625D01*
X175277Y86465D01*
Y86199D01*
X175402Y85959D01*
X175652Y85799D01*
X175943Y85745D01*
X176235Y85799D01*
X176443Y85932D01*
X176568Y86145D01*
X176610Y86332D01*
G01X167318Y100519D02*
X167193Y100359D01*
X167110Y100172D01*
Y99959D01*
X167235Y99719D01*
X167443Y99532D01*
X167693Y99399D01*
X168110Y99292D01*
X168485Y99265D01*
X168860Y99319D01*
X169110Y99399D01*
X169360Y99559D01*
X169527Y99745D01*
X169610Y99932D01*
Y100119D01*
X169527Y100305D01*
X169402Y100465D01*
X169235Y100599D01*
G01X169610Y101599D02*
X167110D01*
Y102239D01*
X167235Y102452D01*
X167527Y102612D01*
X167860Y102665D01*
X168193Y102612D01*
X168443Y102479D01*
X168568Y102239D01*
Y101599D01*
G01X167110Y103745D02*
X168902D01*
X169277Y103852D01*
X169527Y104065D01*
X169610Y104332D01*
X169527Y104599D01*
X169277Y104812D01*
X168902Y104919D01*
X167110D01*
G01X169610Y105999D02*
X167110D01*
Y106639D01*
X167235Y106852D01*
X167527Y107012D01*
X167860Y107065D01*
X168193Y107012D01*
X168443Y106879D01*
X168568Y106639D01*
Y105999D01*
G01X167110Y107932D02*
X169610Y108305D01*
X167110Y108732D01*
X169610Y109159D01*
X167110Y109532D01*
G01X169610Y110399D02*
X167110D01*
Y111065D01*
X167235Y111279D01*
X167402Y111412D01*
X167735Y111465D01*
X168068Y111412D01*
X168277Y111252D01*
X168402Y111065D01*
Y110399D01*
G01Y111065D02*
X169610Y111465D01*
G01X168360Y113292D02*
Y113825D01*
X169110D01*
X169360Y113665D01*
X169527Y113479D01*
X169610Y113212D01*
X169527Y112945D01*
X169360Y112759D01*
X169110Y112599D01*
X168818Y112492D01*
X168485Y112439D01*
X168193D01*
X167943Y112492D01*
X167652Y112599D01*
X167402Y112759D01*
X167235Y112919D01*
X167110Y113132D01*
Y113319D01*
X167193Y113532D01*
X167360Y113692D01*
G01X169610Y114745D02*
X167110D01*
Y115279D01*
X167235Y115492D01*
X167402Y115652D01*
X167652Y115785D01*
X167943Y115892D01*
X168360Y115919D01*
X168777Y115892D01*
X169068Y115785D01*
X169318Y115652D01*
X169485Y115492D01*
X169610Y115279D01*
Y114745D01*
G01X170443Y116732D02*
Y118332D01*
G01X168360Y119892D02*
Y120425D01*
X169110D01*
X169360Y120265D01*
X169527Y120079D01*
X169610Y119812D01*
X169527Y119545D01*
X169360Y119359D01*
X169110Y119199D01*
X168818Y119092D01*
X168485Y119039D01*
X168193D01*
X167943Y119092D01*
X167652Y119199D01*
X167402Y119359D01*
X167235Y119519D01*
X167110Y119732D01*
Y119919D01*
X167193Y120132D01*
X167360Y120292D01*
G01X167110Y121932D02*
X169610D01*
G01X167110Y121319D02*
Y122545D01*
G01Y123599D02*
X169610D01*
Y124665D01*
G01X162610Y103899D02*
X160110D01*
Y104565D01*
X160235Y104779D01*
X160402Y104912D01*
X160735Y104965D01*
X161068Y104912D01*
X161277Y104752D01*
X161402Y104565D01*
Y103899D01*
G01Y104565D02*
X162610Y104965D01*
G01X162277Y106072D02*
X162485Y106285D01*
X162610Y106525D01*
Y106739D01*
X162485Y106952D01*
X162277Y107112D01*
X161985Y107192D01*
X161693Y107139D01*
X161443Y107005D01*
X161277Y106765D01*
X161193Y106445D01*
X161027Y106259D01*
X160735Y106179D01*
X160443Y106232D01*
X160235Y106365D01*
X160110Y106552D01*
Y106739D01*
X160193Y106925D01*
X160402Y107085D01*
G01X160110Y108832D02*
X162610D01*
G01X160110Y108219D02*
Y109445D01*
G01X163443Y110232D02*
Y111832D01*
G01X162610Y112699D02*
X160110D01*
Y113339D01*
X160235Y113552D01*
X160527Y113712D01*
X160860Y113765D01*
X161193Y113712D01*
X161443Y113579D01*
X161568Y113339D01*
Y112699D01*
G01X160110Y114899D02*
X162610D01*
Y115965D01*
G01X160110Y117632D02*
X162610D01*
G01X160110Y117019D02*
Y118245D01*
G01X162610Y119299D02*
X160110D01*
Y119965D01*
X160235Y120179D01*
X160402Y120312D01*
X160735Y120365D01*
X161068Y120312D01*
X161277Y120152D01*
X161402Y119965D01*
Y119299D01*
G01Y119965D02*
X162610Y120365D01*
G01X162277Y121472D02*
X162485Y121685D01*
X162610Y121925D01*
Y122139D01*
X162485Y122352D01*
X162277Y122512D01*
X161985Y122592D01*
X161693Y122539D01*
X161443Y122405D01*
X161277Y122165D01*
X161193Y121845D01*
X161027Y121659D01*
X160735Y121579D01*
X160443Y121632D01*
X160235Y121765D01*
X160110Y121952D01*
Y122139D01*
X160193Y122325D01*
X160402Y122485D01*
G01X160110Y124232D02*
X162610D01*
G01X160110Y123619D02*
Y124845D01*
G01X176277Y105872D02*
X176485Y106085D01*
X176610Y106325D01*
Y106539D01*
X176485Y106752D01*
X176277Y106912D01*
X175985Y106992D01*
X175693Y106939D01*
X175443Y106805D01*
X175277Y106565D01*
X175193Y106245D01*
X175027Y106059D01*
X174735Y105979D01*
X174443Y106032D01*
X174235Y106165D01*
X174110Y106352D01*
Y106539D01*
X174193Y106725D01*
X174402Y106885D01*
G01X176610Y108632D02*
X175485D01*
X174110Y108099D01*
G01Y109165D02*
X175485Y108632D01*
G01X176277Y110272D02*
X176485Y110485D01*
X176610Y110725D01*
Y110939D01*
X176485Y111152D01*
X176277Y111312D01*
X175985Y111392D01*
X175693Y111339D01*
X175443Y111205D01*
X175277Y110965D01*
X175193Y110645D01*
X175027Y110459D01*
X174735Y110379D01*
X174443Y110432D01*
X174235Y110565D01*
X174110Y110752D01*
Y110939D01*
X174193Y111125D01*
X174402Y111285D01*
G01X177443Y112232D02*
Y113832D01*
G01X176610Y114699D02*
X174110D01*
Y115339D01*
X174235Y115552D01*
X174527Y115712D01*
X174860Y115765D01*
X175193Y115712D01*
X175443Y115579D01*
X175568Y115339D01*
Y114699D01*
G01X174110Y116632D02*
X176610Y117005D01*
X174110Y117432D01*
X176610Y117859D01*
X174110Y118232D01*
G01X176610Y119099D02*
X174110D01*
Y119765D01*
X174235Y119979D01*
X174402Y120112D01*
X174735Y120165D01*
X175068Y120112D01*
X175277Y119952D01*
X175402Y119765D01*
Y119099D01*
G01Y119765D02*
X176610Y120165D01*
G01Y121832D02*
X176568Y121619D01*
X176402Y121432D01*
X176152Y121272D01*
X175860Y121165D01*
X175527Y121112D01*
X175193D01*
X174860Y121165D01*
X174568Y121272D01*
X174318Y121432D01*
X174152Y121619D01*
X174110Y121832D01*
X174152Y122045D01*
X174318Y122232D01*
X174568Y122392D01*
X174860Y122499D01*
X175193Y122552D01*
X175527D01*
X175860Y122499D01*
X176152Y122392D01*
X176402Y122232D01*
X176568Y122045D01*
X176610Y121832D01*
G01Y123445D02*
X174110D01*
G01Y124459D02*
X175652Y123445D01*
G01X176610Y124619D02*
X174943Y123899D01*
G01X165110Y157685D02*
Y126632D01*
G01X172110Y166632D02*
Y126632D01*
G01X179110D02*
X172110D01*
G01D02*
X165110D01*
G01X162610Y145399D02*
X160110D01*
Y146039D01*
X160235Y146252D01*
X160527Y146412D01*
X160860Y146465D01*
X161193Y146412D01*
X161443Y146279D01*
X161568Y146039D01*
Y145399D01*
G01X160110Y147465D02*
X162610Y148132D01*
X160110Y148799D01*
G01X160318Y150919D02*
X160193Y150759D01*
X160110Y150572D01*
Y150359D01*
X160235Y150119D01*
X160443Y149932D01*
X160693Y149799D01*
X161110Y149692D01*
X161485Y149665D01*
X161860Y149719D01*
X162110Y149799D01*
X162360Y149959D01*
X162527Y150145D01*
X162610Y150332D01*
Y150519D01*
X162527Y150705D01*
X162402Y150865D01*
X162235Y150999D01*
G01X160318Y153119D02*
X160193Y152959D01*
X160110Y152772D01*
Y152559D01*
X160235Y152319D01*
X160443Y152132D01*
X160693Y151999D01*
X161110Y151892D01*
X161485Y151865D01*
X161860Y151919D01*
X162110Y151999D01*
X162360Y152159D01*
X162527Y152345D01*
X162610Y152532D01*
Y152719D01*
X162527Y152905D01*
X162402Y153065D01*
X162235Y153199D01*
G01X162610Y154145D02*
X160110D01*
Y154679D01*
X160235Y154892D01*
X160402Y155052D01*
X160652Y155185D01*
X160943Y155292D01*
X161360Y155319D01*
X161777Y155292D01*
X162068Y155185D01*
X162318Y155052D01*
X162485Y154892D01*
X162610Y154679D01*
Y154145D01*
G01X163443Y156132D02*
Y157732D01*
G01X162610Y158572D02*
X160110D01*
G01Y159692D02*
X162610D01*
G01X161360D02*
Y158572D01*
G01X160110Y160665D02*
X162610Y161332D01*
X160110Y161999D01*
G01X163443Y162732D02*
Y164332D01*
G01X160318Y166319D02*
X160193Y166159D01*
X160110Y165972D01*
Y165759D01*
X160235Y165519D01*
X160443Y165332D01*
X160693Y165199D01*
X161110Y165092D01*
X161485Y165065D01*
X161860Y165119D01*
X162110Y165199D01*
X162360Y165359D01*
X162527Y165545D01*
X162610Y165732D01*
Y165919D01*
X162527Y166105D01*
X162402Y166265D01*
X162235Y166399D01*
G01X162610Y167399D02*
X160110D01*
Y168039D01*
X160235Y168252D01*
X160527Y168412D01*
X160860Y168465D01*
X161193Y168412D01*
X161443Y168279D01*
X161568Y168039D01*
Y167399D01*
G01X160110Y169545D02*
X161902D01*
X162277Y169652D01*
X162527Y169865D01*
X162610Y170132D01*
X162527Y170399D01*
X162277Y170612D01*
X161902Y170719D01*
X160110D01*
G01Y172332D02*
X160193Y172119D01*
X160402Y171959D01*
X160652Y171852D01*
X160985Y171772D01*
X161360Y171745D01*
X161735Y171772D01*
X162068Y171852D01*
X162318Y171959D01*
X162527Y172119D01*
X162610Y172332D01*
X162527Y172545D01*
X162318Y172705D01*
X162068Y172812D01*
X161735Y172892D01*
X161360Y172919D01*
X160985Y172892D01*
X160652Y172812D01*
X160402Y172705D01*
X160193Y172545D01*
X160110Y172332D01*
G01X176610Y150399D02*
X174110D01*
Y151039D01*
X174235Y151252D01*
X174527Y151412D01*
X174860Y151465D01*
X175193Y151412D01*
X175443Y151279D01*
X175568Y151039D01*
Y150399D01*
G01X176235Y152545D02*
X176443Y152705D01*
X176568Y152892D01*
X176610Y153132D01*
X176527Y153372D01*
X176360Y153559D01*
X176068Y153692D01*
X175735Y153719D01*
X175402Y153665D01*
X175193Y153532D01*
X175027Y153345D01*
X174985Y153159D01*
X175027Y152972D01*
X175193Y152732D01*
X174110Y152812D01*
Y153532D01*
G01Y154665D02*
X176610Y155332D01*
X174110Y155999D01*
G01X169610Y148399D02*
X167110D01*
Y149039D01*
X167235Y149252D01*
X167527Y149412D01*
X167860Y149465D01*
X168193Y149412D01*
X168443Y149279D01*
X168568Y149039D01*
Y148399D01*
G01X169110Y150545D02*
X169402Y150705D01*
X169568Y150919D01*
X169610Y151159D01*
X169568Y151372D01*
X169360Y151585D01*
X169110Y151719D01*
X168860Y151745D01*
X168568Y151692D01*
X168360Y151505D01*
X168277Y151319D01*
Y151079D01*
G01Y151319D02*
X168152Y151479D01*
X167943Y151612D01*
X167693Y151665D01*
X167443Y151612D01*
X167235Y151479D01*
X167110Y151239D01*
X167152Y150999D01*
X167318Y150759D01*
G01X167110Y152665D02*
X169610Y153332D01*
X167110Y153999D01*
G01X169110Y154945D02*
X169402Y155105D01*
X169568Y155319D01*
X169610Y155559D01*
X169568Y155772D01*
X169360Y155985D01*
X169110Y156119D01*
X168860Y156145D01*
X168568Y156092D01*
X168360Y155905D01*
X168277Y155719D01*
Y155479D01*
G01Y155719D02*
X168152Y155879D01*
X167943Y156012D01*
X167693Y156065D01*
X167443Y156012D01*
X167235Y155879D01*
X167110Y155639D01*
X167152Y155399D01*
X167318Y155159D01*
G01X172110Y166632D02*
X165110D01*
G01X172110D02*
X179110D01*
G01X228110Y157685D02*
X165110D01*
G01D02*
Y174685D01*
G01X170004Y159384D02*
X167504D01*
Y159918D01*
X167629Y160131D01*
X167796Y160291D01*
X168046Y160424D01*
X168337Y160531D01*
X168754Y160558D01*
X169171Y160531D01*
X169462Y160424D01*
X169712Y160291D01*
X169879Y160131D01*
X170004Y159918D01*
Y159384D01*
G01X169712Y161718D02*
X169921Y161904D01*
X170004Y162118D01*
X169921Y162331D01*
X169671Y162518D01*
X169296Y162651D01*
X168921Y162704D01*
X168462D01*
X168087Y162651D01*
X167754Y162518D01*
X167587Y162358D01*
X167504Y162171D01*
X167587Y161958D01*
X167754Y161798D01*
X168004Y161691D01*
X168337Y161638D01*
X168629Y161691D01*
X168921Y161824D01*
X169087Y161984D01*
X169129Y162171D01*
X169046Y162384D01*
X168837Y162544D01*
X168462Y162704D01*
G01X169712Y163918D02*
X169921Y164104D01*
X170004Y164318D01*
X169921Y164531D01*
X169671Y164718D01*
X169296Y164851D01*
X168921Y164904D01*
X168462D01*
X168087Y164851D01*
X167754Y164718D01*
X167587Y164558D01*
X167504Y164371D01*
X167587Y164158D01*
X167754Y163998D01*
X168004Y163891D01*
X168337Y163838D01*
X168629Y163891D01*
X168921Y164024D01*
X169087Y164184D01*
X169129Y164371D01*
X169046Y164584D01*
X168837Y164744D01*
X168462Y164904D01*
G01X177104Y159384D02*
X174604D01*
Y159918D01*
X174729Y160131D01*
X174896Y160291D01*
X175146Y160424D01*
X175437Y160531D01*
X175854Y160558D01*
X176271Y160531D01*
X176562Y160424D01*
X176812Y160291D01*
X176979Y160131D01*
X177104Y159918D01*
Y159384D01*
G01X176812Y161718D02*
X177021Y161904D01*
X177104Y162118D01*
X177021Y162331D01*
X176771Y162518D01*
X176396Y162651D01*
X176021Y162704D01*
X175562D01*
X175187Y162651D01*
X174854Y162518D01*
X174687Y162358D01*
X174604Y162171D01*
X174687Y161958D01*
X174854Y161798D01*
X175104Y161691D01*
X175437Y161638D01*
X175729Y161691D01*
X176021Y161824D01*
X176187Y161984D01*
X176229Y162171D01*
X176146Y162384D01*
X175937Y162544D01*
X175562Y162704D01*
G01X177104Y164371D02*
X177062Y164558D01*
X176937Y164771D01*
X176729Y164904D01*
X176437Y164958D01*
X176146Y164904D01*
X175896Y164744D01*
X175771Y164504D01*
Y164238D01*
X175687Y164078D01*
X175479Y163944D01*
X175187Y163891D01*
X174896Y163971D01*
X174687Y164158D01*
X174604Y164371D01*
X174687Y164584D01*
X174896Y164771D01*
X175187Y164851D01*
X175479Y164798D01*
X175687Y164664D01*
X175771Y164504D01*
Y164238D01*
X175896Y163998D01*
X176146Y163838D01*
X176437Y163784D01*
X176729Y163838D01*
X176937Y163971D01*
X177062Y164184D01*
X177104Y164371D01*
G01X165110Y174685D02*
Y183632D01*
G01X162904Y176384D02*
X160404D01*
Y176918D01*
X160529Y177131D01*
X160696Y177291D01*
X160946Y177424D01*
X161237Y177531D01*
X161654Y177558D01*
X162071Y177531D01*
X162362Y177424D01*
X162612Y177291D01*
X162779Y177131D01*
X162904Y176918D01*
Y176384D01*
G01Y179118D02*
X162362Y179171D01*
X161904Y179251D01*
X161487Y179358D01*
X161029Y179491D01*
X160404Y179704D01*
Y178638D01*
G01X162404Y180784D02*
X162696Y180944D01*
X162862Y181158D01*
X162904Y181398D01*
X162862Y181611D01*
X162654Y181824D01*
X162404Y181958D01*
X162154Y181984D01*
X161862Y181931D01*
X161654Y181744D01*
X161571Y181558D01*
Y181318D01*
G01Y181558D02*
X161446Y181718D01*
X161237Y181851D01*
X160987Y181904D01*
X160737Y181851D01*
X160529Y181718D01*
X160404Y181478D01*
X160446Y181238D01*
X160612Y180998D01*
G01X184000Y224000D02*
X169500D01*
Y228000D01*
X168000Y226500D01*
X171000D01*
X169500Y228000D01*
G01X165624Y232828D02*
X172714D01*
Y229028D01*
X165624D01*
G01X165024Y232828D02*
X172214D01*
Y229028D01*
X165024D01*
G01X164624Y232828D02*
X171714D01*
Y229028D01*
X164574D01*
Y232778D01*
G01X162831Y385832D02*
Y405438D01*
G01D02*
X160380D01*
G01X170796Y419783D02*
Y422983D01*
G01X176996Y419783D02*
X170796D01*
G01Y422983D02*
X176996D01*
G01X170796Y423783D02*
Y426983D01*
G01X176996Y423783D02*
X170796D01*
G01Y426983D02*
X176996D01*
G01X170796Y441783D02*
Y444983D01*
G01X176996Y441783D02*
X170796D01*
G01Y444983D02*
X176996D01*
G01X170796Y429283D02*
Y432483D01*
G01X176996Y429283D02*
X170796D01*
G01Y432483D02*
X176996D01*
G01X171478Y577116D02*
Y594832D01*
G01X174886Y577116D02*
X171478D01*
G01Y594832D02*
X174886D01*
G01X162203Y611380D02*
Y614480D01*
X163123D01*
X163430Y614325D01*
X163660Y613963D01*
X163737Y613550D01*
X163660Y613137D01*
X163468Y612827D01*
X163123Y612672D01*
X162203D01*
G01X165227Y614480D02*
Y612258D01*
X165380Y611793D01*
X165687Y611483D01*
X166070Y611380D01*
X166453Y611483D01*
X166760Y611793D01*
X166913Y612258D01*
Y614480D01*
G01X168327Y611845D02*
X168557Y611587D01*
X168825Y611432D01*
X169170Y611380D01*
X169515Y611483D01*
X169783Y611690D01*
X169975Y612052D01*
X170013Y612465D01*
X169937Y612878D01*
X169745Y613137D01*
X169477Y613343D01*
X169208Y613395D01*
X168940Y613343D01*
X168595Y613137D01*
X168710Y614480D01*
X169745D01*
G01X172270D02*
X171963Y614377D01*
X171733Y614118D01*
X171580Y613808D01*
X171465Y613395D01*
X171427Y612930D01*
X171465Y612465D01*
X171580Y612052D01*
X171733Y611742D01*
X171963Y611483D01*
X172270Y611380D01*
X172577Y611483D01*
X172807Y611742D01*
X172960Y612052D01*
X173075Y612465D01*
X173113Y612930D01*
X173075Y613395D01*
X172960Y613808D01*
X172807Y614118D01*
X172577Y614377D01*
X172270Y614480D01*
G01X174220Y610347D02*
X176520D01*
G01X177703Y611380D02*
Y614480D01*
X178623D01*
X178930Y614325D01*
X179160Y613963D01*
X179237Y613550D01*
X179160Y613137D01*
X178968Y612827D01*
X178623Y612672D01*
X177703D01*
G01X181570Y611380D02*
Y614480D01*
X181110Y613860D01*
G01Y611380D02*
X182030D01*
G01X183520Y610347D02*
X185820D01*
G01X187770Y611380D02*
Y614480D01*
X187310Y613860D01*
G01Y611380D02*
X188230D01*
G01X188071Y642289D02*
G03I-13386J0D01*
G01X161299D02*
X188071D01*
G01X187779Y673433D02*
G03I-13386J0D01*
G01X161007D02*
X187779D01*
G01X171715Y697211D02*
Y1335007D01*
G01X164687Y720660D02*
Y714660D01*
G01X164663Y713840D02*
Y707840D01*
G01X182423Y720186D02*
X166327D01*
G01D02*
Y712934D01*
G01Y712756D02*
X182423D01*
G01X194674Y1324715D02*
G03I-10827J0D01*
G01X178441Y1337690D02*
X172527D01*
G01X171715Y1335007D02*
X165480D01*
G01X194674Y1324715D02*
X173020D01*
G01X173485Y1380110D02*
X172692D01*
G01X173485Y1382710D02*
Y1380110D01*
G01X172527Y1377060D02*
X178441D01*
G01X173485Y1403732D02*
Y1401541D01*
G01X172752Y1403732D02*
X173485D01*
G01X174543Y1412915D02*
X186543D01*
G01X174543Y1406915D02*
Y1412915D01*
G01X186543Y1406915D02*
X174543D01*
G01X162797Y1421265D02*
Y1424673D01*
G01X180513Y1421265D02*
X162797D01*
G01X169073Y1414045D02*
X172273D01*
G01X169073Y1407845D02*
Y1414045D01*
G01X172273Y1407845D02*
X169073D01*
G01X172273Y1414045D02*
Y1407845D01*
G01X168231D02*
X165031D01*
G01X168231Y1414045D02*
Y1407845D01*
G01X165031Y1414045D02*
X168231D01*
G01X165031Y1407845D02*
Y1414045D01*
G01X161658Y1413773D02*
Y1410573D01*
G01X162797Y1435573D02*
Y1438981D01*
G01X172956Y1441370D02*
Y1444470D01*
X173876D01*
X174183Y1444315D01*
X174413Y1443953D01*
X174490Y1443540D01*
X174413Y1443127D01*
X174221Y1442817D01*
X173876Y1442662D01*
X172956D01*
G01X176056Y1444470D02*
Y1441370D01*
X177590D01*
G01X180383D02*
Y1444470D01*
X178965Y1442248D01*
X180881D01*
G01X182180Y1441990D02*
X182410Y1441628D01*
X182716Y1441422D01*
X183061Y1441370D01*
X183368Y1441422D01*
X183675Y1441680D01*
X183866Y1441990D01*
X183905Y1442300D01*
X183828Y1442662D01*
X183560Y1442920D01*
X183291Y1443023D01*
X182946D01*
G01X183291D02*
X183521Y1443178D01*
X183713Y1443437D01*
X183790Y1443747D01*
X183713Y1444057D01*
X183521Y1444315D01*
X183176Y1444470D01*
X182831Y1444418D01*
X182486Y1444212D01*
G01X162797Y1438981D02*
X180513D01*
G01X164011Y1441790D02*
Y1444990D01*
G01X170211Y1441790D02*
X164011D01*
G01X170211Y1444990D02*
Y1441790D01*
G01X164011Y1444990D02*
X170211D01*
G01X163323Y1553072D02*
X165394D01*
Y1551001D01*
G01Y1539001D02*
Y1536930D01*
X163323D01*
G01X178393Y1577874D02*
X175193D01*
G01Y1584074D02*
X178393D01*
G01X175193Y1577874D02*
Y1584074D01*
G01X174218Y1705517D02*
Y1717517D01*
G01X185018Y1705517D02*
X174218D01*
G01X159718Y1713117D02*
Y1706917D01*
G01X169107Y1721300D02*
Y1719078D01*
X169260Y1718613D01*
X169567Y1718303D01*
X169950Y1718200D01*
X170333Y1718303D01*
X170640Y1718613D01*
X170793Y1719078D01*
Y1721300D01*
G01X173050Y1718200D02*
Y1721300D01*
X172590Y1720680D01*
G01Y1718200D02*
X173510D01*
G01X175498Y1718562D02*
X175767Y1718303D01*
X176073Y1718200D01*
X176380Y1718303D01*
X176648Y1718613D01*
X176840Y1719078D01*
X176917Y1719543D01*
Y1720112D01*
X176840Y1720577D01*
X176648Y1720990D01*
X176418Y1721197D01*
X176150Y1721300D01*
X175843Y1721197D01*
X175613Y1720990D01*
X175460Y1720680D01*
X175383Y1720267D01*
X175460Y1719905D01*
X175652Y1719543D01*
X175882Y1719337D01*
X176150Y1719285D01*
X176457Y1719388D01*
X176687Y1719647D01*
X176917Y1720112D01*
G01X179710Y1718200D02*
Y1721300D01*
X178292Y1719078D01*
X180208D01*
G01X174218Y1717517D02*
X177618D01*
G01X173467Y1725192D02*
X179667D01*
G01X173467Y1721992D02*
Y1725192D01*
G01X179667Y1721992D02*
X173467D01*
G01Y1728492D02*
Y1734692D01*
G01X176667Y1728492D02*
X173467D01*
G01X159820Y1717962D02*
Y1714762D01*
G01X173467Y1734692D02*
X176667D01*
G01X197723Y51139D02*
X178900D01*
G01X194222Y43779D02*
X181022D01*
G01X186110Y79632D02*
X193110D01*
G01X186110D02*
Y126632D01*
G01X179110Y79632D02*
X186110D01*
G01X179110D02*
Y126632D01*
G01X183610Y81345D02*
X181110D01*
Y81879D01*
X181235Y82092D01*
X181402Y82252D01*
X181652Y82385D01*
X181943Y82492D01*
X182360Y82519D01*
X182777Y82492D01*
X183068Y82385D01*
X183318Y82252D01*
X183485Y82092D01*
X183610Y81879D01*
Y81345D01*
G01Y84132D02*
X183568Y84319D01*
X183443Y84532D01*
X183235Y84665D01*
X182943Y84719D01*
X182652Y84665D01*
X182402Y84505D01*
X182277Y84265D01*
Y83999D01*
X182193Y83839D01*
X181985Y83705D01*
X181693Y83652D01*
X181402Y83732D01*
X181193Y83919D01*
X181110Y84132D01*
X181193Y84345D01*
X181402Y84532D01*
X181693Y84612D01*
X181985Y84559D01*
X182193Y84425D01*
X182277Y84265D01*
Y83999D01*
X182402Y83759D01*
X182652Y83599D01*
X182943Y83545D01*
X183235Y83599D01*
X183443Y83732D01*
X183568Y83945D01*
X183610Y84132D01*
G01Y86279D02*
X183068Y86332D01*
X182610Y86412D01*
X182193Y86519D01*
X181735Y86652D01*
X181110Y86865D01*
Y85799D01*
G01X190610Y81345D02*
X188110D01*
Y81879D01*
X188235Y82092D01*
X188402Y82252D01*
X188652Y82385D01*
X188943Y82492D01*
X189360Y82519D01*
X189777Y82492D01*
X190068Y82385D01*
X190318Y82252D01*
X190485Y82092D01*
X190610Y81879D01*
Y81345D01*
G01Y84132D02*
X190568Y84319D01*
X190443Y84532D01*
X190235Y84665D01*
X189943Y84719D01*
X189652Y84665D01*
X189402Y84505D01*
X189277Y84265D01*
Y83999D01*
X189193Y83839D01*
X188985Y83705D01*
X188693Y83652D01*
X188402Y83732D01*
X188193Y83919D01*
X188110Y84132D01*
X188193Y84345D01*
X188402Y84532D01*
X188693Y84612D01*
X188985Y84559D01*
X189193Y84425D01*
X189277Y84265D01*
Y83999D01*
X189402Y83759D01*
X189652Y83599D01*
X189943Y83545D01*
X190235Y83599D01*
X190443Y83732D01*
X190568Y83945D01*
X190610Y84132D01*
G01X189568Y85825D02*
X189277Y86012D01*
X189110Y86172D01*
X189027Y86385D01*
X189110Y86572D01*
X189277Y86705D01*
X189527Y86812D01*
X189818Y86839D01*
X190068Y86812D01*
X190318Y86705D01*
X190527Y86545D01*
X190610Y86359D01*
X190527Y86145D01*
X190277Y85959D01*
X189902Y85852D01*
X189485Y85825D01*
X188943Y85879D01*
X188652Y85959D01*
X188360Y86092D01*
X188152Y86279D01*
X188110Y86465D01*
X188193Y86652D01*
X188402Y86785D01*
G01X190610Y101899D02*
X188110D01*
Y102539D01*
X188235Y102752D01*
X188527Y102912D01*
X188860Y102965D01*
X189193Y102912D01*
X189443Y102779D01*
X189568Y102539D01*
Y101899D01*
G01X188110Y103965D02*
X190610Y104632D01*
X188110Y105299D01*
G01X188318Y107419D02*
X188193Y107259D01*
X188110Y107072D01*
Y106859D01*
X188235Y106619D01*
X188443Y106432D01*
X188693Y106299D01*
X189110Y106192D01*
X189485Y106165D01*
X189860Y106219D01*
X190110Y106299D01*
X190360Y106459D01*
X190527Y106645D01*
X190610Y106832D01*
Y107019D01*
X190527Y107205D01*
X190402Y107365D01*
X190235Y107499D01*
G01X188318Y109619D02*
X188193Y109459D01*
X188110Y109272D01*
Y109059D01*
X188235Y108819D01*
X188443Y108632D01*
X188693Y108499D01*
X189110Y108392D01*
X189485Y108365D01*
X189860Y108419D01*
X190110Y108499D01*
X190360Y108659D01*
X190527Y108845D01*
X190610Y109032D01*
Y109219D01*
X190527Y109405D01*
X190402Y109565D01*
X190235Y109699D01*
G01X188110Y110912D02*
Y111552D01*
G01Y111232D02*
X190610D01*
G01Y110912D02*
Y111552D01*
G01Y112819D02*
X188110D01*
X190610Y114045D01*
X188110D01*
G01X191443Y114832D02*
Y116432D01*
G01X188318Y118419D02*
X188193Y118259D01*
X188110Y118072D01*
Y117859D01*
X188235Y117619D01*
X188443Y117432D01*
X188693Y117299D01*
X189110Y117192D01*
X189485Y117165D01*
X189860Y117219D01*
X190110Y117299D01*
X190360Y117459D01*
X190527Y117645D01*
X190610Y117832D01*
Y118019D01*
X190527Y118205D01*
X190402Y118365D01*
X190235Y118499D01*
G01X190610Y119499D02*
X188110D01*
Y120139D01*
X188235Y120352D01*
X188527Y120512D01*
X188860Y120565D01*
X189193Y120512D01*
X189443Y120379D01*
X189568Y120139D01*
Y119499D01*
G01X188110Y121645D02*
X189902D01*
X190277Y121752D01*
X190527Y121965D01*
X190610Y122232D01*
X190527Y122499D01*
X190277Y122712D01*
X189902Y122819D01*
X188110D01*
G01X190610Y124432D02*
X188110D01*
X188610Y124112D01*
G01X190610D02*
Y124752D01*
G01X183610Y105899D02*
X181110D01*
Y106539D01*
X181235Y106752D01*
X181527Y106912D01*
X181860Y106965D01*
X182193Y106912D01*
X182443Y106779D01*
X182568Y106539D01*
Y105899D01*
G01X181318Y109219D02*
X181193Y109059D01*
X181110Y108872D01*
Y108659D01*
X181235Y108419D01*
X181443Y108232D01*
X181693Y108099D01*
X182110Y107992D01*
X182485Y107965D01*
X182860Y108019D01*
X183110Y108099D01*
X183360Y108259D01*
X183527Y108445D01*
X183610Y108632D01*
Y108819D01*
X183527Y109005D01*
X183402Y109165D01*
X183235Y109299D01*
G01X183610Y110272D02*
X181110D01*
G01Y111392D02*
X183610D01*
G01X182360D02*
Y110272D01*
G01X184443Y112232D02*
Y113832D01*
G01X183610Y114699D02*
X181110D01*
Y115339D01*
X181235Y115552D01*
X181527Y115712D01*
X181860Y115765D01*
X182193Y115712D01*
X182443Y115579D01*
X182568Y115339D01*
Y114699D01*
G01X181110Y116632D02*
X183610Y117005D01*
X181110Y117432D01*
X183610Y117859D01*
X181110Y118232D01*
G01X183610Y119099D02*
X181110D01*
Y119765D01*
X181235Y119979D01*
X181402Y120112D01*
X181735Y120165D01*
X182068Y120112D01*
X182277Y119952D01*
X182402Y119765D01*
Y119099D01*
G01Y119765D02*
X183610Y120165D01*
G01Y121832D02*
X183568Y121619D01*
X183402Y121432D01*
X183152Y121272D01*
X182860Y121165D01*
X182527Y121112D01*
X182193D01*
X181860Y121165D01*
X181568Y121272D01*
X181318Y121432D01*
X181152Y121619D01*
X181110Y121832D01*
X181152Y122045D01*
X181318Y122232D01*
X181568Y122392D01*
X181860Y122499D01*
X182193Y122552D01*
X182527D01*
X182860Y122499D01*
X183152Y122392D01*
X183402Y122232D01*
X183568Y122045D01*
X183610Y121832D01*
G01Y123445D02*
X181110D01*
G01Y124459D02*
X182652Y123445D01*
G01X183610Y124619D02*
X181943Y123899D01*
G01X179110Y166632D02*
Y126632D01*
G01X186110Y166632D02*
Y126632D01*
G01X193110D02*
X186110D01*
G01D02*
X179110D01*
G01X190277Y143872D02*
X190485Y144085D01*
X190610Y144325D01*
Y144539D01*
X190485Y144752D01*
X190277Y144912D01*
X189985Y144992D01*
X189693Y144939D01*
X189443Y144805D01*
X189277Y144565D01*
X189193Y144245D01*
X189027Y144059D01*
X188735Y143979D01*
X188443Y144032D01*
X188235Y144165D01*
X188110Y144352D01*
Y144539D01*
X188193Y144725D01*
X188402Y144885D01*
G01X188110Y146099D02*
X190610D01*
Y147165D01*
G01Y148299D02*
X188110D01*
Y148939D01*
X188235Y149152D01*
X188527Y149312D01*
X188860Y149365D01*
X189193Y149312D01*
X189443Y149179D01*
X189568Y148939D01*
Y148299D01*
G01X191443Y150232D02*
Y151832D01*
G01X190277Y152672D02*
X190485Y152885D01*
X190610Y153125D01*
Y153339D01*
X190485Y153552D01*
X190277Y153712D01*
X189985Y153792D01*
X189693Y153739D01*
X189443Y153605D01*
X189277Y153365D01*
X189193Y153045D01*
X189027Y152859D01*
X188735Y152779D01*
X188443Y152832D01*
X188235Y152965D01*
X188110Y153152D01*
Y153339D01*
X188193Y153525D01*
X188402Y153685D01*
G01X190110Y154845D02*
X190402Y155005D01*
X190568Y155219D01*
X190610Y155459D01*
X190568Y155672D01*
X190360Y155885D01*
X190110Y156019D01*
X189860Y156045D01*
X189568Y155992D01*
X189360Y155805D01*
X189277Y155619D01*
Y155379D01*
G01Y155619D02*
X189152Y155779D01*
X188943Y155912D01*
X188693Y155965D01*
X188443Y155912D01*
X188235Y155779D01*
X188110Y155539D01*
X188152Y155299D01*
X188318Y155059D01*
G01X183610Y139399D02*
X181110D01*
Y140039D01*
X181235Y140252D01*
X181527Y140412D01*
X181860Y140465D01*
X182193Y140412D01*
X182443Y140279D01*
X182568Y140039D01*
Y139399D01*
G01X183277Y141572D02*
X183485Y141785D01*
X183610Y142025D01*
Y142239D01*
X183485Y142452D01*
X183277Y142612D01*
X182985Y142692D01*
X182693Y142639D01*
X182443Y142505D01*
X182277Y142265D01*
X182193Y141945D01*
X182027Y141759D01*
X181735Y141679D01*
X181443Y141732D01*
X181235Y141865D01*
X181110Y142052D01*
Y142239D01*
X181193Y142425D01*
X181402Y142585D01*
G01X184443Y143532D02*
Y145132D01*
G01X183610Y145999D02*
X181110D01*
Y146639D01*
X181235Y146852D01*
X181527Y147012D01*
X181860Y147065D01*
X182193Y147012D01*
X182443Y146879D01*
X182568Y146639D01*
Y145999D01*
G01X181110Y147932D02*
X183610Y148305D01*
X181110Y148732D01*
X183610Y149159D01*
X181110Y149532D01*
G01X183610Y150399D02*
X181110D01*
Y151065D01*
X181235Y151279D01*
X181402Y151412D01*
X181735Y151465D01*
X182068Y151412D01*
X182277Y151252D01*
X182402Y151065D01*
Y150399D01*
G01Y151065D02*
X183610Y151465D01*
G01Y153132D02*
X183568Y152919D01*
X183402Y152732D01*
X183152Y152572D01*
X182860Y152465D01*
X182527Y152412D01*
X182193D01*
X181860Y152465D01*
X181568Y152572D01*
X181318Y152732D01*
X181152Y152919D01*
X181110Y153132D01*
X181152Y153345D01*
X181318Y153532D01*
X181568Y153692D01*
X181860Y153799D01*
X182193Y153852D01*
X182527D01*
X182860Y153799D01*
X183152Y153692D01*
X183402Y153532D01*
X183568Y153345D01*
X183610Y153132D01*
G01Y154745D02*
X181110D01*
G01Y155759D02*
X182652Y154745D01*
G01X183610Y155919D02*
X181943Y155199D01*
G01X186110Y166632D02*
X193110D01*
G01X179110D02*
X186110D01*
G01X183704Y159384D02*
X181204D01*
Y159918D01*
X181329Y160131D01*
X181496Y160291D01*
X181746Y160424D01*
X182037Y160531D01*
X182454Y160558D01*
X182871Y160531D01*
X183162Y160424D01*
X183412Y160291D01*
X183579Y160131D01*
X183704Y159918D01*
Y159384D01*
G01X183412Y161718D02*
X183621Y161904D01*
X183704Y162118D01*
X183621Y162331D01*
X183371Y162518D01*
X182996Y162651D01*
X182621Y162704D01*
X182162D01*
X181787Y162651D01*
X181454Y162518D01*
X181287Y162358D01*
X181204Y162171D01*
X181287Y161958D01*
X181454Y161798D01*
X181704Y161691D01*
X182037Y161638D01*
X182329Y161691D01*
X182621Y161824D01*
X182787Y161984D01*
X182829Y162171D01*
X182746Y162384D01*
X182537Y162544D01*
X182162Y162704D01*
G01X182662Y163864D02*
X182371Y164051D01*
X182204Y164211D01*
X182121Y164424D01*
X182204Y164611D01*
X182371Y164744D01*
X182621Y164851D01*
X182912Y164878D01*
X183162Y164851D01*
X183412Y164744D01*
X183621Y164584D01*
X183704Y164398D01*
X183621Y164184D01*
X183371Y163998D01*
X182996Y163891D01*
X182579Y163864D01*
X182037Y163918D01*
X181746Y163998D01*
X181454Y164131D01*
X181246Y164318D01*
X181204Y164504D01*
X181287Y164691D01*
X181496Y164824D01*
G01X191304Y159384D02*
X188804D01*
Y159918D01*
X188929Y160131D01*
X189096Y160291D01*
X189346Y160424D01*
X189637Y160531D01*
X190054Y160558D01*
X190471Y160531D01*
X190762Y160424D01*
X191012Y160291D01*
X191179Y160131D01*
X191304Y159918D01*
Y159384D01*
G01X191012Y161718D02*
X191221Y161904D01*
X191304Y162118D01*
X191221Y162331D01*
X190971Y162518D01*
X190596Y162651D01*
X190221Y162704D01*
X189762D01*
X189387Y162651D01*
X189054Y162518D01*
X188887Y162358D01*
X188804Y162171D01*
X188887Y161958D01*
X189054Y161798D01*
X189304Y161691D01*
X189637Y161638D01*
X189929Y161691D01*
X190221Y161824D01*
X190387Y161984D01*
X190429Y162171D01*
X190346Y162384D01*
X190137Y162544D01*
X189762Y162704D01*
G01X190929Y163784D02*
X191137Y163944D01*
X191262Y164131D01*
X191304Y164371D01*
X191221Y164611D01*
X191054Y164798D01*
X190762Y164931D01*
X190429Y164958D01*
X190096Y164904D01*
X189887Y164771D01*
X189721Y164584D01*
X189679Y164398D01*
X189721Y164211D01*
X189887Y163971D01*
X188804Y164051D01*
Y164771D01*
G01X184958Y186557D02*
X190958D01*
G01D02*
Y192557D01*
G01Y204179D02*
Y210179D01*
G01D02*
X184958D01*
G01X185383Y226000D02*
Y229100D01*
X186303D01*
X186610Y228945D01*
X186840Y228583D01*
X186917Y228170D01*
X186840Y227757D01*
X186648Y227447D01*
X186303Y227292D01*
X185383D01*
G01X189250Y226000D02*
Y229100D01*
X188790Y228480D01*
G01Y226000D02*
X189710D01*
G01X191622Y228583D02*
X191852Y228893D01*
X192120Y229048D01*
X192427Y229100D01*
X192810Y228997D01*
X193078Y228738D01*
X193155Y228428D01*
X193117Y228118D01*
X192963Y227860D01*
X192197Y227343D01*
X191852Y226982D01*
X191622Y226465D01*
X191545Y226000D01*
X193155D01*
G01X194492Y229100D02*
X195450Y226000D01*
X196408Y229100D01*
G01X197400Y224967D02*
X199700D01*
G01X200883Y226000D02*
Y229100D01*
X201803D01*
X202110Y228945D01*
X202340Y228583D01*
X202417Y228170D01*
X202340Y227757D01*
X202148Y227447D01*
X201803Y227292D01*
X200883D01*
G01X203945Y226413D02*
X204252Y226155D01*
X204597Y226000D01*
X204903D01*
X205210Y226155D01*
X205440Y226413D01*
X205555Y226775D01*
X205478Y227137D01*
X205287Y227447D01*
X204942Y227653D01*
X204482Y227757D01*
X204213Y227963D01*
X204098Y228325D01*
X204175Y228687D01*
X204367Y228945D01*
X204635Y229100D01*
X204903D01*
X205172Y228997D01*
X205402Y228738D01*
G01X207007Y229100D02*
Y226878D01*
X207160Y226413D01*
X207467Y226103D01*
X207850Y226000D01*
X208233Y226103D01*
X208540Y226413D01*
X208693Y226878D01*
Y229100D01*
G01X184000Y236500D02*
X211000D01*
Y224000D01*
X184000D01*
Y236500D01*
G01X185217Y231160D02*
Y234260D01*
X185983D01*
X186290Y234105D01*
X186520Y233898D01*
X186712Y233588D01*
X186865Y233227D01*
X186903Y232710D01*
X186865Y232193D01*
X186712Y231832D01*
X186520Y231522D01*
X186290Y231315D01*
X185983Y231160D01*
X185217D01*
G01X189160D02*
Y234260D01*
X188700Y233640D01*
G01Y231160D02*
X189620D01*
G01X192720D02*
Y234260D01*
X191302Y232038D01*
X193218D01*
G01X194517Y231780D02*
X194747Y231418D01*
X195053Y231212D01*
X195398Y231160D01*
X195705Y231212D01*
X196012Y231470D01*
X196203Y231780D01*
X196242Y232090D01*
X196165Y232452D01*
X195897Y232710D01*
X195628Y232813D01*
X195283D01*
G01X195628D02*
X195858Y232968D01*
X196050Y233227D01*
X196127Y233537D01*
X196050Y233847D01*
X195858Y234105D01*
X195513Y234260D01*
X195168Y234208D01*
X194823Y234002D01*
G01X179382Y391471D02*
Y394671D01*
G01X185582Y391471D02*
X179382D01*
G01X185582Y394671D02*
Y391471D01*
G01X179382Y394671D02*
X185582D01*
G01X179382Y383471D02*
Y386671D01*
G01X185582Y383471D02*
X179382D01*
G01X185582Y386671D02*
Y383471D01*
G01X179382Y386671D02*
X185582D01*
G01X179382Y387471D02*
Y390671D01*
G01X185582Y387471D02*
X179382D01*
G01X185582Y390671D02*
Y387471D01*
G01X179382Y390671D02*
X185582D01*
G01X178366Y407549D02*
Y413549D01*
G01X190366Y407549D02*
X178366D01*
G01X190366Y413549D02*
Y407549D01*
G01X179382Y403471D02*
Y406671D01*
G01X185582Y403471D02*
X179382D01*
G01X185582Y406671D02*
Y403471D01*
G01X179382Y406671D02*
X185582D01*
G01X178366Y413549D02*
X190366D01*
G01X183267Y414527D02*
Y419127D01*
G01X178767Y414527D02*
Y419127D01*
G01X188767Y414527D02*
Y419127D01*
G01X178767D02*
X188767D01*
G01X178767Y419027D02*
Y419127D01*
G01X188767Y414527D02*
X178767D01*
G01X184267D02*
Y419127D01*
G01X186496Y422983D02*
Y419783D01*
G01X180296Y422983D02*
X186496D01*
G01X180296Y419783D02*
Y422983D01*
G01X186496Y419783D02*
X180296D01*
G01X186496Y426983D02*
Y423783D01*
G01X180296Y426983D02*
X186496D01*
G01X180296Y423783D02*
Y426983D01*
G01X186496Y423783D02*
X180296D01*
G01X176996Y422983D02*
Y419783D01*
G01Y426983D02*
Y423783D01*
G01X186496Y444983D02*
Y441783D01*
G01X180296Y444983D02*
X186496D01*
G01X180296Y441783D02*
Y444983D01*
G01X186496Y441783D02*
X180296D01*
G01X176996Y444983D02*
Y441783D01*
G01X186496Y432483D02*
Y429283D01*
G01X180296Y432483D02*
X186496D01*
G01X180296Y429283D02*
Y432483D01*
G01X186496Y429283D02*
X180296D01*
G01X176996Y432483D02*
Y429283D01*
G01X188510Y574072D02*
X191710D01*
G01X188510Y567872D02*
Y574072D01*
G01X191710Y567872D02*
X188510D01*
G01X191710Y574072D02*
Y567872D01*
G01X189194Y577116D02*
X185786D01*
G01X189194Y594832D02*
Y577116D01*
G01X185786Y594832D02*
X189194D01*
G01X180273Y655530D02*
Y658630D01*
X181193D01*
X181500Y658475D01*
X181730Y658113D01*
X181807Y657700D01*
X181730Y657287D01*
X181538Y656977D01*
X181193Y656822D01*
X180273D01*
G01X183297Y658630D02*
Y656408D01*
X183450Y655943D01*
X183757Y655633D01*
X184140Y655530D01*
X184523Y655633D01*
X184830Y655943D01*
X184983Y656408D01*
Y658630D01*
G01X187240Y655530D02*
Y658630D01*
X186780Y658010D01*
G01Y655530D02*
X187700D01*
G01X190263D02*
X190340Y656202D01*
X190455Y656770D01*
X190608Y657287D01*
X190800Y657855D01*
X191107Y658630D01*
X189573D01*
G01X190451Y679691D02*
Y682891D01*
G01X196651Y679691D02*
X190451D01*
G01Y682891D02*
X196651D01*
G01X176843Y689642D02*
Y692742D01*
X177763D01*
X178070Y692587D01*
X178300Y692225D01*
X178377Y691812D01*
X178300Y691399D01*
X178108Y691089D01*
X177763Y690934D01*
X176843D01*
G01X179867Y692742D02*
Y690520D01*
X180020Y690055D01*
X180327Y689745D01*
X180710Y689642D01*
X181093Y689745D01*
X181400Y690055D01*
X181553Y690520D01*
Y692742D01*
G01X184270Y689642D02*
Y692742D01*
X182852Y690520D01*
X184768D01*
G01X186258Y690004D02*
X186527Y689745D01*
X186833Y689642D01*
X187140Y689745D01*
X187408Y690055D01*
X187600Y690520D01*
X187677Y690985D01*
Y691554D01*
X187600Y692019D01*
X187408Y692432D01*
X187178Y692639D01*
X186910Y692742D01*
X186603Y692639D01*
X186373Y692432D01*
X186220Y692122D01*
X186143Y691709D01*
X186220Y691347D01*
X186412Y690985D01*
X186642Y690779D01*
X186910Y690727D01*
X187217Y690830D01*
X187447Y691089D01*
X187677Y691554D01*
G01X189542Y688083D02*
Y691283D01*
G01X195742Y688083D02*
X189542D01*
G01X182667Y695026D02*
Y707026D01*
G01X188667Y695026D02*
X182667D01*
G01X188667Y707026D02*
Y695026D01*
G01X175825Y697211D02*
X181530D01*
G01X190730D02*
X201415D01*
G01X175825Y1315480D02*
Y697211D01*
G01X192867Y697926D02*
X189667D01*
G01Y704126D02*
X192867D01*
G01X189667Y697926D02*
Y704126D01*
G01X189542Y692023D02*
Y695223D01*
G01X195742Y692023D02*
X189542D01*
G01Y695223D02*
X195742D01*
G01X189542Y691283D02*
X195742D01*
G01X182667Y707026D02*
X188667D01*
G01X182423Y712756D02*
Y720186D01*
G01X201415Y732644D02*
X175825D01*
G01X201415Y1299574D02*
X175825D01*
G01X187013Y1337690D02*
Y1357375D01*
G01X192977Y1337690D02*
X187013D01*
G01X178441Y1377060D02*
Y1337690D01*
G01X178213Y1336902D02*
X178405Y1336592D01*
X178635Y1336385D01*
X178903Y1336282D01*
X179210Y1336385D01*
X179440Y1336592D01*
X179670Y1336902D01*
X179747Y1337315D01*
Y1339382D01*
G01X181352Y1338865D02*
X181582Y1339175D01*
X181850Y1339330D01*
X182157Y1339382D01*
X182540Y1339279D01*
X182808Y1339020D01*
X182885Y1338710D01*
X182847Y1338400D01*
X182693Y1338142D01*
X181927Y1337625D01*
X181582Y1337264D01*
X181352Y1336747D01*
X181275Y1336282D01*
X182885D01*
G01X185180Y1339382D02*
X184873Y1339279D01*
X184643Y1339020D01*
X184490Y1338710D01*
X184375Y1338297D01*
X184337Y1337832D01*
X184375Y1337367D01*
X184490Y1336954D01*
X184643Y1336644D01*
X184873Y1336385D01*
X185180Y1336282D01*
X185487Y1336385D01*
X185717Y1336644D01*
X185870Y1336954D01*
X185985Y1337367D01*
X186023Y1337832D01*
X185985Y1338297D01*
X185870Y1338710D01*
X185717Y1339020D01*
X185487Y1339279D01*
X185180Y1339382D01*
G01X201415Y1335007D02*
X189890D01*
G01X175825D02*
Y1333760D01*
G01X178450Y1335007D02*
X175825D01*
G01X184000Y1365745D02*
X180900D01*
Y1366665D01*
X181055Y1366972D01*
X181417Y1367202D01*
X181830Y1367279D01*
X182243Y1367202D01*
X182553Y1367010D01*
X182708Y1366665D01*
Y1365745D01*
G01X180900Y1368845D02*
X184000D01*
Y1370379D01*
G01Y1372712D02*
X180900D01*
X181520Y1372252D01*
G01X184000D02*
Y1373172D01*
G01X183638Y1375160D02*
X183897Y1375429D01*
X184000Y1375735D01*
X183897Y1376042D01*
X183587Y1376310D01*
X183122Y1376502D01*
X182657Y1376579D01*
X182088D01*
X181623Y1376502D01*
X181210Y1376310D01*
X181003Y1376080D01*
X180900Y1375812D01*
X181003Y1375505D01*
X181210Y1375275D01*
X181520Y1375122D01*
X181933Y1375045D01*
X182295Y1375122D01*
X182657Y1375314D01*
X182863Y1375544D01*
X182915Y1375812D01*
X182812Y1376119D01*
X182553Y1376349D01*
X182088Y1376579D01*
G01X187013Y1357375D02*
Y1377060D01*
G01D02*
X192927D01*
G01X186111Y1388070D02*
Y1394270D01*
G01X189311Y1388070D02*
X186111D01*
G01X189311Y1394270D02*
Y1388070D01*
G01Y1398570D02*
X186111D01*
G01X189311Y1404770D02*
Y1398570D01*
G01X186111Y1404770D02*
X189311D01*
G01X186111Y1398570D02*
Y1404770D01*
G01Y1394270D02*
X189311D01*
G01X180206Y1395290D02*
X183406D01*
G01X180206Y1389090D02*
Y1395290D01*
G01X183406Y1389090D02*
X180206D01*
G01X183406Y1395290D02*
Y1389090D01*
G01X176102Y1395290D02*
X179302D01*
G01X176102Y1389090D02*
Y1395290D01*
G01X179302Y1389090D02*
X176102D01*
G01X179302Y1395290D02*
Y1389090D01*
G01X186543Y1412915D02*
Y1406915D01*
G01X180513Y1424673D02*
Y1421265D01*
G01X189349Y1413059D02*
X192549D01*
G01X189349Y1406859D02*
Y1413059D01*
G01X192549Y1406859D02*
X189349D01*
G01X213623Y1430034D02*
G03I-13386J0D01*
G01X180513Y1438981D02*
Y1435573D01*
G01X197550Y1533777D02*
X191350D01*
Y1536977D01*
X197550D01*
Y1533777D01*
G01X178382Y1537062D02*
X184582D01*
Y1533862D01*
X178382D01*
Y1537062D01*
G01X178268Y1542428D02*
Y1545628D01*
G01X184468Y1542428D02*
X178268D01*
G01X184468Y1545628D02*
Y1542428D01*
G01X178268Y1545628D02*
X184468D01*
G01X197491Y1538078D02*
X191291D01*
Y1541278D01*
X197491D01*
Y1538078D01*
G01X178348Y1550086D02*
X184548D01*
Y1546886D01*
X178348D01*
Y1550086D01*
G01X197291Y1551340D02*
X191091D01*
Y1554540D01*
X197291D01*
Y1551340D01*
G01X197383Y1546830D02*
X191183D01*
Y1550030D01*
X197383D01*
Y1546830D01*
G01X178339Y1554474D02*
X184539D01*
Y1551274D01*
X178339D01*
Y1554474D01*
G01X178371Y1541323D02*
X184571D01*
Y1538123D01*
X178371D01*
Y1541323D01*
G01X178339Y1559474D02*
X184539D01*
Y1556274D01*
X178339D01*
Y1559474D01*
G01X178393Y1584074D02*
Y1577874D01*
G01X185018Y1717517D02*
Y1705517D01*
G01X181618Y1717517D02*
X185018D01*
G01X179618Y1715517D02*
X181618Y1717517D01*
G01X177618D02*
X179618Y1715517D01*
G01X191768Y1718097D02*
Y1721297D01*
G01X197968Y1718097D02*
X191768D01*
G01Y1721297D02*
X197968D01*
G01X180467Y1721992D02*
Y1725192D01*
G01X186667Y1721992D02*
X180467D01*
G01X186667Y1725192D02*
Y1721992D01*
G01X180467Y1725192D02*
X186667D01*
G01X179667D02*
Y1721992D01*
G01X176667Y1734692D02*
Y1728492D01*
G01X186667Y1730692D02*
Y1727492D01*
G01X180467D02*
Y1730692D01*
G01X186667Y1727492D02*
X180467D01*
G01Y1730692D02*
X186667D01*
G01Y1734692D02*
Y1731492D01*
G01X180467Y1734692D02*
X186667D01*
G01X180467Y1731492D02*
Y1734692D01*
G01X186667Y1731492D02*
X180467D01*
G01X204579Y-507370D02*
X205379Y-508036D01*
X206279Y-508436D01*
X207079D01*
X207879Y-508036D01*
X208479Y-507370D01*
X208779Y-506436D01*
X208579Y-505503D01*
X208079Y-504703D01*
X207179Y-504169D01*
X205979Y-503903D01*
X205279Y-503369D01*
X204979Y-502436D01*
X205179Y-501503D01*
X205679Y-500836D01*
X206379Y-500436D01*
X207079D01*
X207779Y-500703D01*
X208379Y-501369D01*
G01X213479Y-500436D02*
X215879D01*
G01X214679D02*
Y-508436D01*
G01X213479D02*
X215879D01*
G01X220679Y-500436D02*
Y-508436D01*
X224679D01*
G01X228479D02*
Y-500436D01*
G01X232279D02*
X228479Y-505370D01*
G01X232879Y-508436D02*
X230179Y-503103D01*
G01X237379Y-505769D02*
X239979D01*
G01X246679Y-500436D02*
Y-508436D01*
G01X244379Y-500436D02*
X248979D01*
G01X254679Y-508436D02*
X253879Y-508303D01*
X253179Y-507769D01*
X252579Y-506969D01*
X252179Y-506036D01*
X251979Y-504969D01*
Y-503903D01*
X252179Y-502836D01*
X252579Y-501903D01*
X253179Y-501103D01*
X253879Y-500569D01*
X254679Y-500436D01*
X255479Y-500569D01*
X256179Y-501103D01*
X256779Y-501903D01*
X257179Y-502836D01*
X257379Y-503903D01*
Y-504969D01*
X257179Y-506036D01*
X256779Y-506969D01*
X256179Y-507769D01*
X255479Y-508303D01*
X254679Y-508436D01*
G01X260679D02*
Y-500436D01*
X263079D01*
X263879Y-500836D01*
X264479Y-501769D01*
X264679Y-502836D01*
X264479Y-503903D01*
X263979Y-504703D01*
X263079Y-505103D01*
X260679D01*
G01X199650Y-473979D02*
Y-481979D01*
X203650D01*
G01X211450D02*
Y-476646D01*
G01Y-477579D02*
X211050Y-477046D01*
X210450Y-476779D01*
X209750Y-476646D01*
X209050Y-476912D01*
X208450Y-477446D01*
X208050Y-478246D01*
X207850Y-479312D01*
X208050Y-480379D01*
X208450Y-481179D01*
X209050Y-481712D01*
X209750Y-481979D01*
X210450Y-481846D01*
X211050Y-481446D01*
X211450Y-480913D01*
G01X215550Y-484379D02*
X216150Y-484646D01*
X216950Y-484379D01*
X217450Y-483846D01*
X217850Y-483179D01*
X218450Y-481046D01*
X219750Y-476646D01*
G01X216550D02*
X218450Y-481046D01*
G01X224150Y-478379D02*
X227350D01*
X227050Y-477446D01*
X226550Y-476912D01*
X225850Y-476646D01*
X225150Y-476779D01*
X224550Y-477179D01*
X224150Y-478112D01*
X223950Y-478913D01*
Y-479712D01*
X224150Y-480512D01*
X224650Y-481312D01*
X225250Y-481846D01*
X225950Y-481979D01*
X226650Y-481712D01*
X227350Y-480913D01*
G01X232250Y-481979D02*
Y-476646D01*
G01Y-477712D02*
X232750Y-477179D01*
X233250Y-476779D01*
X233950Y-476646D01*
X234450Y-476779D01*
X235050Y-477179D01*
G01X211796Y51139D02*
X207328D01*
G01X204808D02*
X200500D01*
G01X207110Y79632D02*
X214110D01*
G01X207110D02*
Y126632D01*
G01X200110Y79632D02*
X207110D01*
G01X193110D02*
X200110D01*
G01D02*
Y126632D01*
G01X193110Y79632D02*
Y126632D01*
G01X204610Y81345D02*
X202110D01*
Y81879D01*
X202235Y82092D01*
X202402Y82252D01*
X202652Y82385D01*
X202943Y82492D01*
X203360Y82519D01*
X203777Y82492D01*
X204068Y82385D01*
X204318Y82252D01*
X204485Y82092D01*
X204610Y81879D01*
Y81345D01*
G01Y84132D02*
X204568Y84319D01*
X204443Y84532D01*
X204235Y84665D01*
X203943Y84719D01*
X203652Y84665D01*
X203402Y84505D01*
X203277Y84265D01*
Y83999D01*
X203193Y83839D01*
X202985Y83705D01*
X202693Y83652D01*
X202402Y83732D01*
X202193Y83919D01*
X202110Y84132D01*
X202193Y84345D01*
X202402Y84532D01*
X202693Y84612D01*
X202985Y84559D01*
X203193Y84425D01*
X203277Y84265D01*
Y83999D01*
X203402Y83759D01*
X203652Y83599D01*
X203943Y83545D01*
X204235Y83599D01*
X204443Y83732D01*
X204568Y83945D01*
X204610Y84132D01*
G01X204235Y85745D02*
X204443Y85905D01*
X204568Y86092D01*
X204610Y86332D01*
X204527Y86572D01*
X204360Y86759D01*
X204068Y86892D01*
X203735Y86919D01*
X203402Y86865D01*
X203193Y86732D01*
X203027Y86545D01*
X202985Y86359D01*
X203027Y86172D01*
X203193Y85932D01*
X202110Y86012D01*
Y86732D01*
G01X197610Y81345D02*
X195110D01*
Y81879D01*
X195235Y82092D01*
X195402Y82252D01*
X195652Y82385D01*
X195943Y82492D01*
X196360Y82519D01*
X196777Y82492D01*
X197068Y82385D01*
X197318Y82252D01*
X197485Y82092D01*
X197610Y81879D01*
Y81345D01*
G01Y84079D02*
X197068Y84132D01*
X196610Y84212D01*
X196193Y84319D01*
X195735Y84452D01*
X195110Y84665D01*
Y83599D01*
G01X197318Y85879D02*
X197527Y86065D01*
X197610Y86279D01*
X197527Y86492D01*
X197277Y86679D01*
X196902Y86812D01*
X196527Y86865D01*
X196068D01*
X195693Y86812D01*
X195360Y86679D01*
X195193Y86519D01*
X195110Y86332D01*
X195193Y86119D01*
X195360Y85959D01*
X195610Y85852D01*
X195943Y85799D01*
X196235Y85852D01*
X196527Y85985D01*
X196693Y86145D01*
X196735Y86332D01*
X196652Y86545D01*
X196443Y86705D01*
X196068Y86865D01*
G01X197610Y101399D02*
X195110D01*
Y102039D01*
X195235Y102252D01*
X195527Y102412D01*
X195860Y102465D01*
X196193Y102412D01*
X196443Y102279D01*
X196568Y102039D01*
Y101399D01*
G01X195110Y103465D02*
X197610Y104132D01*
X195110Y104799D01*
G01X195318Y106919D02*
X195193Y106759D01*
X195110Y106572D01*
Y106359D01*
X195235Y106119D01*
X195443Y105932D01*
X195693Y105799D01*
X196110Y105692D01*
X196485Y105665D01*
X196860Y105719D01*
X197110Y105799D01*
X197360Y105959D01*
X197527Y106145D01*
X197610Y106332D01*
Y106519D01*
X197527Y106705D01*
X197402Y106865D01*
X197235Y106999D01*
G01X195318Y109119D02*
X195193Y108959D01*
X195110Y108772D01*
Y108559D01*
X195235Y108319D01*
X195443Y108132D01*
X195693Y107999D01*
X196110Y107892D01*
X196485Y107865D01*
X196860Y107919D01*
X197110Y107999D01*
X197360Y108159D01*
X197527Y108345D01*
X197610Y108532D01*
Y108719D01*
X197527Y108905D01*
X197402Y109065D01*
X197235Y109199D01*
G01X195110Y110412D02*
Y111052D01*
G01Y110732D02*
X197610D01*
G01Y110412D02*
Y111052D01*
G01Y112319D02*
X195110D01*
X197610Y113545D01*
X195110D01*
G01X198443Y114332D02*
Y115932D01*
G01X195318Y117919D02*
X195193Y117759D01*
X195110Y117572D01*
Y117359D01*
X195235Y117119D01*
X195443Y116932D01*
X195693Y116799D01*
X196110Y116692D01*
X196485Y116665D01*
X196860Y116719D01*
X197110Y116799D01*
X197360Y116959D01*
X197527Y117145D01*
X197610Y117332D01*
Y117519D01*
X197527Y117705D01*
X197402Y117865D01*
X197235Y117999D01*
G01X197610Y118999D02*
X195110D01*
Y119639D01*
X195235Y119852D01*
X195527Y120012D01*
X195860Y120065D01*
X196193Y120012D01*
X196443Y119879D01*
X196568Y119639D01*
Y118999D01*
G01X195110Y121145D02*
X196902D01*
X197277Y121252D01*
X197527Y121465D01*
X197610Y121732D01*
X197527Y121999D01*
X197277Y122212D01*
X196902Y122319D01*
X195110D01*
G01Y123932D02*
X195193Y123719D01*
X195402Y123559D01*
X195652Y123452D01*
X195985Y123372D01*
X196360Y123345D01*
X196735Y123372D01*
X197068Y123452D01*
X197318Y123559D01*
X197527Y123719D01*
X197610Y123932D01*
X197527Y124145D01*
X197318Y124305D01*
X197068Y124412D01*
X196735Y124492D01*
X196360Y124519D01*
X195985Y124492D01*
X195652Y124412D01*
X195402Y124305D01*
X195193Y124145D01*
X195110Y123932D01*
G01X204610Y94899D02*
X202110D01*
Y95539D01*
X202235Y95752D01*
X202527Y95912D01*
X202860Y95965D01*
X203193Y95912D01*
X203443Y95779D01*
X203568Y95539D01*
Y94899D01*
G01X202110Y96965D02*
X204610Y97632D01*
X202110Y98299D01*
G01X204610Y99219D02*
X202110D01*
X204610Y100445D01*
X202110D01*
G01X204610Y101419D02*
X202110D01*
X204610Y102645D01*
X202110D01*
G01X205443Y103432D02*
Y105032D01*
G01X204610Y105739D02*
X202110D01*
X204193Y106432D01*
X202110Y107125D01*
X204610D01*
G01Y107965D02*
X202110Y108632D01*
X204610Y109299D01*
G01X203735Y109059D02*
Y108205D01*
G01X202110Y110512D02*
Y111152D01*
G01Y110832D02*
X204610D01*
G01Y110512D02*
Y111152D01*
G01Y112419D02*
X202110D01*
X204610Y113645D01*
X202110D01*
G01X205443Y114432D02*
Y116032D01*
G01X202318Y118019D02*
X202193Y117859D01*
X202110Y117672D01*
Y117459D01*
X202235Y117219D01*
X202443Y117032D01*
X202693Y116899D01*
X203110Y116792D01*
X203485Y116765D01*
X203860Y116819D01*
X204110Y116899D01*
X204360Y117059D01*
X204527Y117245D01*
X204610Y117432D01*
Y117619D01*
X204527Y117805D01*
X204402Y117965D01*
X204235Y118099D01*
G01X204610Y119099D02*
X202110D01*
Y119739D01*
X202235Y119952D01*
X202527Y120112D01*
X202860Y120165D01*
X203193Y120112D01*
X203443Y119979D01*
X203568Y119739D01*
Y119099D01*
G01X202110Y121245D02*
X203902D01*
X204277Y121352D01*
X204527Y121565D01*
X204610Y121832D01*
X204527Y122099D01*
X204277Y122312D01*
X203902Y122419D01*
X202110D01*
G01X204610Y124032D02*
X202110D01*
X202610Y123712D01*
G01X204610D02*
Y124352D01*
G01Y135399D02*
X202110D01*
Y136065D01*
X202235Y136279D01*
X202402Y136412D01*
X202735Y136465D01*
X203068Y136412D01*
X203277Y136252D01*
X203402Y136065D01*
Y135399D01*
G01Y136065D02*
X204610Y136465D01*
G01X204277Y137572D02*
X204485Y137785D01*
X204610Y138025D01*
Y138239D01*
X204485Y138452D01*
X204277Y138612D01*
X203985Y138692D01*
X203693Y138639D01*
X203443Y138505D01*
X203277Y138265D01*
X203193Y137945D01*
X203027Y137759D01*
X202735Y137679D01*
X202443Y137732D01*
X202235Y137865D01*
X202110Y138052D01*
Y138239D01*
X202193Y138425D01*
X202402Y138585D01*
G01X202110Y140332D02*
X204610D01*
G01X202110Y139719D02*
Y140945D01*
G01X205443Y141732D02*
Y143332D01*
G01X204610Y144199D02*
X202110D01*
Y144865D01*
X202235Y145079D01*
X202402Y145212D01*
X202735Y145265D01*
X203068Y145212D01*
X203277Y145052D01*
X203402Y144865D01*
Y144199D01*
G01Y144865D02*
X204610Y145265D01*
G01X204277Y146372D02*
X204485Y146585D01*
X204610Y146825D01*
Y147039D01*
X204485Y147252D01*
X204277Y147412D01*
X203985Y147492D01*
X203693Y147439D01*
X203443Y147305D01*
X203277Y147065D01*
X203193Y146745D01*
X203027Y146559D01*
X202735Y146479D01*
X202443Y146532D01*
X202235Y146665D01*
X202110Y146852D01*
Y147039D01*
X202193Y147225D01*
X202402Y147385D01*
G01X204610Y148439D02*
X202110D01*
X204193Y149132D01*
X202110Y149825D01*
X204610D01*
G01Y150799D02*
X202110D01*
Y151465D01*
X202235Y151679D01*
X202402Y151812D01*
X202735Y151865D01*
X203068Y151812D01*
X203277Y151652D01*
X203402Y151465D01*
Y150799D01*
G01Y151465D02*
X204610Y151865D01*
G01X204277Y152972D02*
X204485Y153185D01*
X204610Y153425D01*
Y153639D01*
X204485Y153852D01*
X204277Y154012D01*
X203985Y154092D01*
X203693Y154039D01*
X203443Y153905D01*
X203277Y153665D01*
X203193Y153345D01*
X203027Y153159D01*
X202735Y153079D01*
X202443Y153132D01*
X202235Y153265D01*
X202110Y153452D01*
Y153639D01*
X202193Y153825D01*
X202402Y153985D01*
G01X202110Y155732D02*
X204610D01*
G01X202110Y155119D02*
Y156345D01*
G01X193110Y166632D02*
Y126632D01*
G01X200110Y166632D02*
Y126632D01*
G01X207110Y166632D02*
Y126632D01*
G01X214110D02*
X207110D01*
G01D02*
X200110D01*
G01D02*
X193110D01*
G01X197277Y143872D02*
X197485Y144085D01*
X197610Y144325D01*
Y144539D01*
X197485Y144752D01*
X197277Y144912D01*
X196985Y144992D01*
X196693Y144939D01*
X196443Y144805D01*
X196277Y144565D01*
X196193Y144245D01*
X196027Y144059D01*
X195735Y143979D01*
X195443Y144032D01*
X195235Y144165D01*
X195110Y144352D01*
Y144539D01*
X195193Y144725D01*
X195402Y144885D01*
G01X195110Y146099D02*
X197610D01*
Y147165D01*
G01Y148299D02*
X195110D01*
Y148939D01*
X195235Y149152D01*
X195527Y149312D01*
X195860Y149365D01*
X196193Y149312D01*
X196443Y149179D01*
X196568Y148939D01*
Y148299D01*
G01X198443Y150232D02*
Y151832D01*
G01X197277Y152672D02*
X197485Y152885D01*
X197610Y153125D01*
Y153339D01*
X197485Y153552D01*
X197277Y153712D01*
X196985Y153792D01*
X196693Y153739D01*
X196443Y153605D01*
X196277Y153365D01*
X196193Y153045D01*
X196027Y152859D01*
X195735Y152779D01*
X195443Y152832D01*
X195235Y152965D01*
X195110Y153152D01*
Y153339D01*
X195193Y153525D01*
X195402Y153685D01*
G01X197610Y155752D02*
X195110D01*
X196902Y154765D01*
Y156099D01*
G01X207110Y166632D02*
X214110D01*
G01X200110D02*
X207110D01*
G01X193110D02*
X200110D01*
G01X197904Y159384D02*
X195404D01*
Y159918D01*
X195529Y160131D01*
X195696Y160291D01*
X195946Y160424D01*
X196237Y160531D01*
X196654Y160558D01*
X197071Y160531D01*
X197362Y160424D01*
X197612Y160291D01*
X197779Y160131D01*
X197904Y159918D01*
Y159384D01*
G01X197612Y161718D02*
X197821Y161904D01*
X197904Y162118D01*
X197821Y162331D01*
X197571Y162518D01*
X197196Y162651D01*
X196821Y162704D01*
X196362D01*
X195987Y162651D01*
X195654Y162518D01*
X195487Y162358D01*
X195404Y162171D01*
X195487Y161958D01*
X195654Y161798D01*
X195904Y161691D01*
X196237Y161638D01*
X196529Y161691D01*
X196821Y161824D01*
X196987Y161984D01*
X197029Y162171D01*
X196946Y162384D01*
X196737Y162544D01*
X196362Y162704D01*
G01X197904Y164691D02*
X195404D01*
X197196Y163704D01*
Y165038D01*
G01X204504Y159384D02*
X202004D01*
Y159918D01*
X202129Y160131D01*
X202296Y160291D01*
X202546Y160424D01*
X202837Y160531D01*
X203254Y160558D01*
X203671Y160531D01*
X203962Y160424D01*
X204212Y160291D01*
X204379Y160131D01*
X204504Y159918D01*
Y159384D01*
G01X204212Y161718D02*
X204421Y161904D01*
X204504Y162118D01*
X204421Y162331D01*
X204171Y162518D01*
X203796Y162651D01*
X203421Y162704D01*
X202962D01*
X202587Y162651D01*
X202254Y162518D01*
X202087Y162358D01*
X202004Y162171D01*
X202087Y161958D01*
X202254Y161798D01*
X202504Y161691D01*
X202837Y161638D01*
X203129Y161691D01*
X203421Y161824D01*
X203587Y161984D01*
X203629Y162171D01*
X203546Y162384D01*
X203337Y162544D01*
X202962Y162704D01*
G01X204004Y163784D02*
X204296Y163944D01*
X204462Y164158D01*
X204504Y164398D01*
X204462Y164611D01*
X204254Y164824D01*
X204004Y164958D01*
X203754Y164984D01*
X203462Y164931D01*
X203254Y164744D01*
X203171Y164558D01*
Y164318D01*
G01Y164558D02*
X203046Y164718D01*
X202837Y164851D01*
X202587Y164904D01*
X202337Y164851D01*
X202129Y164718D01*
X202004Y164478D01*
X202046Y164238D01*
X202212Y163998D01*
G01X200024Y418655D02*
Y421855D01*
G01X206224Y418655D02*
X200024D01*
G01X206224Y421855D02*
Y418655D01*
G01X200024Y421855D02*
X206224D01*
G01X200024Y413155D02*
Y416355D01*
G01X206224Y413155D02*
X200024D01*
G01X206224Y416355D02*
Y413155D01*
G01X200024Y416355D02*
X206224D01*
G01X200024Y424155D02*
Y427355D01*
G01X206224Y424155D02*
X200024D01*
G01X206224Y427355D02*
Y424155D01*
G01X200024Y427355D02*
X206224D01*
G01X200024Y435155D02*
Y438355D01*
G01X206224Y435155D02*
X200024D01*
G01X206224Y438355D02*
Y435155D01*
G01X200024Y438355D02*
X206224D01*
G01X200024Y429655D02*
Y432855D01*
G01X206224Y429655D02*
X200024D01*
G01X206224Y432855D02*
Y429655D01*
G01X200024Y432855D02*
X206224D01*
G01X200024Y440655D02*
Y443855D01*
G01X206224Y440655D02*
X200024D01*
G01X206224Y443855D02*
Y440655D01*
G01X200024Y443855D02*
X206224D01*
G01X200024Y446155D02*
Y449355D01*
G01X206224Y446155D02*
X200024D01*
G01X206224Y449355D02*
Y446155D01*
G01X200024Y449355D02*
X206224D01*
G01X200024Y451655D02*
Y454855D01*
G01X206224Y451655D02*
X200024D01*
G01X206224Y454855D02*
Y451655D01*
G01X200024Y454855D02*
X206224D01*
G01X200024Y457155D02*
Y460355D01*
G01X206224Y457155D02*
X200024D01*
G01X206224Y460355D02*
Y457155D01*
G01X200024Y460355D02*
X206224D01*
G01X200024Y461155D02*
Y464355D01*
G01X206224Y461155D02*
X200024D01*
G01X206224Y464355D02*
Y461155D01*
G01X200024Y464355D02*
X206224D01*
G01X200024Y466655D02*
Y469855D01*
G01X206224Y466655D02*
X200024D01*
G01X206224Y469855D02*
Y466655D01*
G01X200024Y469855D02*
X206224D01*
G01X200246Y557842D02*
Y560942D01*
X201166D01*
X201473Y560787D01*
X201703Y560425D01*
X201780Y560012D01*
X201703Y559599D01*
X201511Y559289D01*
X201166Y559134D01*
X200246D01*
G01X203270Y560942D02*
Y558720D01*
X203423Y558255D01*
X203730Y557945D01*
X204113Y557842D01*
X204496Y557945D01*
X204803Y558255D01*
X204956Y558720D01*
Y560942D01*
G01X206370Y558307D02*
X206600Y558049D01*
X206868Y557894D01*
X207213Y557842D01*
X207558Y557945D01*
X207826Y558152D01*
X208018Y558514D01*
X208056Y558927D01*
X207980Y559340D01*
X207788Y559599D01*
X207520Y559805D01*
X207251Y559857D01*
X206983Y559805D01*
X206638Y559599D01*
X206753Y560942D01*
X207788D01*
G01X210313Y557842D02*
Y560942D01*
X209853Y560322D01*
G01Y557842D02*
X210773D01*
G01X212263Y556809D02*
X214563D01*
G01X215746Y557842D02*
Y560942D01*
X216666D01*
X216973Y560787D01*
X217203Y560425D01*
X217280Y560012D01*
X217203Y559599D01*
X217011Y559289D01*
X216666Y559134D01*
X215746D01*
G01X219613Y557842D02*
Y560942D01*
X219153Y560322D01*
G01Y557842D02*
X220073D01*
G01X221563Y556809D02*
X223863D01*
G01X225085Y560425D02*
X225315Y560735D01*
X225583Y560890D01*
X225890Y560942D01*
X226273Y560839D01*
X226541Y560580D01*
X226618Y560270D01*
X226580Y559960D01*
X226426Y559702D01*
X225660Y559185D01*
X225315Y558824D01*
X225085Y558307D01*
X225008Y557842D01*
X226618D01*
G01X204329Y572212D02*
Y573220D01*
G01X206183Y572212D02*
X204329D01*
G01X203291Y569581D02*
X209491D01*
G01X203291Y566381D02*
Y569581D01*
G01X209491Y566381D02*
X203291D01*
G01X195001Y569301D02*
Y572501D01*
G01X201201Y569301D02*
X195001D01*
G01X201201Y572501D02*
Y569301D01*
G01X195001Y572501D02*
X201201D01*
G01X197488Y573871D02*
X194288D01*
G01X197488Y580071D02*
Y573871D01*
G01X194288D02*
Y580071D01*
G01X204329Y591165D02*
Y591898D01*
G01X195473Y587279D02*
Y590479D01*
G01X201673Y587279D02*
X195473D01*
G01X201673Y590479D02*
Y587279D01*
G01X195473Y590479D02*
X201673D01*
G01X201665Y586391D02*
Y583191D01*
G01X195465Y586391D02*
X201665D01*
G01X195465Y583191D02*
Y586391D01*
G01X201665Y583191D02*
X195465D01*
G01X194288Y580071D02*
X197488D01*
G01X204329Y591898D02*
X206520D01*
G01X206183Y606212D02*
X204329D01*
Y607220D01*
G01X203291Y603581D02*
X209491D01*
G01X203291Y600381D02*
Y603581D01*
G01X209491Y600381D02*
X203291D01*
G01X201541Y595973D02*
X198341D01*
G01X201541Y602173D02*
Y595973D01*
G01X198341Y602173D02*
X201541D01*
G01X198341Y595973D02*
Y602173D01*
G01X195001Y603301D02*
Y606501D01*
G01X201201Y603301D02*
X195001D01*
G01X201201Y606501D02*
Y603301D01*
G01X195001Y606501D02*
X201201D01*
G01X197488Y607871D02*
X194288D01*
G01X197488Y614071D02*
Y607871D01*
G01X194288D02*
Y614071D01*
G01X195473Y621279D02*
Y624479D01*
G01X201673Y621279D02*
X195473D01*
G01X201673Y624479D02*
Y621279D01*
G01X201665Y620391D02*
Y617191D01*
G01X195465Y620391D02*
X201665D01*
G01X195465Y617191D02*
Y620391D01*
G01X201665Y617191D02*
X195465D01*
G01X194288Y614071D02*
X197488D01*
G01X206183Y640212D02*
X204329D01*
Y641220D01*
G01Y625165D02*
Y625898D01*
X206520D01*
G01X203291Y637581D02*
X209491D01*
G01X203291Y634381D02*
Y637581D01*
G01X209491Y634381D02*
X203291D01*
G01X195001Y637301D02*
Y640501D01*
G01X201201Y637301D02*
X195001D01*
G01X201201Y640501D02*
Y637301D01*
G01X195001Y640501D02*
X201201D01*
G01X195473Y624479D02*
X201673D01*
G01X201541Y629973D02*
X198341D01*
G01X201541Y636173D02*
Y629973D01*
G01X198341Y636173D02*
X201541D01*
G01X198341Y629973D02*
Y636173D01*
G01X195473Y655279D02*
Y658479D01*
G01X201673Y655279D02*
X195473D01*
G01X201673Y658479D02*
Y655279D01*
G01X197488Y641871D02*
X194288D01*
G01X197488Y648071D02*
Y641871D01*
G01X194288Y648071D02*
X197488D01*
G01X194288Y641871D02*
Y648071D01*
G01X201665Y654391D02*
Y651191D01*
G01X195465Y654391D02*
X201665D01*
G01X195465Y651191D02*
Y654391D01*
G01X201665Y651191D02*
X195465D01*
G01X204329Y659165D02*
Y659898D01*
X206520D01*
G01X203720Y668462D02*
Y674662D01*
G01X206920Y668462D02*
X203720D01*
G01X206920Y674662D02*
Y668462D01*
G01X195473Y658479D02*
X201673D01*
G01X195061Y665043D02*
X191861D01*
G01X195061Y671243D02*
Y665043D01*
G01X191861Y671243D02*
X195061D01*
G01X191861Y665043D02*
Y671243D01*
G01X199620Y668462D02*
Y674662D01*
G01X202820Y668462D02*
X199620D01*
G01X202820Y674662D02*
Y668462D01*
G01X203720Y674662D02*
X206920D01*
G01X196651Y682891D02*
Y679691D01*
G01X199374Y679583D02*
Y677877D01*
G01D02*
X201040D01*
G01X199620Y674662D02*
X202820D01*
G01X195742Y691283D02*
Y688083D01*
G01X198270Y676692D02*
Y673492D01*
G01X192070Y676692D02*
X198270D01*
G01X192070Y673492D02*
Y676692D01*
G01X198270Y673492D02*
X192070D01*
G01X205525Y697211D02*
X231115D01*
G01X205525Y1312500D02*
Y697211D01*
G01X201415D02*
Y1313660D01*
G01X192867Y704126D02*
Y697926D01*
G01X195742Y695223D02*
Y692023D01*
G01X197067Y697926D02*
X193867D01*
G01X197067Y704126D02*
Y697926D01*
G01X193867Y704126D02*
X197067D01*
G01X193867Y697926D02*
Y704126D01*
G01X201611Y694019D02*
X199374D01*
G01D02*
Y693494D01*
G01X231115Y732644D02*
X205525D01*
G01X231115Y1299574D02*
X205525D01*
G01X219074Y1324715D02*
G03I-10827J0D01*
G01X201415Y1333710D02*
Y1335007D01*
G01X219074Y1324715D02*
X197420D01*
G01X191942Y1380110D02*
Y1382710D01*
G01X192735Y1380110D02*
X191942D01*
G01Y1403732D02*
X192950D01*
G01X191942Y1401878D02*
Y1403732D01*
G01Y1389321D02*
Y1391019D01*
G01X206116Y1413345D02*
X209316D01*
G01X206116Y1407145D02*
Y1413345D01*
G01X209316Y1407145D02*
X206116D01*
G01X192549Y1413059D02*
Y1406859D01*
G01X193601Y1410573D02*
Y1413773D01*
G01X199801Y1410573D02*
X193601D01*
G01X199801Y1413773D02*
Y1410573D01*
G01X193601Y1413773D02*
X199801D01*
G01X205774Y1407145D02*
X202574D01*
G01X205774Y1413345D02*
Y1407145D01*
G01X202574Y1413345D02*
X205774D01*
G01X202574Y1407145D02*
Y1413345D01*
G01X200237Y1416648D02*
Y1443420D01*
G01X199839Y1695079D02*
X200031Y1694769D01*
X200261Y1694562D01*
X200529Y1694459D01*
X200836Y1694562D01*
X201066Y1694769D01*
X201296Y1695079D01*
X201373Y1695492D01*
Y1697559D01*
G01X203706Y1694459D02*
Y1697559D01*
X203246Y1696939D01*
G01Y1694459D02*
X204166D01*
G01X206806D02*
Y1697559D01*
X206346Y1696939D01*
G01Y1694459D02*
X207266D01*
G01X209178Y1697042D02*
X209408Y1697352D01*
X209676Y1697507D01*
X209983Y1697559D01*
X210366Y1697456D01*
X210634Y1697197D01*
X210711Y1696887D01*
X210673Y1696577D01*
X210519Y1696319D01*
X209753Y1695802D01*
X209408Y1695441D01*
X209178Y1694924D01*
X209101Y1694459D01*
X210711D01*
G01X203620Y1711462D02*
X209820D01*
G01X203620Y1708262D02*
Y1711462D01*
G01X209820Y1708262D02*
X203620D01*
G01X203518Y1712417D02*
Y1715617D01*
G01X209718Y1712417D02*
X203518D01*
G01X202320Y1708762D02*
X199120D01*
G01X202320Y1714962D02*
Y1708762D01*
G01X199120D02*
Y1714962D01*
G01X197968Y1721297D02*
Y1718097D01*
G01X203518Y1716417D02*
Y1719617D01*
G01X209718Y1716417D02*
X203518D01*
G01Y1719617D02*
X209718D01*
G01X203518Y1715617D02*
X209718D01*
G01X199120Y1714962D02*
X202320D01*
G01X197525Y1731422D02*
Y1734622D01*
G01X203725Y1731422D02*
X197525D01*
G01X203725Y1734622D02*
Y1731422D01*
G01X197525Y1734622D02*
X203725D01*
G01X223350Y-531979D02*
Y-523979D01*
X227950Y-531979D01*
Y-523979D01*
G01X233650Y-526646D02*
Y-531979D01*
G01Y-524512D02*
X233450Y-524379D01*
Y-524112D01*
X233650Y-523979D01*
X233850Y-524112D01*
Y-524379D01*
X233650Y-524512D01*
G01X239950Y-531979D02*
Y-526646D01*
G01Y-527979D02*
X240350Y-527312D01*
X240950Y-526779D01*
X241750Y-526646D01*
X242450Y-526779D01*
X243050Y-527312D01*
X243350Y-528246D01*
Y-531979D01*
G01X251450D02*
Y-526646D01*
G01Y-527579D02*
X251050Y-527046D01*
X250450Y-526779D01*
X249750Y-526646D01*
X249050Y-526912D01*
X248450Y-527446D01*
X248050Y-528246D01*
X247850Y-529312D01*
X248050Y-530379D01*
X248450Y-531179D01*
X249050Y-531712D01*
X249750Y-531979D01*
X250450Y-531846D01*
X251050Y-531446D01*
X251450Y-530913D01*
G01X224500Y51139D02*
X222837D01*
G01X219327D02*
X214828D01*
G01X221110Y79632D02*
Y126632D01*
G01X214110Y79632D02*
X221110D01*
G01X214110D02*
Y126632D01*
G01X218610Y81345D02*
X216110D01*
Y81879D01*
X216235Y82092D01*
X216402Y82252D01*
X216652Y82385D01*
X216943Y82492D01*
X217360Y82519D01*
X217777Y82492D01*
X218068Y82385D01*
X218318Y82252D01*
X218485Y82092D01*
X218610Y81879D01*
Y81345D01*
G01Y84132D02*
X218568Y84319D01*
X218443Y84532D01*
X218235Y84665D01*
X217943Y84719D01*
X217652Y84665D01*
X217402Y84505D01*
X217277Y84265D01*
Y83999D01*
X217193Y83839D01*
X216985Y83705D01*
X216693Y83652D01*
X216402Y83732D01*
X216193Y83919D01*
X216110Y84132D01*
X216193Y84345D01*
X216402Y84532D01*
X216693Y84612D01*
X216985Y84559D01*
X217193Y84425D01*
X217277Y84265D01*
Y83999D01*
X217402Y83759D01*
X217652Y83599D01*
X217943Y83545D01*
X218235Y83599D01*
X218443Y83732D01*
X218568Y83945D01*
X218610Y84132D01*
G01Y86652D02*
X216110D01*
X217902Y85665D01*
Y86999D01*
G01X211610Y81345D02*
X209110D01*
Y81879D01*
X209235Y82092D01*
X209402Y82252D01*
X209652Y82385D01*
X209943Y82492D01*
X210360Y82519D01*
X210777Y82492D01*
X211068Y82385D01*
X211318Y82252D01*
X211485Y82092D01*
X211610Y81879D01*
Y81345D01*
G01Y84079D02*
X211068Y84132D01*
X210610Y84212D01*
X210193Y84319D01*
X209735Y84452D01*
X209110Y84665D01*
Y83599D01*
G01X211610Y86332D02*
X211568Y86519D01*
X211443Y86732D01*
X211235Y86865D01*
X210943Y86919D01*
X210652Y86865D01*
X210402Y86705D01*
X210277Y86465D01*
Y86199D01*
X210193Y86039D01*
X209985Y85905D01*
X209693Y85852D01*
X209402Y85932D01*
X209193Y86119D01*
X209110Y86332D01*
X209193Y86545D01*
X209402Y86732D01*
X209693Y86812D01*
X209985Y86759D01*
X210193Y86625D01*
X210277Y86465D01*
Y86199D01*
X210402Y85959D01*
X210652Y85799D01*
X210943Y85745D01*
X211235Y85799D01*
X211443Y85932D01*
X211568Y86145D01*
X211610Y86332D01*
G01Y94899D02*
X209110D01*
Y95539D01*
X209235Y95752D01*
X209527Y95912D01*
X209860Y95965D01*
X210193Y95912D01*
X210443Y95779D01*
X210568Y95539D01*
Y94899D01*
G01X209110Y96965D02*
X211610Y97632D01*
X209110Y98299D01*
G01X211610Y99219D02*
X209110D01*
X211610Y100445D01*
X209110D01*
G01X211610Y101419D02*
X209110D01*
X211610Y102645D01*
X209110D01*
G01X212443Y103432D02*
Y105032D01*
G01X211610Y105739D02*
X209110D01*
X211193Y106432D01*
X209110Y107125D01*
X211610D01*
G01Y107965D02*
X209110Y108632D01*
X211610Y109299D01*
G01X210735Y109059D02*
Y108205D01*
G01X209110Y110512D02*
Y111152D01*
G01Y110832D02*
X211610D01*
G01Y110512D02*
Y111152D01*
G01Y112419D02*
X209110D01*
X211610Y113645D01*
X209110D01*
G01X212443Y114432D02*
Y116032D01*
G01X209318Y118019D02*
X209193Y117859D01*
X209110Y117672D01*
Y117459D01*
X209235Y117219D01*
X209443Y117032D01*
X209693Y116899D01*
X210110Y116792D01*
X210485Y116765D01*
X210860Y116819D01*
X211110Y116899D01*
X211360Y117059D01*
X211527Y117245D01*
X211610Y117432D01*
Y117619D01*
X211527Y117805D01*
X211402Y117965D01*
X211235Y118099D01*
G01X211610Y119099D02*
X209110D01*
Y119739D01*
X209235Y119952D01*
X209527Y120112D01*
X209860Y120165D01*
X210193Y120112D01*
X210443Y119979D01*
X210568Y119739D01*
Y119099D01*
G01X209110Y121245D02*
X210902D01*
X211277Y121352D01*
X211527Y121565D01*
X211610Y121832D01*
X211527Y122099D01*
X211277Y122312D01*
X210902Y122419D01*
X209110D01*
G01Y124032D02*
X209193Y123819D01*
X209402Y123659D01*
X209652Y123552D01*
X209985Y123472D01*
X210360Y123445D01*
X210735Y123472D01*
X211068Y123552D01*
X211318Y123659D01*
X211527Y123819D01*
X211610Y124032D01*
X211527Y124245D01*
X211318Y124405D01*
X211068Y124512D01*
X210735Y124592D01*
X210360Y124619D01*
X209985Y124592D01*
X209652Y124512D01*
X209402Y124405D01*
X209193Y124245D01*
X209110Y124032D01*
G01X218610Y92899D02*
X216110D01*
Y93539D01*
X216235Y93752D01*
X216527Y93912D01*
X216860Y93965D01*
X217193Y93912D01*
X217443Y93779D01*
X217568Y93539D01*
Y92899D01*
G01X216110Y94965D02*
X218610Y95632D01*
X216110Y96299D01*
G01X216318Y98419D02*
X216193Y98259D01*
X216110Y98072D01*
Y97859D01*
X216235Y97619D01*
X216443Y97432D01*
X216693Y97299D01*
X217110Y97192D01*
X217485Y97165D01*
X217860Y97219D01*
X218110Y97299D01*
X218360Y97459D01*
X218527Y97645D01*
X218610Y97832D01*
Y98019D01*
X218527Y98205D01*
X218402Y98365D01*
X218235Y98499D01*
G01X216318Y100619D02*
X216193Y100459D01*
X216110Y100272D01*
Y100059D01*
X216235Y99819D01*
X216443Y99632D01*
X216693Y99499D01*
X217110Y99392D01*
X217485Y99365D01*
X217860Y99419D01*
X218110Y99499D01*
X218360Y99659D01*
X218527Y99845D01*
X218610Y100032D01*
Y100219D01*
X218527Y100405D01*
X218402Y100565D01*
X218235Y100699D01*
G01X216110Y101912D02*
Y102552D01*
G01Y102232D02*
X218610D01*
G01Y101912D02*
Y102552D01*
G01Y103819D02*
X216110D01*
X218610Y105045D01*
X216110D01*
G01X218610Y106125D02*
X216110D01*
Y107139D01*
G01X217318Y106765D02*
Y106125D01*
G01X218610Y108165D02*
X216110Y108832D01*
X218610Y109499D01*
G01X217735Y109259D02*
Y108405D01*
G01X218610Y111032D02*
X218568Y110819D01*
X218402Y110632D01*
X218152Y110472D01*
X217860Y110365D01*
X217527Y110312D01*
X217193D01*
X216860Y110365D01*
X216568Y110472D01*
X216318Y110632D01*
X216152Y110819D01*
X216110Y111032D01*
X216152Y111245D01*
X216318Y111432D01*
X216568Y111592D01*
X216860Y111699D01*
X217193Y111752D01*
X217527D01*
X217860Y111699D01*
X218152Y111592D01*
X218402Y111432D01*
X218568Y111245D01*
X218610Y111032D01*
G01Y112619D02*
X216110D01*
X218610Y113845D01*
X216110D01*
G01X219443Y114632D02*
Y116232D01*
G01X216318Y118219D02*
X216193Y118059D01*
X216110Y117872D01*
Y117659D01*
X216235Y117419D01*
X216443Y117232D01*
X216693Y117099D01*
X217110Y116992D01*
X217485Y116965D01*
X217860Y117019D01*
X218110Y117099D01*
X218360Y117259D01*
X218527Y117445D01*
X218610Y117632D01*
Y117819D01*
X218527Y118005D01*
X218402Y118165D01*
X218235Y118299D01*
G01X218610Y119299D02*
X216110D01*
Y119939D01*
X216235Y120152D01*
X216527Y120312D01*
X216860Y120365D01*
X217193Y120312D01*
X217443Y120179D01*
X217568Y119939D01*
Y119299D01*
G01X216110Y121445D02*
X217902D01*
X218277Y121552D01*
X218527Y121765D01*
X218610Y122032D01*
X218527Y122299D01*
X218277Y122512D01*
X217902Y122619D01*
X216110D01*
G01X218610Y124232D02*
X216110D01*
X216610Y123912D01*
G01X218610D02*
Y124552D01*
G01X221110Y88890D02*
Y88778D01*
G01X218610Y130899D02*
X216110D01*
Y131539D01*
X216235Y131752D01*
X216527Y131912D01*
X216860Y131965D01*
X217193Y131912D01*
X217443Y131779D01*
X217568Y131539D01*
Y130899D01*
G01X218610Y133632D02*
X216110D01*
X216610Y133312D01*
G01X218610D02*
Y133952D01*
G01X216110Y135165D02*
X218610Y135832D01*
X216110Y136499D01*
G01X218610Y138032D02*
X218568Y138219D01*
X218443Y138432D01*
X218235Y138565D01*
X217943Y138619D01*
X217652Y138565D01*
X217402Y138405D01*
X217277Y138165D01*
Y137899D01*
X217193Y137739D01*
X216985Y137605D01*
X216693Y137552D01*
X216402Y137632D01*
X216193Y137819D01*
X216110Y138032D01*
X216193Y138245D01*
X216402Y138432D01*
X216693Y138512D01*
X216985Y138459D01*
X217193Y138325D01*
X217277Y138165D01*
Y137899D01*
X217402Y137659D01*
X217652Y137499D01*
X217943Y137445D01*
X218235Y137499D01*
X218443Y137632D01*
X218568Y137845D01*
X218610Y138032D01*
G01X219443Y139432D02*
Y141032D01*
G01X218610Y141899D02*
X216110D01*
Y142539D01*
X216235Y142752D01*
X216527Y142912D01*
X216860Y142965D01*
X217193Y142912D01*
X217443Y142779D01*
X217568Y142539D01*
Y141899D01*
G01X216318Y145219D02*
X216193Y145059D01*
X216110Y144872D01*
Y144659D01*
X216235Y144419D01*
X216443Y144232D01*
X216693Y144099D01*
X217110Y143992D01*
X217485Y143965D01*
X217860Y144019D01*
X218110Y144099D01*
X218360Y144259D01*
X218527Y144445D01*
X218610Y144632D01*
Y144819D01*
X218527Y145005D01*
X218402Y145165D01*
X218235Y145299D01*
G01X218610Y146272D02*
X216110D01*
G01Y147392D02*
X218610D01*
G01X217360D02*
Y146272D01*
G01X219443Y148232D02*
Y149832D01*
G01X218610Y150565D02*
X216110Y151232D01*
X218610Y151899D01*
G01X217735Y151659D02*
Y150805D01*
G01X216110Y152845D02*
X217902D01*
X218277Y152952D01*
X218527Y153165D01*
X218610Y153432D01*
X218527Y153699D01*
X218277Y153912D01*
X217902Y154019D01*
X216110D01*
G01X218610Y155072D02*
X216110Y156192D01*
G01Y155072D02*
X218610Y156192D01*
G01X211610Y128399D02*
X209110D01*
Y129039D01*
X209235Y129252D01*
X209527Y129412D01*
X209860Y129465D01*
X210193Y129412D01*
X210443Y129279D01*
X210568Y129039D01*
Y128399D01*
G01X211610Y131132D02*
X209110D01*
X209610Y130812D01*
G01X211610D02*
Y131452D01*
G01X209110Y132665D02*
X211610Y133332D01*
X209110Y133999D01*
G01Y135532D02*
X209193Y135319D01*
X209402Y135159D01*
X209652Y135052D01*
X209985Y134972D01*
X210360Y134945D01*
X210735Y134972D01*
X211068Y135052D01*
X211318Y135159D01*
X211527Y135319D01*
X211610Y135532D01*
X211527Y135745D01*
X211318Y135905D01*
X211068Y136012D01*
X210735Y136092D01*
X210360Y136119D01*
X209985Y136092D01*
X209652Y136012D01*
X209402Y135905D01*
X209193Y135745D01*
X209110Y135532D01*
G01X211235Y137145D02*
X211443Y137305D01*
X211568Y137492D01*
X211610Y137732D01*
X211527Y137972D01*
X211360Y138159D01*
X211068Y138292D01*
X210735Y138319D01*
X210402Y138265D01*
X210193Y138132D01*
X210027Y137945D01*
X209985Y137759D01*
X210027Y137572D01*
X210193Y137332D01*
X209110Y137412D01*
Y138132D01*
G01X212443Y139132D02*
Y140732D01*
G01X211610Y141599D02*
X209110D01*
Y142239D01*
X209235Y142452D01*
X209527Y142612D01*
X209860Y142665D01*
X210193Y142612D01*
X210443Y142479D01*
X210568Y142239D01*
Y141599D01*
G01X209318Y144919D02*
X209193Y144759D01*
X209110Y144572D01*
Y144359D01*
X209235Y144119D01*
X209443Y143932D01*
X209693Y143799D01*
X210110Y143692D01*
X210485Y143665D01*
X210860Y143719D01*
X211110Y143799D01*
X211360Y143959D01*
X211527Y144145D01*
X211610Y144332D01*
Y144519D01*
X211527Y144705D01*
X211402Y144865D01*
X211235Y144999D01*
G01X211610Y145972D02*
X209110D01*
G01Y147092D02*
X211610D01*
G01X210360D02*
Y145972D01*
G01X212443Y147932D02*
Y149532D01*
G01X211610Y150265D02*
X209110Y150932D01*
X211610Y151599D01*
G01X210735Y151359D02*
Y150505D01*
G01X209110Y152545D02*
X210902D01*
X211277Y152652D01*
X211527Y152865D01*
X211610Y153132D01*
X211527Y153399D01*
X211277Y153612D01*
X210902Y153719D01*
X209110D01*
G01X211610Y154772D02*
X209110Y155892D01*
G01Y154772D02*
X211610Y155892D01*
G01X214110Y166632D02*
Y126632D01*
G01X221110Y166632D02*
Y126632D01*
G01X228110D02*
X221110D01*
G01D02*
X214110D01*
G01X225610Y139899D02*
X223110D01*
Y140539D01*
X223235Y140752D01*
X223527Y140912D01*
X223860Y140965D01*
X224193Y140912D01*
X224443Y140779D01*
X224568Y140539D01*
Y139899D01*
G01X225235Y142045D02*
X225443Y142205D01*
X225568Y142392D01*
X225610Y142632D01*
X225527Y142872D01*
X225360Y143059D01*
X225068Y143192D01*
X224735Y143219D01*
X224402Y143165D01*
X224193Y143032D01*
X224027Y142845D01*
X223985Y142659D01*
X224027Y142472D01*
X224193Y142232D01*
X223110Y142312D01*
Y143032D01*
G01Y144165D02*
X225610Y144832D01*
X223110Y145499D01*
G01X226443Y146232D02*
Y147832D01*
G01X225277Y148672D02*
X225485Y148885D01*
X225610Y149125D01*
Y149339D01*
X225485Y149552D01*
X225277Y149712D01*
X224985Y149792D01*
X224693Y149739D01*
X224443Y149605D01*
X224277Y149365D01*
X224193Y149045D01*
X224027Y148859D01*
X223735Y148779D01*
X223443Y148832D01*
X223235Y148965D01*
X223110Y149152D01*
Y149339D01*
X223193Y149525D01*
X223402Y149685D01*
G01X223110Y151432D02*
X225610D01*
G01X223110Y150819D02*
Y152045D01*
G01X224277Y153845D02*
X224152Y153952D01*
X223943Y154032D01*
X223652Y154085D01*
X223402Y154032D01*
X223235Y153925D01*
X223110Y153739D01*
Y153019D01*
X225610D01*
Y153899D01*
X225443Y154085D01*
X225193Y154192D01*
X224902Y154245D01*
X224610Y154192D01*
X224360Y154032D01*
X224277Y153845D01*
Y153019D01*
G01X225610Y155832D02*
X224485D01*
X223110Y155299D01*
G01Y156365D02*
X224485Y155832D01*
G01X221110Y166632D02*
X228110D01*
G01X214110D02*
X221110D01*
G01X211604Y159384D02*
X209104D01*
Y159918D01*
X209229Y160131D01*
X209396Y160291D01*
X209646Y160424D01*
X209937Y160531D01*
X210354Y160558D01*
X210771Y160531D01*
X211062Y160424D01*
X211312Y160291D01*
X211479Y160131D01*
X211604Y159918D01*
Y159384D01*
G01X211312Y161718D02*
X211521Y161904D01*
X211604Y162118D01*
X211521Y162331D01*
X211271Y162518D01*
X210896Y162651D01*
X210521Y162704D01*
X210062D01*
X209687Y162651D01*
X209354Y162518D01*
X209187Y162358D01*
X209104Y162171D01*
X209187Y161958D01*
X209354Y161798D01*
X209604Y161691D01*
X209937Y161638D01*
X210229Y161691D01*
X210521Y161824D01*
X210687Y161984D01*
X210729Y162171D01*
X210646Y162384D01*
X210437Y162544D01*
X210062Y162704D01*
G01X209521Y163864D02*
X209271Y164024D01*
X209146Y164211D01*
X209104Y164424D01*
X209187Y164691D01*
X209396Y164878D01*
X209646Y164931D01*
X209896Y164904D01*
X210104Y164798D01*
X210521Y164264D01*
X210812Y164024D01*
X211229Y163864D01*
X211604Y163811D01*
Y164931D01*
G01X218704Y159384D02*
X216204D01*
Y159918D01*
X216329Y160131D01*
X216496Y160291D01*
X216746Y160424D01*
X217037Y160531D01*
X217454Y160558D01*
X217871Y160531D01*
X218162Y160424D01*
X218412Y160291D01*
X218579Y160131D01*
X218704Y159918D01*
Y159384D01*
G01X218412Y161718D02*
X218621Y161904D01*
X218704Y162118D01*
X218621Y162331D01*
X218371Y162518D01*
X217996Y162651D01*
X217621Y162704D01*
X217162D01*
X216787Y162651D01*
X216454Y162518D01*
X216287Y162358D01*
X216204Y162171D01*
X216287Y161958D01*
X216454Y161798D01*
X216704Y161691D01*
X217037Y161638D01*
X217329Y161691D01*
X217621Y161824D01*
X217787Y161984D01*
X217829Y162171D01*
X217746Y162384D01*
X217537Y162544D01*
X217162Y162704D01*
G01X218704Y164371D02*
X216204D01*
X216704Y164051D01*
G01X218704D02*
Y164691D01*
G01X225804Y159384D02*
X223304D01*
Y159918D01*
X223429Y160131D01*
X223596Y160291D01*
X223846Y160424D01*
X224137Y160531D01*
X224554Y160558D01*
X224971Y160531D01*
X225262Y160424D01*
X225512Y160291D01*
X225679Y160131D01*
X225804Y159918D01*
Y159384D01*
G01X225512Y161718D02*
X225721Y161904D01*
X225804Y162118D01*
X225721Y162331D01*
X225471Y162518D01*
X225096Y162651D01*
X224721Y162704D01*
X224262D01*
X223887Y162651D01*
X223554Y162518D01*
X223387Y162358D01*
X223304Y162171D01*
X223387Y161958D01*
X223554Y161798D01*
X223804Y161691D01*
X224137Y161638D01*
X224429Y161691D01*
X224721Y161824D01*
X224887Y161984D01*
X224929Y162171D01*
X224846Y162384D01*
X224637Y162544D01*
X224262Y162704D01*
G01X225804Y164318D02*
X225262Y164371D01*
X224804Y164451D01*
X224387Y164558D01*
X223929Y164691D01*
X223304Y164904D01*
Y163838D01*
G01X220930Y313772D02*
Y267672D01*
G01D02*
X268520D01*
G01X220930Y316512D02*
Y313772D01*
G01X225620Y316512D02*
X220930D01*
G01X224507Y317156D02*
X221307D01*
G01Y323356D02*
X224507D01*
G01X221307Y317156D02*
Y323356D01*
G01X216654Y422335D02*
Y419135D01*
G01X210454Y422335D02*
X216654D01*
G01X210454Y419135D02*
Y422335D01*
G01X216654Y419135D02*
X210454D01*
G01X216654Y426335D02*
Y423135D01*
G01X210454Y426335D02*
X216654D01*
G01X210454Y423135D02*
Y426335D01*
G01X216654Y423135D02*
X210454D01*
G01X216654Y430335D02*
Y427135D01*
G01X210454D02*
Y430335D01*
G01X216654Y427135D02*
X210454D01*
G01Y430335D02*
X216654D01*
G01Y438335D02*
Y435135D01*
G01X210454Y438335D02*
X216654D01*
G01X210454Y435135D02*
Y438335D01*
G01X216654Y435135D02*
X210454D01*
G01X216654Y434335D02*
Y431135D01*
G01X210454Y434335D02*
X216654D01*
G01X210454Y431135D02*
Y434335D01*
G01X216654Y431135D02*
X210454D01*
G01X216654Y442335D02*
Y439135D01*
G01X210454Y442335D02*
X216654D01*
G01X210454Y439135D02*
Y442335D01*
G01X216654Y439135D02*
X210454D01*
G01X216654Y446335D02*
Y443135D01*
G01X210454D02*
Y446335D01*
G01X216654Y443135D02*
X210454D01*
G01Y446335D02*
X216654D01*
G01X210454Y451135D02*
Y454335D01*
G01X216654Y451135D02*
X210454D01*
G01X216654Y454335D02*
Y451135D01*
G01X210454Y454335D02*
X216654D01*
G01Y450335D02*
Y447135D01*
G01X210454Y450335D02*
X216654D01*
G01X210454Y447135D02*
Y450335D01*
G01X216654Y447135D02*
X210454D01*
G01X216654Y458822D02*
Y455622D01*
G01X210454Y458822D02*
X216654D01*
G01X210454Y455622D02*
Y458822D01*
G01X216654Y455622D02*
X210454D01*
G01X216654Y463835D02*
Y460635D01*
G01X210454D02*
Y463835D01*
G01X216654Y460635D02*
X210454D01*
G01Y463835D02*
X216654D01*
G01X218740Y572212D02*
X217042D01*
G01X213791Y566381D02*
Y569581D01*
G01X219991Y566381D02*
X213791D01*
G01X219991Y569581D02*
Y566381D01*
G01X213791Y569581D02*
X219991D01*
G01X209491D02*
Y566381D01*
G01X218740Y606212D02*
X217042D01*
G01X209491Y603581D02*
Y600381D01*
G01X212692Y594507D02*
Y597707D01*
G01X218892Y594507D02*
X212692D01*
G01X218892Y597707D02*
Y594507D01*
G01X212692Y597707D02*
X218892D01*
G01X213791Y600381D02*
Y603581D01*
G01X219991Y600381D02*
X213791D01*
G01X219991Y603581D02*
Y600381D01*
G01X213791Y603581D02*
X219991D01*
G01X218740Y640212D02*
X217042D01*
G01X212692Y628507D02*
Y631707D01*
G01X218892Y628507D02*
X212692D01*
G01X218892Y631707D02*
Y628507D01*
G01X212692Y631707D02*
X218892D01*
G01X213791Y634381D02*
Y637581D01*
G01X219991Y634381D02*
X213791D01*
G01X219991Y637581D02*
Y634381D01*
G01X213791Y637581D02*
X219991D01*
G01X209491D02*
Y634381D01*
G01X212692Y662507D02*
Y665707D01*
G01X218892Y662507D02*
X212692D01*
G01X218892Y665707D02*
Y662507D01*
G01X212692Y665707D02*
X218892D01*
G01X209941Y672137D02*
Y675337D01*
G01X216141Y672137D02*
X209941D01*
G01X216141Y675337D02*
Y672137D01*
G01X223131Y673350D02*
Y679298D01*
G01X260927Y673350D02*
X223131D01*
G01X216853Y677877D02*
X219452D01*
G01D02*
Y680948D01*
G01X211014Y677877D02*
X212509D01*
G01X209941Y675337D02*
X216141D01*
G01X216433Y702330D02*
Y705430D01*
X217353D01*
X217660Y705275D01*
X217890Y704913D01*
X217967Y704500D01*
X217890Y704087D01*
X217698Y703777D01*
X217353Y703622D01*
X216433D01*
G01X219533Y705430D02*
Y702330D01*
X221067D01*
G01X222672Y704913D02*
X222902Y705223D01*
X223170Y705378D01*
X223477Y705430D01*
X223860Y705327D01*
X224128Y705068D01*
X224205Y704758D01*
X224167Y704448D01*
X224013Y704190D01*
X223247Y703673D01*
X222902Y703312D01*
X222672Y702795D01*
X222595Y702330D01*
X224205D01*
G01X226500Y705430D02*
X226193Y705327D01*
X225963Y705068D01*
X225810Y704758D01*
X225695Y704345D01*
X225657Y703880D01*
X225695Y703415D01*
X225810Y703002D01*
X225963Y702692D01*
X226193Y702433D01*
X226500Y702330D01*
X226807Y702433D01*
X227037Y702692D01*
X227190Y703002D01*
X227305Y703415D01*
X227343Y703880D01*
X227305Y704345D01*
X227190Y704758D01*
X227037Y705068D01*
X226807Y705327D01*
X226500Y705430D01*
G01X223131Y698546D02*
X260927D01*
G01X223131Y692598D02*
Y698546D01*
G01X209753Y694019D02*
X208711D01*
G01X219452Y690948D02*
Y694019D01*
G01D02*
X216853D01*
G01X221113Y1321259D02*
Y1324459D01*
G01X227313Y1321259D02*
X221113D01*
G01X216541Y1337690D02*
X210627D01*
G01X216541Y1377060D02*
Y1337690D01*
G01X218000Y1337055D02*
X218192Y1336745D01*
X218422Y1336538D01*
X218690Y1336435D01*
X218997Y1336538D01*
X219227Y1336745D01*
X219457Y1337055D01*
X219534Y1337468D01*
Y1339535D01*
G01X221867Y1336435D02*
Y1339535D01*
X221407Y1338915D01*
G01Y1336435D02*
X222327D01*
G01X224890D02*
X224967Y1337107D01*
X225082Y1337675D01*
X225235Y1338192D01*
X225427Y1338760D01*
X225734Y1339535D01*
X224200D01*
G01X231115Y1335007D02*
X216140D01*
G01X221113Y1328459D02*
X227313D01*
G01X221113Y1325259D02*
Y1328459D01*
G01X227313Y1325259D02*
X221113D01*
G01Y1324459D02*
X227313D01*
G01X211628Y1380110D02*
X210835D01*
G01X211628Y1382710D02*
Y1380110D01*
G01X210627Y1377060D02*
X216541D01*
G01X211628Y1403732D02*
Y1401541D01*
G01X210895Y1403732D02*
X211628D01*
G01X218787Y1395399D02*
X221987D01*
G01X218787Y1389199D02*
Y1395399D01*
G01X221987Y1389199D02*
X218787D01*
G01X221987Y1395399D02*
Y1389199D01*
G01X214490Y1395399D02*
X217690D01*
G01X214490Y1389199D02*
Y1395399D01*
G01X217690Y1389199D02*
X214490D01*
G01X217690Y1395399D02*
Y1389199D01*
G01X215847Y1417975D02*
Y1423975D01*
G01X227847Y1417975D02*
X215847D01*
G01X215586Y1412915D02*
X227586D01*
G01X215586Y1406915D02*
Y1412915D01*
G01X227586Y1406915D02*
X215586D01*
G01X209316Y1413345D02*
Y1407145D01*
G01X215847Y1430783D02*
X227847D01*
G01X215847Y1424783D02*
Y1430783D01*
G01X227847Y1424783D02*
X215847D01*
G01Y1423975D02*
X227847D01*
G01X220143Y1528447D02*
Y1531547D01*
X221140Y1528964D01*
X222137Y1531547D01*
Y1528447D01*
G01X225007D02*
X223473D01*
Y1531547D01*
X225007D01*
G01X224393Y1530049D02*
X223473D01*
G01X227340Y1528447D02*
Y1531547D01*
X226880Y1530927D01*
G01Y1528447D02*
X227800D01*
G01X229712Y1531030D02*
X229942Y1531340D01*
X230210Y1531495D01*
X230517Y1531547D01*
X230900Y1531444D01*
X231168Y1531185D01*
X231245Y1530875D01*
X231207Y1530565D01*
X231053Y1530307D01*
X230287Y1529790D01*
X229942Y1529429D01*
X229712Y1528912D01*
X229635Y1528447D01*
X231245D01*
G01X214174Y1617677D02*
X304331D01*
G01X214174Y1781456D02*
Y1617677D01*
G01X222306Y1646132D02*
Y1643032D01*
G01X221424Y1646132D02*
X223188D01*
G01X221501Y1648169D02*
X221808Y1647911D01*
X222153Y1647756D01*
X222459D01*
X222766Y1647911D01*
X222996Y1648169D01*
X223111Y1648531D01*
X223034Y1648893D01*
X222843Y1649203D01*
X222498Y1649409D01*
X222038Y1649513D01*
X221769Y1649719D01*
X221654Y1650081D01*
X221731Y1650443D01*
X221923Y1650701D01*
X222191Y1650856D01*
X222459D01*
X222728Y1650753D01*
X222958Y1650494D01*
G01X221539Y1661929D02*
Y1665029D01*
X222459D01*
X222766Y1664874D01*
X222996Y1664512D01*
X223073Y1664099D01*
X222996Y1663686D01*
X222804Y1663376D01*
X222459Y1663221D01*
X221539D01*
G01X222306Y1657205D02*
X221999Y1657257D01*
X221731Y1657463D01*
X221501Y1657773D01*
X221348Y1658135D01*
X221271Y1658548D01*
Y1658962D01*
X221348Y1659375D01*
X221501Y1659737D01*
X221731Y1660047D01*
X221999Y1660253D01*
X222306Y1660305D01*
X222613Y1660253D01*
X222881Y1660047D01*
X223111Y1659737D01*
X223264Y1659375D01*
X223341Y1658962D01*
Y1658548D01*
X223264Y1658135D01*
X223111Y1657773D01*
X222881Y1657463D01*
X222613Y1657257D01*
X222306Y1657205D01*
G01X222613Y1658032D02*
X223073Y1657205D01*
G01X221539Y1652480D02*
Y1655580D01*
X222498D01*
X222804Y1655425D01*
X222996Y1655218D01*
X223073Y1654805D01*
X222996Y1654392D01*
X222766Y1654133D01*
X222498Y1653978D01*
X221539D01*
G01X222498D02*
X223073Y1652480D01*
G01X221424Y1671378D02*
Y1674478D01*
X223188Y1671378D01*
Y1674478D01*
G01X222306Y1666654D02*
X221999Y1666706D01*
X221731Y1666912D01*
X221501Y1667222D01*
X221348Y1667584D01*
X221271Y1667997D01*
Y1668411D01*
X221348Y1668824D01*
X221501Y1669186D01*
X221731Y1669496D01*
X221999Y1669702D01*
X222306Y1669754D01*
X222613Y1669702D01*
X222881Y1669496D01*
X223111Y1669186D01*
X223264Y1668824D01*
X223341Y1668411D01*
Y1667997D01*
X223264Y1667584D01*
X223111Y1667222D01*
X222881Y1666912D01*
X222613Y1666706D01*
X222306Y1666654D01*
G01X221539Y1683927D02*
Y1680827D01*
X223073D01*
G01X221309Y1676102D02*
Y1679202D01*
X222306Y1676619D01*
X223303Y1679202D01*
Y1676102D01*
G01X221846Y1698100D02*
X222766D01*
G01X222306D02*
Y1695000D01*
G01X221846D02*
X222766D01*
G01X221539Y1690896D02*
X221731Y1690586D01*
X221961Y1690379D01*
X222229Y1690276D01*
X222536Y1690379D01*
X222766Y1690586D01*
X222996Y1690896D01*
X223073Y1691309D01*
Y1693376D01*
G01X221463Y1685551D02*
Y1688651D01*
G01X222919D02*
X221463Y1686739D01*
G01X223149Y1685551D02*
X222114Y1687618D01*
G01X222536Y1705999D02*
X223303D01*
Y1705069D01*
X223073Y1704759D01*
X222804Y1704552D01*
X222421Y1704449D01*
X222038Y1704552D01*
X221769Y1704759D01*
X221539Y1705069D01*
X221386Y1705431D01*
X221309Y1705844D01*
Y1706206D01*
X221386Y1706516D01*
X221539Y1706877D01*
X221769Y1707187D01*
X221999Y1707394D01*
X222306Y1707549D01*
X222574D01*
X222881Y1707446D01*
X223111Y1707239D01*
G01X221501Y1699724D02*
Y1702824D01*
G01X223111D02*
Y1699724D01*
G01Y1701274D02*
X221501D01*
G01X223073Y1713898D02*
X221539D01*
Y1716998D01*
X223073D01*
G01X222459Y1715500D02*
X221539D01*
G01X221578Y1709173D02*
Y1712273D01*
X223034D01*
G01X222498Y1710775D02*
X221578D01*
G01X210520Y1711362D02*
X213720D01*
G01X210520Y1705162D02*
Y1711362D01*
G01X213720Y1705162D02*
X210520D01*
G01X213720Y1711362D02*
Y1705162D01*
G01X209820Y1711462D02*
Y1708262D01*
G01X209718Y1715617D02*
Y1712417D01*
G01X221463Y1718622D02*
Y1721722D01*
X222229D01*
X222536Y1721567D01*
X222766Y1721360D01*
X222958Y1721050D01*
X223111Y1720689D01*
X223149Y1720172D01*
X223111Y1719655D01*
X222958Y1719294D01*
X222766Y1718984D01*
X222536Y1718777D01*
X222229Y1718622D01*
X221463D01*
G01X223149Y1726189D02*
X222919Y1726344D01*
X222651Y1726447D01*
X222344D01*
X221999Y1726292D01*
X221731Y1726034D01*
X221539Y1725724D01*
X221386Y1725207D01*
X221348Y1724742D01*
X221424Y1724277D01*
X221539Y1723967D01*
X221769Y1723657D01*
X222038Y1723450D01*
X222306Y1723347D01*
X222574D01*
X222843Y1723450D01*
X223073Y1723605D01*
X223264Y1723812D01*
G01X222613Y1729724D02*
X222766Y1729879D01*
X222881Y1730138D01*
X222958Y1730499D01*
X222881Y1730809D01*
X222728Y1731016D01*
X222459Y1731171D01*
X221424D01*
Y1728071D01*
X222689D01*
X222958Y1728278D01*
X223111Y1728588D01*
X223188Y1728949D01*
X223111Y1729311D01*
X222881Y1729621D01*
X222613Y1729724D01*
X221424D01*
G01X209718Y1719617D02*
Y1716417D01*
G01X304331Y1781456D02*
X214174D01*
G01X278930Y51139D02*
X230850D01*
G01X235620Y66962D02*
X238820D01*
G01X235620Y60762D02*
Y66962D01*
G01X238820Y60762D02*
X235620D01*
G01X238820Y66962D02*
Y60762D01*
G01X239620Y66962D02*
X242820D01*
G01X239620Y60762D02*
Y66962D01*
G01X242820Y60762D02*
X239620D01*
G01X228110Y166632D02*
Y126632D01*
G01X239822Y125518D02*
X233622D01*
Y128718D01*
X239822D01*
Y125518D01*
G01X239897Y128643D02*
Y122443D01*
X236697D01*
Y128643D01*
X239897D01*
G01X228110Y151685D02*
Y151741D01*
G01X238800Y143662D02*
Y140462D01*
G01X232600Y143662D02*
X238800D01*
G01X232600Y140462D02*
Y143662D01*
G01X238800Y140462D02*
X232600D01*
G01X228920Y152526D02*
Y155726D01*
G01X235120Y152526D02*
X228920D01*
G01X235120Y155726D02*
Y152526D01*
G01X228920Y155726D02*
X235120D01*
G01X228920Y160671D02*
X235120D01*
G01D02*
Y157471D01*
G01X228920D02*
Y160671D01*
G01X235120Y157471D02*
X228920D01*
G01X239654Y276785D02*
Y280535D01*
G01X246794Y276785D02*
X239654D01*
G01X239704Y280585D02*
X246794D01*
G01X247294Y276785D02*
X240104D01*
G01Y280585D02*
X247294D01*
G01X227054Y276785D02*
Y280535D01*
G01X234194Y276785D02*
X227054D01*
G01X234194Y280585D02*
Y276785D01*
G01X227104Y280585D02*
X234194D01*
G01X234694Y276785D02*
X227504D01*
G01X234694Y280585D02*
Y276785D01*
G01X227504Y280585D02*
X234694D01*
G01X235194Y276785D02*
X228104D01*
G01X235194Y280585D02*
Y276785D01*
G01X228104Y280585D02*
X235194D01*
G01X238924Y309434D02*
Y313184D01*
G01X246064Y309434D02*
X238924D01*
G01X238974Y313234D02*
X246064D01*
G01X246564Y309434D02*
X239374D01*
G01Y313234D02*
X246564D01*
G01X247064Y309434D02*
X239974D01*
G01Y313234D02*
X247064D01*
G01X226324Y309434D02*
Y313184D01*
G01X233464Y309434D02*
X226324D01*
G01X233464Y313234D02*
Y309434D01*
G01X226374Y313234D02*
X233464D01*
G01X233964Y309434D02*
X226774D01*
G01X233964Y313234D02*
Y309434D01*
G01X226774Y313234D02*
X233964D01*
G01X234464Y309434D02*
X227374D01*
G01X234464Y313234D02*
Y309434D01*
G01X227374Y313234D02*
X234464D01*
G01X453800Y316512D02*
X230870D01*
G01X224507Y323356D02*
Y317156D01*
G01X240849Y448399D02*
X235798Y453450D01*
X233549D01*
Y422348D01*
X248149D01*
Y453450D01*
X245900D01*
X240849Y448399D01*
G01X232556Y457666D02*
Y455444D01*
X232709Y454979D01*
X233016Y454669D01*
X233399Y454566D01*
X233782Y454669D01*
X234089Y454979D01*
X234242Y455444D01*
Y457666D01*
G01X235656Y455186D02*
X235886Y454824D01*
X236192Y454618D01*
X236537Y454566D01*
X236844Y454618D01*
X237151Y454876D01*
X237342Y455186D01*
X237381Y455496D01*
X237304Y455858D01*
X237036Y456116D01*
X236767Y456219D01*
X236422D01*
G01X236767D02*
X236997Y456374D01*
X237189Y456633D01*
X237266Y456943D01*
X237189Y457253D01*
X236997Y457511D01*
X236652Y457666D01*
X236307Y457614D01*
X235962Y457408D01*
G01X238947Y454928D02*
X239216Y454669D01*
X239522Y454566D01*
X239829Y454669D01*
X240097Y454979D01*
X240289Y455444D01*
X240366Y455909D01*
Y456478D01*
X240289Y456943D01*
X240097Y457356D01*
X239867Y457563D01*
X239599Y457666D01*
X239292Y457563D01*
X239062Y457356D01*
X238909Y457046D01*
X238832Y456633D01*
X238909Y456271D01*
X239101Y455909D01*
X239331Y455703D01*
X239599Y455651D01*
X239906Y455754D01*
X240136Y456013D01*
X240366Y456478D01*
G01X227951Y572212D02*
X225351D01*
G01X227951Y573005D02*
Y572212D01*
G01X232695Y569260D02*
Y573255D01*
G01X258285Y569260D02*
X232695D01*
G01X227951Y591898D02*
Y591105D01*
G01X232695Y590855D02*
Y594850D01*
G01X225351Y591898D02*
X227951D01*
G01Y607005D02*
Y606212D01*
X225351D01*
G01X232695Y603260D02*
Y607255D01*
G01X258285Y603260D02*
X232695D01*
G01X232013Y597842D02*
Y600942D01*
X232933D01*
X233240Y600787D01*
X233470Y600425D01*
X233547Y600012D01*
X233470Y599599D01*
X233278Y599289D01*
X232933Y599134D01*
X232013D01*
G01X235113Y600942D02*
Y597842D01*
X236647D01*
G01X238252Y600425D02*
X238482Y600735D01*
X238750Y600890D01*
X239057Y600942D01*
X239440Y600839D01*
X239708Y600580D01*
X239785Y600270D01*
X239747Y599960D01*
X239593Y599702D01*
X238827Y599185D01*
X238482Y598824D01*
X238252Y598307D01*
X238175Y597842D01*
X239785D01*
G01X241352Y600425D02*
X241582Y600735D01*
X241850Y600890D01*
X242157Y600942D01*
X242540Y600839D01*
X242808Y600580D01*
X242885Y600270D01*
X242847Y599960D01*
X242693Y599702D01*
X241927Y599185D01*
X241582Y598824D01*
X241352Y598307D01*
X241275Y597842D01*
X242885D01*
G01X232695Y594850D02*
X258285D01*
G01X227951Y641005D02*
Y640212D01*
X225351D01*
G01Y625898D02*
X227951D01*
Y625105D01*
G01X232695Y637260D02*
Y641255D01*
G01X258285Y637260D02*
X232695D01*
G01X232183Y632342D02*
Y635442D01*
X233103D01*
X233410Y635287D01*
X233640Y634925D01*
X233717Y634512D01*
X233640Y634099D01*
X233448Y633789D01*
X233103Y633634D01*
X232183D01*
G01X235283Y635442D02*
Y632342D01*
X236817D01*
G01X238422Y634925D02*
X238652Y635235D01*
X238920Y635390D01*
X239227Y635442D01*
X239610Y635339D01*
X239878Y635080D01*
X239955Y634770D01*
X239917Y634460D01*
X239763Y634202D01*
X238997Y633685D01*
X238652Y633324D01*
X238422Y632807D01*
X238345Y632342D01*
X239955D01*
G01X242250D02*
Y635442D01*
X241790Y634822D01*
G01Y632342D02*
X242710D01*
G01X232695Y628850D02*
X258285D01*
G01X232695Y624855D02*
Y628850D01*
G01X225351Y659898D02*
X227951D01*
Y659105D01*
G01X229703Y666332D02*
Y669432D01*
X230623D01*
X230930Y669277D01*
X231160Y668915D01*
X231237Y668502D01*
X231160Y668089D01*
X230968Y667779D01*
X230623Y667624D01*
X229703D01*
G01X232803Y669432D02*
Y666332D01*
X234337D01*
G01X236670D02*
Y669432D01*
X236210Y668812D01*
G01Y666332D02*
X237130D01*
G01X239693D02*
X239770Y667004D01*
X239885Y667572D01*
X240038Y668089D01*
X240230Y668657D01*
X240537Y669432D01*
X239003D01*
G01X232695Y662850D02*
X258285D01*
G01X232695Y658855D02*
Y662850D01*
G01X235225Y697211D02*
X260815D01*
G01X235225Y1335007D02*
Y697211D01*
G01X231115D02*
Y1335007D01*
G01X260815Y732644D02*
X235225D01*
G01X260815Y1299574D02*
X235225D01*
G01X227313Y1324459D02*
Y1321259D01*
G01X260815Y1335007D02*
X235225D01*
G01X227313Y1328459D02*
Y1325259D01*
G01X226633Y1396102D02*
Y1399202D01*
X227553D01*
X227860Y1399047D01*
X228090Y1398685D01*
X228167Y1398272D01*
X228090Y1397859D01*
X227898Y1397549D01*
X227553Y1397394D01*
X226633D01*
G01X229657Y1399202D02*
Y1396980D01*
X229810Y1396515D01*
X230117Y1396205D01*
X230500Y1396102D01*
X230883Y1396205D01*
X231190Y1396515D01*
X231343Y1396980D01*
Y1399202D01*
G01X233523Y1396102D02*
X233600Y1396774D01*
X233715Y1397342D01*
X233868Y1397859D01*
X234060Y1398427D01*
X234367Y1399202D01*
X232833D01*
G01X235972Y1397394D02*
X236240Y1397755D01*
X236470Y1397962D01*
X236777Y1398065D01*
X237045Y1397962D01*
X237237Y1397755D01*
X237390Y1397445D01*
X237428Y1397084D01*
X237390Y1396774D01*
X237237Y1396464D01*
X237007Y1396205D01*
X236738Y1396102D01*
X236432Y1396205D01*
X236163Y1396515D01*
X236010Y1396980D01*
X235972Y1397497D01*
X236048Y1398169D01*
X236163Y1398530D01*
X236355Y1398892D01*
X236623Y1399150D01*
X236892Y1399202D01*
X237160Y1399099D01*
X237352Y1398840D01*
G01X238650Y1395069D02*
X240950D01*
G01X242133Y1396102D02*
Y1399202D01*
X243053D01*
X243360Y1399047D01*
X243590Y1398685D01*
X243667Y1398272D01*
X243590Y1397859D01*
X243398Y1397549D01*
X243053Y1397394D01*
X242133D01*
G01X246000Y1396102D02*
Y1399202D01*
X245540Y1398582D01*
G01Y1396102D02*
X246460D01*
G01X247950Y1395069D02*
X250250D01*
G01X251472Y1398685D02*
X251702Y1398995D01*
X251970Y1399150D01*
X252277Y1399202D01*
X252660Y1399099D01*
X252928Y1398840D01*
X253005Y1398530D01*
X252967Y1398220D01*
X252813Y1397962D01*
X252047Y1397445D01*
X251702Y1397084D01*
X251472Y1396567D01*
X251395Y1396102D01*
X253005D01*
G01X227847Y1423975D02*
Y1417975D01*
G01X227586Y1412915D02*
Y1406915D01*
G01X227847Y1430783D02*
Y1424783D01*
G01X226533Y1631052D02*
Y1638552D01*
X228773D01*
X229520Y1638177D01*
X230080Y1637302D01*
X230267Y1636302D01*
X230080Y1635302D01*
X229613Y1634552D01*
X228773Y1634177D01*
X226533D01*
G01X234033Y1631052D02*
Y1638552D01*
X236367D01*
X237113Y1638177D01*
X237580Y1637677D01*
X237767Y1636677D01*
X237580Y1635677D01*
X237020Y1635052D01*
X236367Y1634677D01*
X234033D01*
G01X236367D02*
X237767Y1631052D01*
G01X245267D02*
X241533D01*
Y1638552D01*
X245267D01*
G01X243773Y1634927D02*
X241533D01*
G01X248940Y1632052D02*
X249687Y1631427D01*
X250527Y1631052D01*
X251273D01*
X252020Y1631427D01*
X252580Y1632052D01*
X252860Y1632927D01*
X252673Y1633802D01*
X252207Y1634552D01*
X251367Y1635052D01*
X250247Y1635302D01*
X249593Y1635802D01*
X249313Y1636677D01*
X249500Y1637552D01*
X249967Y1638177D01*
X250620Y1638552D01*
X251273D01*
X251927Y1638302D01*
X252487Y1637677D01*
G01X256440Y1632052D02*
X257187Y1631427D01*
X258027Y1631052D01*
X258773D01*
X259520Y1631427D01*
X260080Y1632052D01*
X260360Y1632927D01*
X260173Y1633802D01*
X259707Y1634552D01*
X258867Y1635052D01*
X257747Y1635302D01*
X257093Y1635802D01*
X256813Y1636677D01*
X257000Y1637552D01*
X257467Y1638177D01*
X258120Y1638552D01*
X258773D01*
X259427Y1638302D01*
X259987Y1637677D01*
G01X264687Y1633552D02*
X267113D01*
G01X271627Y1631052D02*
Y1638552D01*
X275173D01*
G01X273867Y1634927D02*
X271627D01*
G01X279780Y1638552D02*
X282020D01*
G01X280900D02*
Y1631052D01*
G01X279780D02*
X282020D01*
G01X288400Y1638552D02*
Y1631052D01*
G01X286253Y1638552D02*
X290547D01*
G01X230906Y1625425D02*
Y1628525D01*
X230446Y1627905D01*
G01Y1625425D02*
X231366D01*
G01X238052Y1627941D02*
X238282Y1628251D01*
X238550Y1628406D01*
X238857Y1628458D01*
X239240Y1628355D01*
X239508Y1628096D01*
X239585Y1627786D01*
X239547Y1627476D01*
X239393Y1627218D01*
X238627Y1626701D01*
X238282Y1626340D01*
X238052Y1625823D01*
X237975Y1625358D01*
X239585D01*
G01X225985Y1629488D02*
Y1769645D01*
G01X292520Y1629488D02*
X225985D01*
G01X238856Y1736412D02*
X239756Y1737312D01*
G01X233856Y1736412D02*
X238856D01*
G01X233856Y1739812D02*
Y1736412D01*
G01X235856Y1737812D02*
X233856Y1739812D01*
G01X231856Y1737812D02*
X235856D01*
G01X233856Y1739812D02*
X231856Y1737812D01*
G01X225985Y1740118D02*
X292520D01*
G01X225985Y1769645D02*
X292520D01*
G01X265465Y67636D02*
X253465D01*
G01D02*
Y73636D01*
G01X247620Y66962D02*
X250820D01*
G01X247620Y60762D02*
Y66962D01*
G01X250820Y60762D02*
X247620D01*
G01X250820Y66962D02*
Y60762D01*
G01X243620Y66962D02*
X246820D01*
G01X243620Y60762D02*
Y66962D01*
G01X246820Y60762D02*
X243620D01*
G01X246820Y66962D02*
Y60762D01*
G01X242820Y66962D02*
Y60762D01*
G01X240620Y70262D02*
Y73462D01*
G01X246820Y70262D02*
X240620D01*
G01X246820Y73462D02*
Y70262D01*
G01X253465Y73636D02*
X265465D01*
G01X265169Y75930D02*
X253169D01*
G01Y81930D02*
X265169D01*
G01X253169Y75930D02*
Y81930D01*
G01X246820Y77462D02*
Y74262D01*
G01X240620Y77462D02*
X246820D01*
G01X240620Y74262D02*
Y77462D01*
G01X246820Y74262D02*
X240620D01*
G01X256197Y85943D02*
Y89143D01*
G01X262397Y85943D02*
X256197D01*
G01X240620Y73462D02*
X246820D01*
G01X249287Y90433D02*
Y95033D01*
G01X259487Y90433D02*
X249287D01*
G01Y95033D02*
X259487D01*
G01X254387Y95333D02*
Y99933D01*
G01X249287D02*
X259487D01*
G01X249287Y95333D02*
Y99933D01*
G01X259487Y95333D02*
X249287D01*
G01X244110Y96882D02*
Y99382D01*
X243790Y98882D01*
G01Y96882D02*
X244430D01*
G01X246310D02*
Y99382D01*
X245990Y98882D01*
G01Y96882D02*
X246630D01*
G01X243290Y92022D02*
Y94522D01*
X242970Y94022D01*
G01Y92022D02*
X243610D01*
G01X244983Y94105D02*
X245143Y94355D01*
X245330Y94480D01*
X245543Y94522D01*
X245810Y94439D01*
X245997Y94230D01*
X246050Y93980D01*
X246023Y93730D01*
X245917Y93522D01*
X245383Y93105D01*
X245143Y92814D01*
X244983Y92397D01*
X244930Y92022D01*
X246050D01*
G01X249887Y103160D02*
Y109360D01*
G01X253087Y103160D02*
X249887D01*
G01X253087Y109360D02*
Y103160D01*
G01X249087D02*
X245887D01*
G01X249087Y109360D02*
Y103160D01*
G01X245887D02*
Y109360D01*
G01X245087Y103160D02*
X241887D01*
G01X245087Y109360D02*
Y103160D01*
G01X241887D02*
Y109360D01*
G01X256197Y89143D02*
X262397D01*
G01X251000Y118102D02*
Y120602D01*
X250680Y120102D01*
G01Y118102D02*
X251320D01*
G01X253200Y120602D02*
X252987Y120519D01*
X252827Y120310D01*
X252720Y120060D01*
X252640Y119727D01*
X252613Y119352D01*
X252640Y118977D01*
X252720Y118644D01*
X252827Y118394D01*
X252987Y118185D01*
X253200Y118102D01*
X253413Y118185D01*
X253573Y118394D01*
X253680Y118644D01*
X253760Y118977D01*
X253787Y119352D01*
X253760Y119727D01*
X253680Y120060D01*
X253573Y120310D01*
X253413Y120519D01*
X253200Y120602D01*
G01X256680Y119844D02*
X256494Y120053D01*
X256280Y120136D01*
X256067Y120053D01*
X255880Y119803D01*
X255747Y119428D01*
X255694Y119053D01*
Y118594D01*
X255747Y118219D01*
X255880Y117886D01*
X256040Y117719D01*
X256227Y117636D01*
X256440Y117719D01*
X256600Y117886D01*
X256707Y118136D01*
X256760Y118469D01*
X256707Y118761D01*
X256574Y119053D01*
X256414Y119219D01*
X256227Y119261D01*
X256014Y119178D01*
X255854Y118969D01*
X255694Y118594D01*
G01X256388Y115905D02*
Y112771D01*
G01X257553Y115905D02*
X256388D01*
G01Y110771D02*
Y108835D01*
G01Y103701D02*
X257553D01*
G01X256388Y106835D02*
Y103701D01*
G01X245697Y110143D02*
Y113343D01*
G01X251897Y110143D02*
X245697D01*
G01X251897Y113343D02*
Y110143D01*
G01X245697Y113343D02*
X251897D01*
G01Y117343D02*
Y114143D01*
G01X245697Y117343D02*
X251897D01*
G01X245697Y114143D02*
Y117343D01*
G01X251897Y114143D02*
X245697D01*
G01X249887Y109360D02*
X253087D01*
G01X245887D02*
X249087D01*
G01X241887D02*
X245087D01*
G01X245080Y136762D02*
X244773Y136814D01*
X244505Y137020D01*
X244275Y137330D01*
X244122Y137692D01*
X244045Y138105D01*
Y138519D01*
X244122Y138932D01*
X244275Y139294D01*
X244505Y139604D01*
X244773Y139810D01*
X245080Y139862D01*
X245387Y139810D01*
X245655Y139604D01*
X245885Y139294D01*
X246038Y138932D01*
X246115Y138519D01*
Y138105D01*
X246038Y137692D01*
X245885Y137330D01*
X245655Y137020D01*
X245387Y136814D01*
X245080Y136762D01*
G01X245387Y137589D02*
X245847Y136762D01*
G01X248180D02*
Y139862D01*
X247720Y139242D01*
G01Y136762D02*
X248640D01*
G01X251280D02*
Y139862D01*
X250820Y139242D01*
G01Y136762D02*
X251740D01*
G01X254380D02*
X254648Y136814D01*
X254955Y136969D01*
X255147Y137227D01*
X255223Y137589D01*
X255147Y137950D01*
X254917Y138260D01*
X254572Y138415D01*
X254188D01*
X253958Y138519D01*
X253767Y138777D01*
X253690Y139139D01*
X253805Y139500D01*
X254073Y139759D01*
X254380Y139862D01*
X254687Y139759D01*
X254955Y139500D01*
X255070Y139139D01*
X254993Y138777D01*
X254802Y138519D01*
X254572Y138415D01*
X254188D01*
X253843Y138260D01*
X253613Y137950D01*
X253537Y137589D01*
X253613Y137227D01*
X253805Y136969D01*
X254112Y136814D01*
X254380Y136762D01*
G01X255897Y122443D02*
X252697D01*
G01X255897Y128643D02*
Y122443D01*
G01X252697Y128643D02*
X255897D01*
G01X252697Y122443D02*
Y128643D01*
G01X251897Y122443D02*
X248697D01*
G01X251897Y128643D02*
Y122443D01*
G01X248697Y128643D02*
X251897D01*
G01X248697Y122443D02*
Y128643D01*
G01X247897Y122443D02*
X244697D01*
G01X247897Y128643D02*
Y122443D01*
G01X244697Y128643D02*
X247897D01*
G01X244697Y122443D02*
Y128643D01*
G01X243897Y122443D02*
X240697D01*
G01X243897Y128643D02*
Y122443D01*
G01X240697Y128643D02*
X243897D01*
G01X240697Y122443D02*
Y128643D01*
G01X251202Y151210D02*
Y142548D01*
G01X240708Y151210D02*
X251202D01*
G01X240708Y142548D02*
Y151210D01*
G01X244055Y142548D02*
X240708D01*
G01X245955Y144748D02*
X244055Y142548D01*
G01X247855D02*
X245955Y144748D01*
G01X251202Y142548D02*
X247855D01*
G01X243610Y164562D02*
X243303Y164614D01*
X243035Y164820D01*
X242805Y165130D01*
X242652Y165492D01*
X242575Y165905D01*
Y166319D01*
X242652Y166732D01*
X242805Y167094D01*
X243035Y167404D01*
X243303Y167610D01*
X243610Y167662D01*
X243917Y167610D01*
X244185Y167404D01*
X244415Y167094D01*
X244568Y166732D01*
X244645Y166319D01*
Y165905D01*
X244568Y165492D01*
X244415Y165130D01*
X244185Y164820D01*
X243917Y164614D01*
X243610Y164562D01*
G01X243917Y165389D02*
X244377Y164562D01*
G01X246710D02*
Y167662D01*
X246250Y167042D01*
G01Y164562D02*
X247170D01*
G01X249810D02*
Y167662D01*
X249350Y167042D01*
G01Y164562D02*
X250270D01*
G01X252258Y164924D02*
X252527Y164665D01*
X252833Y164562D01*
X253140Y164665D01*
X253408Y164975D01*
X253600Y165440D01*
X253677Y165905D01*
Y166474D01*
X253600Y166939D01*
X253408Y167352D01*
X253178Y167559D01*
X252910Y167662D01*
X252603Y167559D01*
X252373Y167352D01*
X252220Y167042D01*
X252143Y166629D01*
X252220Y166267D01*
X252412Y165905D01*
X252642Y165699D01*
X252910Y165647D01*
X253217Y165750D01*
X253447Y166009D01*
X253677Y166474D01*
G01X251242Y161934D02*
Y153272D01*
G01X247895Y161934D02*
X251242D01*
G01X245995Y159734D02*
X247895Y161934D01*
G01X244095D02*
X245995Y159734D01*
G01X240748Y153272D02*
Y161934D01*
G01X251242Y153272D02*
X240748D01*
G01Y161934D02*
X244095D01*
G01X256356Y161402D02*
Y155202D01*
G01D02*
X253156D01*
G01Y161402D02*
X256356D01*
G01X253156Y155202D02*
Y161402D01*
G01X246097Y200992D02*
X246200Y204091D01*
G01X247809Y204037D02*
X247706Y200939D01*
G01X247758Y202488D02*
X246148Y202542D01*
G01X249923Y200865D02*
X250022Y201534D01*
X250156Y202098D01*
X250326Y202609D01*
X250537Y203171D01*
X250869Y203935D01*
X249336Y203986D01*
G01X252270Y201252D02*
X252491Y200987D01*
X252754Y200823D01*
X253097Y200760D01*
X253446Y200851D01*
X253721Y201049D01*
X253924Y201404D01*
X253976Y201816D01*
X253914Y202232D01*
X253731Y202496D01*
X253469Y202712D01*
X253203Y202772D01*
X252933Y202730D01*
X252581Y202535D01*
X252741Y203873D01*
X253775Y203839D01*
G01X244153Y219109D02*
Y222209D01*
X245073D01*
X245380Y222054D01*
X245610Y221692D01*
X245687Y221279D01*
X245610Y220866D01*
X245418Y220556D01*
X245073Y220401D01*
X244153D01*
G01X247177Y222209D02*
Y219987D01*
X247330Y219522D01*
X247637Y219212D01*
X248020Y219109D01*
X248403Y219212D01*
X248710Y219522D01*
X248863Y219987D01*
Y222209D01*
G01X250392Y221692D02*
X250622Y222002D01*
X250890Y222157D01*
X251197Y222209D01*
X251580Y222106D01*
X251848Y221847D01*
X251925Y221537D01*
X251887Y221227D01*
X251733Y220969D01*
X250967Y220452D01*
X250622Y220091D01*
X250392Y219574D01*
X250315Y219109D01*
X251925D01*
G01X254220Y222209D02*
X253913Y222106D01*
X253683Y221847D01*
X253530Y221537D01*
X253415Y221124D01*
X253377Y220659D01*
X253415Y220194D01*
X253530Y219781D01*
X253683Y219471D01*
X253913Y219212D01*
X254220Y219109D01*
X254527Y219212D01*
X254757Y219471D01*
X254910Y219781D01*
X255025Y220194D01*
X255063Y220659D01*
X255025Y221124D01*
X254910Y221537D01*
X254757Y221847D01*
X254527Y222106D01*
X254220Y222209D01*
G01X257243Y219109D02*
X257320Y219781D01*
X257435Y220349D01*
X257588Y220866D01*
X257780Y221434D01*
X258087Y222209D01*
X256553D01*
G01X246794Y280585D02*
Y276785D01*
G01X247294Y280585D02*
Y276785D01*
G01X247794D02*
X240704D01*
G01X247794Y280585D02*
Y276785D01*
G01X240704Y280585D02*
X247794D01*
G01X252254Y276785D02*
Y280535D01*
G01X259394Y276785D02*
X252254D01*
G01X252304Y280585D02*
X259394D01*
G01X259894Y276785D02*
X252704D01*
G01Y280585D02*
X259894D01*
G01X260394Y276785D02*
X253304D01*
G01Y280585D02*
X260394D01*
G01X246064Y313234D02*
Y309434D01*
G01X246564Y313234D02*
Y309434D01*
G01X247064Y313234D02*
Y309434D01*
G01X251524D02*
Y313184D01*
G01X258664Y309434D02*
X251524D01*
G01X251574Y313234D02*
X258664D01*
G01X259164Y309434D02*
X251974D01*
G01Y313234D02*
X259164D01*
G01X259664Y309434D02*
X252574D01*
G01Y313234D02*
X259664D01*
G01X255170Y457017D02*
Y460217D01*
G01X261370Y457017D02*
X255170D01*
G01Y460217D02*
X261370D01*
G01X251108Y567576D02*
Y564376D01*
G01X244908Y567576D02*
X251108D01*
G01X244908Y564376D02*
Y567576D01*
G01X251108Y564376D02*
X244908D01*
G01X251565Y600232D02*
Y597032D01*
G01X245365Y600232D02*
X251565D01*
G01X245365Y597032D02*
Y600232D01*
G01X251565Y597032D02*
X245365D01*
G01X251266Y635448D02*
Y632248D01*
G01X245066Y635448D02*
X251266D01*
G01X245066Y632248D02*
Y635448D01*
G01X251266Y632248D02*
X245066D01*
G01X254018Y664750D02*
X242018D01*
G01X254018Y670750D02*
Y664750D01*
G01X242018Y670750D02*
X254018D01*
G01X242018Y664750D02*
Y670750D01*
G01X247118Y704997D02*
Y701797D01*
G01X240918Y704997D02*
X247118D01*
G01X240918Y701797D02*
Y704997D01*
G01X247118Y701797D02*
X240918D01*
G01X242310Y1337525D02*
X242502Y1337215D01*
X242732Y1337008D01*
X243000Y1336905D01*
X243307Y1337008D01*
X243537Y1337215D01*
X243767Y1337525D01*
X243844Y1337938D01*
Y1340005D01*
G01X246177Y1336905D02*
Y1340005D01*
X245717Y1339385D01*
G01Y1336905D02*
X246637D01*
G01X249277D02*
X249545Y1336957D01*
X249852Y1337112D01*
X250044Y1337370D01*
X250120Y1337732D01*
X250044Y1338093D01*
X249814Y1338403D01*
X249469Y1338558D01*
X249085D01*
X248855Y1338662D01*
X248664Y1338920D01*
X248587Y1339282D01*
X248702Y1339643D01*
X248970Y1339902D01*
X249277Y1340005D01*
X249584Y1339902D01*
X249852Y1339643D01*
X249967Y1339282D01*
X249890Y1338920D01*
X249699Y1338662D01*
X249469Y1338558D01*
X249085D01*
X248740Y1338403D01*
X248510Y1338093D01*
X248434Y1337732D01*
X248510Y1337370D01*
X248702Y1337112D01*
X249009Y1336957D01*
X249277Y1336905D01*
G01X245811Y1626045D02*
X246041Y1625683D01*
X246347Y1625477D01*
X246692Y1625425D01*
X246999Y1625477D01*
X247306Y1625735D01*
X247497Y1626045D01*
X247536Y1626355D01*
X247459Y1626717D01*
X247191Y1626975D01*
X246922Y1627078D01*
X246577D01*
G01X246922D02*
X247152Y1627233D01*
X247344Y1627492D01*
X247421Y1627802D01*
X247344Y1628112D01*
X247152Y1628370D01*
X246807Y1628525D01*
X246462Y1628473D01*
X246117Y1628267D01*
G01X254988Y1625358D02*
Y1628458D01*
X253570Y1626236D01*
X255486D01*
G01X242239Y1736579D02*
X241173D01*
Y1739079D01*
X242239D01*
G01X241813Y1737871D02*
X241173D01*
G01X243319Y1736579D02*
Y1739079D01*
X243853D01*
X244066Y1738954D01*
X244226Y1738787D01*
X244359Y1738537D01*
X244466Y1738246D01*
X244493Y1737829D01*
X244466Y1737412D01*
X244359Y1737121D01*
X244226Y1736871D01*
X244066Y1736704D01*
X243853Y1736579D01*
X243319D01*
G01X246266Y1737829D02*
X246799D01*
Y1737079D01*
X246639Y1736829D01*
X246453Y1736662D01*
X246186Y1736579D01*
X245919Y1736662D01*
X245733Y1736829D01*
X245573Y1737079D01*
X245466Y1737371D01*
X245413Y1737704D01*
Y1737996D01*
X245466Y1738246D01*
X245573Y1738537D01*
X245733Y1738787D01*
X245893Y1738954D01*
X246106Y1739079D01*
X246293D01*
X246506Y1738996D01*
X246666Y1738829D01*
G01X248839Y1736579D02*
X247773D01*
Y1739079D01*
X248839D01*
G01X248413Y1737871D02*
X247773D01*
G01X252706Y1736579D02*
X252493Y1736621D01*
X252306Y1736787D01*
X252146Y1737037D01*
X252039Y1737329D01*
X251986Y1737662D01*
Y1737996D01*
X252039Y1738329D01*
X252146Y1738621D01*
X252306Y1738871D01*
X252493Y1739037D01*
X252706Y1739079D01*
X252919Y1739037D01*
X253106Y1738871D01*
X253266Y1738621D01*
X253373Y1738329D01*
X253426Y1737996D01*
Y1737662D01*
X253373Y1737329D01*
X253266Y1737037D01*
X253106Y1736787D01*
X252919Y1736621D01*
X252706Y1736579D01*
G01X254399D02*
Y1739079D01*
X255413D01*
G01X255039Y1737871D02*
X254399D01*
G01X258719Y1736579D02*
Y1739079D01*
X259253D01*
X259466Y1738954D01*
X259626Y1738787D01*
X259759Y1738537D01*
X259866Y1738246D01*
X259893Y1737829D01*
X259866Y1737412D01*
X259759Y1737121D01*
X259626Y1736871D01*
X259466Y1736704D01*
X259253Y1736579D01*
X258719D01*
G01X260839D02*
X261506Y1739079D01*
X262173Y1736579D01*
G01X261933Y1737454D02*
X261079D01*
G01X263119Y1739079D02*
Y1737287D01*
X263226Y1736912D01*
X263439Y1736662D01*
X263706Y1736579D01*
X263973Y1736662D01*
X264186Y1736912D01*
X264293Y1737287D01*
Y1739079D01*
G01X266066Y1737829D02*
X266599D01*
Y1737079D01*
X266439Y1736829D01*
X266253Y1736662D01*
X265986Y1736579D01*
X265719Y1736662D01*
X265533Y1736829D01*
X265373Y1737079D01*
X265266Y1737371D01*
X265213Y1737704D01*
Y1737996D01*
X265266Y1738246D01*
X265373Y1738537D01*
X265533Y1738787D01*
X265693Y1738954D01*
X265906Y1739079D01*
X266093D01*
X266306Y1738996D01*
X266466Y1738829D01*
G01X267546Y1736579D02*
Y1739079D01*
G01X268666D02*
Y1736579D01*
G01Y1737829D02*
X267546D01*
G01X270306Y1739079D02*
Y1736579D01*
G01X269693Y1739079D02*
X270919D01*
G01X273039Y1736579D02*
X271973D01*
Y1739079D01*
X273039D01*
G01X272613Y1737871D02*
X271973D01*
G01X274173Y1736579D02*
Y1739079D01*
X274839D01*
X275053Y1738954D01*
X275186Y1738787D01*
X275239Y1738454D01*
X275186Y1738121D01*
X275026Y1737912D01*
X274839Y1737787D01*
X274173D01*
G01X274839D02*
X275239Y1736579D01*
G01X277493Y1738871D02*
X277333Y1738996D01*
X277146Y1739079D01*
X276933D01*
X276693Y1738954D01*
X276506Y1738746D01*
X276373Y1738496D01*
X276266Y1738079D01*
X276239Y1737704D01*
X276293Y1737329D01*
X276373Y1737079D01*
X276533Y1736829D01*
X276719Y1736662D01*
X276906Y1736579D01*
X277093D01*
X277279Y1736662D01*
X277439Y1736787D01*
X277573Y1736954D01*
G01X278439Y1736579D02*
X279106Y1739079D01*
X279773Y1736579D01*
G01X279533Y1737454D02*
X278679D01*
G01X280773Y1736579D02*
Y1739079D01*
X281439D01*
X281653Y1738954D01*
X281786Y1738787D01*
X281839Y1738454D01*
X281786Y1738121D01*
X281626Y1737912D01*
X281439Y1737787D01*
X280773D01*
G01X281439D02*
X281839Y1736579D01*
G01X282919D02*
Y1739079D01*
X283453D01*
X283666Y1738954D01*
X283826Y1738787D01*
X283959Y1738537D01*
X284066Y1738246D01*
X284093Y1737829D01*
X284066Y1737412D01*
X283959Y1737121D01*
X283826Y1736871D01*
X283666Y1736704D01*
X283453Y1736579D01*
X282919D01*
G01X263536Y57760D02*
Y54560D01*
G01X257336D02*
Y57760D01*
G01X263536Y54560D02*
X257336D01*
G01X275372Y43779D02*
X260572D01*
G01X265465Y73636D02*
Y67636D01*
G01X263581Y66055D02*
Y62855D01*
G01X257381Y66055D02*
X263581D01*
G01X257381Y62855D02*
Y66055D01*
G01X263581Y62855D02*
X257381D01*
G01X263533Y61945D02*
Y58745D01*
G01X257333Y61945D02*
X263533D01*
G01X257333Y58745D02*
Y61945D01*
G01X263533Y58745D02*
X257333D01*
G01X257336Y57760D02*
X263536D01*
G01X265169Y81930D02*
Y75930D01*
G01X262397Y89143D02*
Y85943D01*
G01X259487Y95033D02*
Y90433D01*
G01Y99933D02*
Y95333D01*
G01X272167Y97583D02*
Y100783D01*
G01X278367Y97583D02*
X272167D01*
G01Y100783D02*
X278367D01*
G01X273397Y122443D02*
X270197D01*
G01Y128643D02*
X273397D01*
G01X270197Y122443D02*
Y128643D01*
G01X262897Y122443D02*
X259697D01*
G01X262897Y128643D02*
Y122443D01*
G01X259697Y128643D02*
X262897D01*
G01X259697Y122443D02*
Y128643D01*
G01X269897Y125943D02*
X266697D01*
G01X269897Y132143D02*
Y125943D01*
G01X266697Y132143D02*
X269897D01*
G01X266697Y125943D02*
Y132143D01*
G01X268400Y135362D02*
Y138562D01*
G01X274600Y135362D02*
X268400D01*
G01X265450Y141292D02*
Y144492D01*
G01X271650Y141292D02*
X265450D01*
G01X271650Y144492D02*
Y141292D01*
G01X265450Y144492D02*
X271650D01*
G01X261533Y142202D02*
X258333D01*
G01X261533Y148402D02*
Y142202D01*
G01X258333Y148402D02*
X261533D01*
G01X258333Y142202D02*
Y148402D01*
G01X261700Y152362D02*
X258500D01*
G01X261700Y158562D02*
Y152362D01*
G01X258500D02*
Y158562D01*
G01X271653Y152803D02*
Y149603D01*
G01X265453D02*
Y152803D01*
G01X271653Y149603D02*
X265453D01*
G01Y148803D02*
X271653D01*
G01D02*
Y145603D01*
G01X265453D02*
Y148803D01*
G01X271653Y145603D02*
X265453D01*
G01X268400Y138562D02*
X274600D01*
G01X258500Y158562D02*
X261700D01*
G01X265453Y157603D02*
Y160803D01*
G01X271653Y157603D02*
X265453D01*
G01X271653Y160803D02*
Y157603D01*
G01X265453Y160803D02*
X271653D01*
G01X265453Y152803D02*
X271653D01*
G01X265453Y153603D02*
Y156803D01*
G01X271653Y153603D02*
X265453D01*
G01X271653Y156803D02*
Y153603D01*
G01X265453Y156803D02*
X271653D01*
G01X269220Y212422D02*
X275420D01*
G01X269220Y209222D02*
Y212422D01*
G01X275420Y209222D02*
X269220D01*
G01X261120Y212422D02*
Y215622D01*
G01X267320Y212422D02*
X261120D01*
G01X267320Y215622D02*
Y212422D01*
G01X261120Y215622D02*
X267320D01*
G01X261980Y225702D02*
X265180D01*
G01X261980Y219502D02*
Y225702D01*
G01X265180Y219502D02*
X261980D01*
G01X265180Y225702D02*
Y219502D01*
G01X266859Y218895D02*
Y230669D01*
G01X276621Y218895D02*
X266859D01*
G01Y230669D02*
X276621D01*
G01X264840Y237682D02*
X261640D01*
G01X264840Y243882D02*
Y237682D01*
G01X261640Y243882D02*
X264840D01*
G01X261640Y237682D02*
Y243882D01*
G01X268640D02*
X271840D01*
G01X268640Y237682D02*
Y243882D01*
G01X271840Y237682D02*
X268640D01*
G01X271840Y243882D02*
Y237682D01*
G01X266159Y259331D02*
X269359D01*
G01X266159Y253131D02*
Y259331D01*
G01X269359Y253131D02*
X266159D01*
G01X269359Y259331D02*
Y253131D01*
G01X270221Y259331D02*
X273421D01*
G01X270221Y253131D02*
Y259331D01*
G01X273421Y253131D02*
X270221D01*
G01X259394Y280585D02*
Y276785D01*
G01X259894Y280585D02*
Y276785D01*
G01X260394Y280585D02*
Y276785D01*
G01X264854D02*
Y280535D01*
G01X271994Y276785D02*
X264854D01*
G01X271994Y280585D02*
Y276785D01*
G01X264904Y280585D02*
X271994D01*
G01X272494Y276785D02*
X265304D01*
G01X272494Y280585D02*
Y276785D01*
G01X265304Y280585D02*
X272494D01*
G01X272994Y276785D02*
X265904D01*
G01X272994Y280585D02*
Y276785D01*
G01X265904Y280585D02*
X272994D01*
G01X264124Y309434D02*
Y313184D01*
G01X271264Y309434D02*
X264124D01*
G01X271264Y313234D02*
Y309434D01*
G01X264174Y313234D02*
X271264D01*
G01X271764Y309434D02*
X264574D01*
G01X271764Y313234D02*
Y309434D01*
G01X264574Y313234D02*
X271764D01*
G01X272264Y309434D02*
X265174D01*
G01X272264Y313234D02*
Y309434D01*
G01X265174Y313234D02*
X272264D01*
G01X258664D02*
Y309434D01*
G01X259164Y313234D02*
Y309434D01*
G01X259664Y313234D02*
Y309434D01*
G01X264954Y421135D02*
Y424335D01*
G01X271154Y421135D02*
X264954D01*
G01X271154Y424335D02*
Y421135D01*
G01X264954Y424335D02*
X271154D01*
G01X264936Y416979D02*
Y420179D01*
G01X271136Y416979D02*
X264936D01*
G01X271136Y420179D02*
Y416979D01*
G01X264936Y420179D02*
X271136D01*
G01X264954Y425135D02*
Y428335D01*
G01X271154Y425135D02*
X264954D01*
G01X271154Y428335D02*
Y425135D01*
G01X264954Y428335D02*
X271154D01*
G01X264986Y429439D02*
Y432639D01*
G01X271186Y429439D02*
X264986D01*
G01X271186Y432639D02*
Y429439D01*
G01X264986Y432639D02*
X271186D01*
G01X271184Y441205D02*
Y438005D01*
G01X264984Y441205D02*
X271184D01*
G01X264984Y438005D02*
Y441205D01*
G01X271184Y438005D02*
X264984D01*
G01X264954Y442135D02*
Y445335D01*
G01X271154Y442135D02*
X264954D01*
G01X271154Y445335D02*
Y442135D01*
G01X261370Y460217D02*
Y457017D01*
G01X271154Y453335D02*
Y450135D01*
G01X264954Y453335D02*
X271154D01*
G01X264954Y450135D02*
Y453335D01*
G01X271154Y450135D02*
X264954D01*
G01X271154Y449335D02*
Y446135D01*
G01X264954Y449335D02*
X271154D01*
G01X264954Y446135D02*
Y449335D01*
G01X271154Y446135D02*
X264954D01*
G01Y445335D02*
X271154D01*
G01X268343Y543317D02*
Y546417D01*
X269340Y543834D01*
X270337Y546417D01*
Y543317D01*
G01X273207D02*
X271673D01*
Y546417D01*
X273207D01*
G01X272593Y544919D02*
X271673D01*
G01X274812Y545900D02*
X275042Y546210D01*
X275310Y546365D01*
X275617Y546417D01*
X276000Y546314D01*
X276268Y546055D01*
X276345Y545745D01*
X276307Y545435D01*
X276153Y545177D01*
X275387Y544660D01*
X275042Y544299D01*
X274812Y543782D01*
X274735Y543317D01*
X276345D01*
G01X258285Y573255D02*
Y569260D01*
G01X286116Y579639D02*
G03I-10827J0D01*
G01X258285Y594850D02*
Y590855D01*
G01X286116Y579639D02*
X264462D01*
G01X258285Y607255D02*
Y603260D01*
G01X286116Y603798D02*
G03I-10827J0D01*
G01D02*
X264462D01*
G01X286116Y627952D02*
G03I-10827J0D01*
G01X258285Y641255D02*
Y637260D01*
G01Y628850D02*
Y624855D01*
G01X286116Y627952D02*
X264462D01*
G01X286116Y652106D02*
G03I-10827J0D01*
G01D02*
X264462D01*
G01X258285Y662850D02*
Y658855D01*
G01X285016Y676260D02*
G03I-10827J0D01*
G01X260927Y679298D02*
Y673350D01*
G01Y698546D02*
Y692598D01*
G01X260815Y697211D02*
Y1335007D01*
G01X285016Y700414D02*
G03I-10827J0D01*
G01X273383Y1332362D02*
Y1335462D01*
X274303D01*
X274610Y1335307D01*
X274840Y1334945D01*
X274917Y1334532D01*
X274840Y1334119D01*
X274648Y1333809D01*
X274303Y1333654D01*
X273383D01*
G01X276407Y1335462D02*
Y1333240D01*
X276560Y1332775D01*
X276867Y1332465D01*
X277250Y1332362D01*
X277633Y1332465D01*
X277940Y1332775D01*
X278093Y1333240D01*
Y1335462D01*
G01X279622Y1334945D02*
X279852Y1335255D01*
X280120Y1335410D01*
X280427Y1335462D01*
X280810Y1335359D01*
X281078Y1335100D01*
X281155Y1334790D01*
X281117Y1334480D01*
X280963Y1334222D01*
X280197Y1333705D01*
X279852Y1333344D01*
X279622Y1332827D01*
X279545Y1332362D01*
X281155D01*
G01X283910D02*
Y1335462D01*
X282492Y1333240D01*
X284408D01*
G01X285400Y1331329D02*
X287700D01*
G01X288883Y1332362D02*
Y1335462D01*
X289803D01*
X290110Y1335307D01*
X290340Y1334945D01*
X290417Y1334532D01*
X290340Y1334119D01*
X290148Y1333809D01*
X289803Y1333654D01*
X288883D01*
G01X292750Y1332362D02*
Y1335462D01*
X292290Y1334842D01*
G01Y1332362D02*
X293210D01*
G01X294700Y1331329D02*
X297000D01*
G01X298873Y1332362D02*
X298950Y1333034D01*
X299065Y1333602D01*
X299218Y1334119D01*
X299410Y1334687D01*
X299717Y1335462D01*
X298183D01*
G01X261559Y1625890D02*
X261789Y1625632D01*
X262057Y1625477D01*
X262402Y1625425D01*
X262747Y1625528D01*
X263015Y1625735D01*
X263207Y1626097D01*
X263245Y1626510D01*
X263169Y1626923D01*
X262977Y1627182D01*
X262709Y1627388D01*
X262440Y1627440D01*
X262172Y1627388D01*
X261827Y1627182D01*
X261942Y1628525D01*
X262977D01*
G01X269548Y1626650D02*
X269816Y1627011D01*
X270046Y1627218D01*
X270353Y1627321D01*
X270621Y1627218D01*
X270813Y1627011D01*
X270966Y1626701D01*
X271004Y1626340D01*
X270966Y1626030D01*
X270813Y1625720D01*
X270583Y1625461D01*
X270314Y1625358D01*
X270008Y1625461D01*
X269739Y1625771D01*
X269586Y1626236D01*
X269548Y1626753D01*
X269624Y1627425D01*
X269739Y1627786D01*
X269931Y1628148D01*
X270199Y1628406D01*
X270468Y1628458D01*
X270736Y1628355D01*
X270928Y1628096D01*
G01X321902Y51139D02*
X286330D01*
G01X276392Y81221D02*
Y84321D01*
X277312D01*
X277619Y84166D01*
X277849Y83804D01*
X277926Y83391D01*
X277849Y82978D01*
X277657Y82668D01*
X277312Y82513D01*
X276392D01*
G01X279416Y84321D02*
Y82099D01*
X279569Y81634D01*
X279876Y81324D01*
X280259Y81221D01*
X280642Y81324D01*
X280949Y81634D01*
X281102Y82099D01*
Y84321D01*
G01X282631Y83804D02*
X282861Y84114D01*
X283129Y84269D01*
X283436Y84321D01*
X283819Y84218D01*
X284087Y83959D01*
X284164Y83649D01*
X284126Y83339D01*
X283972Y83081D01*
X283206Y82564D01*
X282861Y82203D01*
X282631Y81686D01*
X282554Y81221D01*
X284164D01*
G01X286459Y84321D02*
X286152Y84218D01*
X285922Y83959D01*
X285769Y83649D01*
X285654Y83236D01*
X285616Y82771D01*
X285654Y82306D01*
X285769Y81893D01*
X285922Y81583D01*
X286152Y81324D01*
X286459Y81221D01*
X286766Y81324D01*
X286996Y81583D01*
X287149Y81893D01*
X287264Y82306D01*
X287302Y82771D01*
X287264Y83236D01*
X287149Y83649D01*
X286996Y83959D01*
X286766Y84218D01*
X286459Y84321D01*
G01X289559Y81221D02*
Y84321D01*
X289099Y83701D01*
G01Y81221D02*
X290019D01*
G01X277883Y104815D02*
X278043Y105065D01*
X278230Y105190D01*
X278443Y105232D01*
X278710Y105149D01*
X278897Y104940D01*
X278950Y104690D01*
X278923Y104440D01*
X278817Y104232D01*
X278283Y103815D01*
X278043Y103524D01*
X277883Y103107D01*
X277830Y102732D01*
X278950D01*
G01X280590Y105232D02*
X280377Y105149D01*
X280217Y104940D01*
X280110Y104690D01*
X280030Y104357D01*
X280003Y103982D01*
X280030Y103607D01*
X280110Y103274D01*
X280217Y103024D01*
X280377Y102815D01*
X280590Y102732D01*
X280803Y102815D01*
X280963Y103024D01*
X281070Y103274D01*
X281150Y103607D01*
X281177Y103982D01*
X281150Y104357D01*
X281070Y104690D01*
X280963Y104940D01*
X280803Y105149D01*
X280590Y105232D01*
G01X278367Y100783D02*
Y97583D01*
G01X284092Y108666D02*
Y111766D01*
X285012D01*
X285319Y111611D01*
X285549Y111249D01*
X285626Y110836D01*
X285549Y110423D01*
X285357Y110113D01*
X285012Y109958D01*
X284092D01*
G01X287116Y111766D02*
Y109544D01*
X287269Y109079D01*
X287576Y108769D01*
X287959Y108666D01*
X288342Y108769D01*
X288649Y109079D01*
X288802Y109544D01*
Y111766D01*
G01X290331Y111249D02*
X290561Y111559D01*
X290829Y111714D01*
X291136Y111766D01*
X291519Y111663D01*
X291787Y111404D01*
X291864Y111094D01*
X291826Y110784D01*
X291672Y110526D01*
X290906Y110009D01*
X290561Y109648D01*
X290331Y109131D01*
X290254Y108666D01*
X291864D01*
G01X294159Y111766D02*
X293852Y111663D01*
X293622Y111404D01*
X293469Y111094D01*
X293354Y110681D01*
X293316Y110216D01*
X293354Y109751D01*
X293469Y109338D01*
X293622Y109028D01*
X293852Y108769D01*
X294159Y108666D01*
X294466Y108769D01*
X294696Y109028D01*
X294849Y109338D01*
X294964Y109751D01*
X295002Y110216D01*
X294964Y110681D01*
X294849Y111094D01*
X294696Y111404D01*
X294466Y111663D01*
X294159Y111766D01*
G01X296531Y109958D02*
X296799Y110319D01*
X297029Y110526D01*
X297336Y110629D01*
X297604Y110526D01*
X297796Y110319D01*
X297949Y110009D01*
X297987Y109648D01*
X297949Y109338D01*
X297796Y109028D01*
X297566Y108769D01*
X297297Y108666D01*
X296991Y108769D01*
X296722Y109079D01*
X296569Y109544D01*
X296531Y110061D01*
X296607Y110733D01*
X296722Y111094D01*
X296914Y111456D01*
X297182Y111714D01*
X297451Y111766D01*
X297719Y111663D01*
X297911Y111404D01*
G01X276466Y103701D02*
Y106842D01*
G01Y115905D02*
X275293D01*
G01X276466Y112764D02*
Y115905D01*
G01X275301Y103701D02*
X276466D01*
G01Y108853D02*
Y110753D01*
G01X290957Y114403D02*
X287757D01*
G01D02*
Y120603D01*
G01X278643Y125315D02*
X278803Y125565D01*
X278990Y125690D01*
X279203Y125732D01*
X279470Y125649D01*
X279657Y125440D01*
X279710Y125190D01*
X279683Y124940D01*
X279577Y124732D01*
X279043Y124315D01*
X278803Y124024D01*
X278643Y123607D01*
X278590Y123232D01*
X279710D01*
G01X281350D02*
Y125732D01*
X281030Y125232D01*
G01Y123232D02*
X281670D01*
G01X282750Y122399D02*
X284350D01*
G01X285243Y125315D02*
X285403Y125565D01*
X285590Y125690D01*
X285803Y125732D01*
X286070Y125649D01*
X286257Y125440D01*
X286310Y125190D01*
X286283Y124940D01*
X286177Y124732D01*
X285643Y124315D01*
X285403Y124024D01*
X285243Y123607D01*
X285190Y123232D01*
X286310D01*
G01X287443Y125315D02*
X287603Y125565D01*
X287790Y125690D01*
X288003Y125732D01*
X288270Y125649D01*
X288457Y125440D01*
X288510Y125190D01*
X288483Y124940D01*
X288377Y124732D01*
X287843Y124315D01*
X287603Y124024D01*
X287443Y123607D01*
X287390Y123232D01*
X288510D01*
G01X287757Y120603D02*
X290957D01*
G01X273397Y128643D02*
Y122443D01*
G01X274197Y128643D02*
X277397D01*
G01X274197Y122443D02*
Y128643D01*
G01X277397Y122443D02*
X274197D01*
G01X277397Y128643D02*
Y122443D01*
G01X275300Y135362D02*
Y138562D01*
G01X281500Y135362D02*
X275300D01*
G01X281500Y138562D02*
Y135362D01*
G01X288400Y138562D02*
Y135362D01*
G01X282200D02*
Y138562D01*
G01X288400Y135362D02*
X282200D01*
G01X274600Y138562D02*
Y135362D01*
G01X280347Y148897D02*
Y150850D01*
G01X282300Y148897D02*
X280347D01*
G01X275300Y138562D02*
X281500D01*
G01X282200D02*
X288400D01*
G01X295300Y137562D02*
X289100D01*
G01Y140762D02*
X295300D01*
G01X289100Y137562D02*
Y140762D01*
G01X280347Y160709D02*
X282300D01*
G01X280347Y158756D02*
Y160709D01*
G01X295800Y207812D02*
X283800D01*
G01Y213812D02*
X295800D01*
G01X283800Y207812D02*
Y213812D01*
G01X285640Y227102D02*
Y215102D01*
G01X279640D02*
Y227102D01*
G01X285640Y215102D02*
X279640D01*
G01X275420Y212422D02*
Y209222D01*
G01X276180Y209202D02*
Y212402D01*
G01X282380Y209202D02*
X276180D01*
G01X282380Y212402D02*
Y209202D01*
G01X276180Y212402D02*
X282380D01*
G01X279640Y227102D02*
X285640D01*
G01X287133Y231206D02*
Y228006D01*
G01X280933Y231206D02*
X287133D01*
G01X280933Y228006D02*
Y231206D01*
G01X287133Y228006D02*
X280933D01*
G01X276621Y230669D02*
Y218895D01*
G01X276253Y247312D02*
X278493D01*
G01X277280Y248937D02*
Y245687D01*
G01X280291Y249385D02*
X309850D01*
G01X280291Y237889D02*
Y249385D01*
G01X309850Y237889D02*
X280291D01*
G01X278840Y237682D02*
X275640D01*
G01X278840Y243882D02*
Y237682D01*
G01X275640Y243882D02*
X278840D01*
G01X275640Y237682D02*
Y243882D01*
G01X273421Y259331D02*
Y253131D01*
G01X274891Y259331D02*
X278091D01*
G01X274891Y253131D02*
Y259331D01*
G01X278091Y253131D02*
X274891D01*
G01X278091Y259331D02*
Y253131D01*
G01X279477Y259331D02*
X282677D01*
G01X279477Y253131D02*
Y259331D01*
G01X282677Y253131D02*
X279477D01*
G01X282677Y259331D02*
Y253131D01*
G01X284881Y259331D02*
X288081D01*
G01X284881Y253131D02*
Y259331D01*
G01X288081Y253131D02*
X284881D01*
G01X288081Y259331D02*
Y253131D01*
G01X273830Y267672D02*
X278960D01*
G01X283800D02*
X289160D01*
G01X277454Y276785D02*
Y280535D01*
G01X284594Y276785D02*
X277454D01*
G01X284594Y280585D02*
Y276785D01*
G01X277504Y280585D02*
X284594D01*
G01X285094Y276785D02*
X277904D01*
G01X285094Y280585D02*
Y276785D01*
G01X277904Y280585D02*
X285094D01*
G01X285594Y276785D02*
X278504D01*
G01X285594Y280585D02*
Y276785D01*
G01X278504Y280585D02*
X285594D01*
G01X287674Y297988D02*
X290874D01*
G01X287674Y291788D02*
Y297988D01*
G01X290874Y291788D02*
X287674D01*
G01X282915Y297988D02*
X286115D01*
G01X282915Y291788D02*
Y297988D01*
G01X286115Y291788D02*
X282915D01*
G01X286115Y297988D02*
Y291788D01*
G01X289324Y309434D02*
Y313184D01*
G01X296464Y309434D02*
X289324D01*
G01X289374Y313234D02*
X296464D01*
G01X276724Y309434D02*
Y313184D01*
G01X283864Y309434D02*
X276724D01*
G01X283864Y313234D02*
Y309434D01*
G01X276774Y313234D02*
X283864D01*
G01X284364Y309434D02*
X277174D01*
G01X284364Y313234D02*
Y309434D01*
G01X277174Y313234D02*
X284364D01*
G01X284864Y309434D02*
X277774D01*
G01X284864Y313234D02*
Y309434D01*
G01X277774Y313234D02*
X284864D01*
G01X280100Y453462D02*
Y450262D01*
G01X273900Y453462D02*
X280100D01*
G01X273900Y450262D02*
Y453462D01*
G01X280100Y450262D02*
X273900D01*
G01X280100Y449462D02*
Y446262D01*
G01X273900Y449462D02*
X280100D01*
G01X273900Y446262D02*
Y449462D01*
G01X280100Y446262D02*
X273900D01*
G01X291620Y567948D02*
X285420D01*
G01D02*
Y571148D01*
G01D02*
X291620D01*
G01Y564422D02*
X285420D01*
G01D02*
Y567622D01*
G01D02*
X291620D01*
G01X288247Y620466D02*
X304343D01*
G01X288247Y627896D02*
Y620644D01*
G01X304343Y627896D02*
X288247D01*
G01X287520Y639409D02*
X293720D01*
G01Y636209D02*
X287520D01*
G01D02*
Y639409D01*
G01X294220Y632683D02*
X288020D01*
G01D02*
Y635883D01*
G01D02*
X294220D01*
G01Y629157D02*
X288020D01*
G01D02*
Y632357D01*
G01D02*
X294220D01*
G01X274189Y687087D02*
Y665433D01*
G01X286294Y686671D02*
X292494D01*
G01X286294Y683471D02*
Y686671D01*
G01X292494Y683471D02*
X286294D01*
G01Y686997D02*
Y690197D01*
G01X292494Y686997D02*
X286294D01*
G01Y690197D02*
X292494D01*
G01X274189Y711241D02*
Y689587D01*
G01X289487Y996187D02*
Y999287D01*
G01X291097D02*
Y996187D01*
G01Y997737D02*
X289487D01*
G01X292664Y998770D02*
X292894Y999080D01*
X293162Y999235D01*
X293469Y999287D01*
X293852Y999184D01*
X294120Y998925D01*
X294197Y998615D01*
X294159Y998305D01*
X294005Y998047D01*
X293239Y997530D01*
X292894Y997169D01*
X292664Y996652D01*
X292587Y996187D01*
X294197D01*
G01X296952D02*
Y999287D01*
X295534Y997065D01*
X297450D01*
G01X278073Y1625425D02*
X278150Y1626097D01*
X278265Y1626665D01*
X278418Y1627182D01*
X278610Y1627750D01*
X278917Y1628525D01*
X277383D01*
G01X286024Y1625358D02*
X286292Y1625410D01*
X286599Y1625565D01*
X286791Y1625823D01*
X286867Y1626185D01*
X286791Y1626546D01*
X286561Y1626856D01*
X286216Y1627011D01*
X285832D01*
X285602Y1627115D01*
X285411Y1627373D01*
X285334Y1627735D01*
X285449Y1628096D01*
X285717Y1628355D01*
X286024Y1628458D01*
X286331Y1628355D01*
X286599Y1628096D01*
X286714Y1627735D01*
X286637Y1627373D01*
X286446Y1627115D01*
X286216Y1627011D01*
X285832D01*
X285487Y1626856D01*
X285257Y1626546D01*
X285181Y1626185D01*
X285257Y1625823D01*
X285449Y1625565D01*
X285756Y1625410D01*
X286024Y1625358D01*
G01X281103Y1646023D02*
Y1781456D01*
G01X371260Y1646023D02*
X281103D01*
G01X289595Y1670205D02*
Y1673305D01*
X291359Y1670205D01*
Y1673305D01*
G01X289480Y1674929D02*
Y1678029D01*
X290477Y1675446D01*
X291474Y1678029D01*
Y1674929D01*
G01X289710Y1682753D02*
Y1679653D01*
X291244D01*
G01X290017Y1696927D02*
X290937D01*
G01X290477D02*
Y1693827D01*
G01X290017D02*
X290937D01*
G01X289634Y1684378D02*
Y1687478D01*
G01X291090D02*
X289634Y1685566D01*
G01X291320Y1684378D02*
X290285Y1686445D01*
G01X289710Y1689722D02*
X289902Y1689412D01*
X290132Y1689205D01*
X290400Y1689102D01*
X290707Y1689205D01*
X290937Y1689412D01*
X291167Y1689722D01*
X291244Y1690135D01*
Y1692202D01*
G01X281103Y1781456D02*
X371260D01*
G01X304394Y54005D02*
Y65501D01*
G01X333953Y54005D02*
X304394D01*
G01X300854Y60053D02*
X303280D01*
G01X304394Y65501D02*
X333953D01*
G01X300017Y69113D02*
Y65913D01*
G01X293817Y69113D02*
X300017D01*
G01X293817Y65913D02*
Y69113D01*
G01X300017Y65913D02*
X293817D01*
G01X300917Y66892D02*
Y73092D01*
G01X304117Y66892D02*
X300917D01*
G01X304117Y73092D02*
Y66892D01*
G01X293817Y69913D02*
Y73113D01*
G01X300017Y69913D02*
X293817D01*
G01X300017Y73113D02*
Y69913D01*
G01X305439Y77379D02*
X319415D01*
G01X305439Y85567D02*
Y77379D01*
G01X319415Y85567D02*
X305439D01*
G01X293847Y74073D02*
Y77273D01*
G01X300047Y74073D02*
X293847D01*
G01X300047Y77273D02*
Y74073D01*
G01X293847Y77273D02*
X300047D01*
G01X300527Y87583D02*
Y84383D01*
G01X294327D02*
Y87583D01*
G01X300527Y84383D02*
X294327D01*
G01X300527Y84083D02*
Y80883D01*
G01X294327Y84083D02*
X300527D01*
G01X294327Y80883D02*
Y84083D01*
G01X300527Y80883D02*
X294327D01*
G01X300917Y73092D02*
X304117D01*
G01X293817Y73113D02*
X300017D01*
G01X306757Y107366D02*
Y104940D01*
G01X300557Y93367D02*
X306757D01*
G01X300557Y90167D02*
Y93367D01*
G01X306757Y90167D02*
X300557D01*
G01X299715Y100399D02*
X302915D01*
G01X299715Y94199D02*
Y100399D01*
G01X302915Y94199D02*
X299715D01*
G01X302915Y100399D02*
Y94199D01*
G01X303715Y100399D02*
X306915D01*
G01X303715Y94199D02*
Y100399D01*
G01X306915Y94199D02*
X303715D01*
G01X294327Y87583D02*
X300527D01*
G01X302820Y108194D02*
X310694D01*
G01X302820Y127412D02*
Y108194D01*
G01X306957Y117053D02*
X305457Y120053D01*
G01X308457Y117053D02*
X305457D01*
G01X290957Y120603D02*
Y114403D01*
G01X306690Y133059D02*
Y130819D01*
G01X308315Y132032D02*
X305065D01*
G01X310694Y127412D02*
X302820D01*
G01X305457Y120053D02*
X308457D01*
G01X292159Y148897D02*
X290206D01*
G01X292159Y150850D02*
Y148897D01*
G01X303500Y148302D02*
X309700D01*
G01X303500Y145102D02*
Y148302D01*
G01X309700Y145102D02*
X303500D01*
G01X294953Y150103D02*
Y153303D01*
G01X301153Y150103D02*
X294953D01*
G01X301153Y153303D02*
Y150103D01*
G01X295300Y140762D02*
Y137562D01*
G01X289979Y171391D02*
Y169169D01*
X290132Y168704D01*
X290439Y168394D01*
X290822Y168291D01*
X291205Y168394D01*
X291512Y168704D01*
X291665Y169169D01*
Y171391D01*
G01X293194Y170874D02*
X293424Y171184D01*
X293692Y171339D01*
X293999Y171391D01*
X294382Y171288D01*
X294650Y171029D01*
X294727Y170719D01*
X294689Y170409D01*
X294535Y170151D01*
X293769Y169634D01*
X293424Y169273D01*
X293194Y168756D01*
X293117Y168291D01*
X294727D01*
G01X296294Y169583D02*
X296562Y169944D01*
X296792Y170151D01*
X297099Y170254D01*
X297367Y170151D01*
X297559Y169944D01*
X297712Y169634D01*
X297750Y169273D01*
X297712Y168963D01*
X297559Y168653D01*
X297329Y168394D01*
X297060Y168291D01*
X296754Y168394D01*
X296485Y168704D01*
X296332Y169169D01*
X296294Y169686D01*
X296370Y170358D01*
X296485Y170719D01*
X296677Y171081D01*
X296945Y171339D01*
X297214Y171391D01*
X297482Y171288D01*
X297674Y171029D01*
G01X299279Y168911D02*
X299509Y168549D01*
X299815Y168343D01*
X300160Y168291D01*
X300467Y168343D01*
X300774Y168601D01*
X300965Y168911D01*
X301004Y169221D01*
X300927Y169583D01*
X300659Y169841D01*
X300390Y169944D01*
X300045D01*
G01X300390D02*
X300620Y170099D01*
X300812Y170358D01*
X300889Y170668D01*
X300812Y170978D01*
X300620Y171236D01*
X300275Y171391D01*
X299930Y171339D01*
X299585Y171133D01*
G01X292159Y160709D02*
Y158756D01*
G01X290206Y160709D02*
X292159D01*
G01X294953Y153303D02*
X301153D01*
G01X294953Y154603D02*
Y157803D01*
G01X301153Y154603D02*
X294953D01*
G01X301153Y157803D02*
Y154603D01*
G01X294953Y157803D02*
X301153D01*
G01X295800Y213812D02*
Y207812D01*
G01X300668Y215125D02*
Y218225D01*
X301588D01*
X301895Y218070D01*
X302125Y217708D01*
X302202Y217295D01*
X302125Y216882D01*
X301933Y216572D01*
X301588Y216417D01*
X300668D01*
G01X303692Y218225D02*
Y216003D01*
X303845Y215538D01*
X304152Y215228D01*
X304535Y215125D01*
X304918Y215228D01*
X305225Y215538D01*
X305378Y216003D01*
Y218225D01*
G01X306907Y217708D02*
X307137Y218018D01*
X307405Y218173D01*
X307712Y218225D01*
X308095Y218122D01*
X308363Y217863D01*
X308440Y217553D01*
X308402Y217243D01*
X308248Y216985D01*
X307482Y216468D01*
X307137Y216107D01*
X306907Y215590D01*
X306830Y215125D01*
X308440D01*
G01X310735Y218225D02*
X310428Y218122D01*
X310198Y217863D01*
X310045Y217553D01*
X309930Y217140D01*
X309892Y216675D01*
X309930Y216210D01*
X310045Y215797D01*
X310198Y215487D01*
X310428Y215228D01*
X310735Y215125D01*
X311042Y215228D01*
X311272Y215487D01*
X311425Y215797D01*
X311540Y216210D01*
X311578Y216675D01*
X311540Y217140D01*
X311425Y217553D01*
X311272Y217863D01*
X311042Y218122D01*
X310735Y218225D01*
G01X313835D02*
X313528Y218122D01*
X313298Y217863D01*
X313145Y217553D01*
X313030Y217140D01*
X312992Y216675D01*
X313030Y216210D01*
X313145Y215797D01*
X313298Y215487D01*
X313528Y215228D01*
X313835Y215125D01*
X314142Y215228D01*
X314372Y215487D01*
X314525Y215797D01*
X314640Y216210D01*
X314678Y216675D01*
X314640Y217140D01*
X314525Y217553D01*
X314372Y217863D01*
X314142Y218122D01*
X313835Y218225D01*
G01X290159Y259331D02*
X293359D01*
G01X290159Y253131D02*
Y259331D01*
G01X293359Y253131D02*
X290159D01*
G01X293359Y259331D02*
Y253131D01*
G01X303051Y259331D02*
X306251D01*
G01X303051Y253131D02*
Y259331D01*
G01X306251Y253131D02*
X303051D01*
G01X294680Y267672D02*
X440900D01*
G01X290054Y276785D02*
Y280535D01*
G01X297194Y276785D02*
X290054D01*
G01X297194Y280585D02*
Y276785D01*
G01X290104Y280585D02*
X297194D01*
G01X297694Y276785D02*
X290504D01*
G01X297694Y280585D02*
Y276785D01*
G01X290504Y280585D02*
X297694D01*
G01X298194Y276785D02*
X291104D01*
G01X298194Y280585D02*
Y276785D01*
G01X291104Y280585D02*
X298194D01*
G01X302654Y276785D02*
Y280535D01*
G01X309794Y276785D02*
X302654D01*
G01X302704Y280585D02*
X309794D01*
G01X310294Y276785D02*
X303104D01*
G01Y280585D02*
X310294D01*
G01X310794Y276785D02*
X303704D01*
G01Y280585D02*
X310794D01*
G01X290874Y297988D02*
Y291788D01*
G01X305136Y297988D02*
X308336D01*
G01X305136Y291788D02*
Y297988D01*
G01X308336Y291788D02*
X305136D01*
G01X296584Y297988D02*
X299784D01*
G01X296584Y291788D02*
Y297988D01*
G01X299784Y291788D02*
X296584D01*
G01X299784Y297988D02*
Y291788D01*
G01X301165Y297988D02*
X304365D01*
G01X301165Y291788D02*
Y297988D01*
G01X304365Y291788D02*
X301165D01*
G01X304365Y297988D02*
Y291788D01*
G01X292163Y297988D02*
X295363D01*
G01X292163Y291788D02*
Y297988D01*
G01X295363Y291788D02*
X292163D01*
G01X295363Y297988D02*
Y291788D01*
G01X296464Y313234D02*
Y309434D01*
G01X296964D02*
X289774D01*
G01X296964Y313234D02*
Y309434D01*
G01X289774Y313234D02*
X296964D01*
G01X297464Y309434D02*
X290374D01*
G01X297464Y313234D02*
Y309434D01*
G01X290374Y313234D02*
X297464D01*
G01X301924Y309434D02*
Y313184D01*
G01X309064Y309434D02*
X301924D01*
G01X301974Y313234D02*
X309064D01*
G01X309564Y309434D02*
X302374D01*
G01Y313234D02*
X309564D01*
G01X310064Y309434D02*
X302974D01*
G01Y313234D02*
X310064D01*
G01X301084Y558267D02*
Y564467D01*
G01X304284Y558267D02*
X301084D01*
G01X304284Y564467D02*
Y558267D01*
G01X308556D02*
X305356D01*
G01D02*
Y564467D01*
G01X301084D02*
X304284D01*
G01X305356D02*
X308556D01*
G01X291620Y571148D02*
Y567948D01*
G01Y567622D02*
Y564422D01*
G01X304619Y600918D02*
X310819D01*
G01X304619Y597718D02*
Y600918D01*
G01X310819Y597718D02*
X304619D01*
G01Y593718D02*
Y596918D01*
G01X310819Y593718D02*
X304619D01*
G01Y596918D02*
X310819D01*
G01X304343Y620466D02*
Y627896D01*
G01X293720Y639409D02*
Y636209D01*
G01X294220Y635883D02*
Y632683D01*
G01Y632357D02*
Y629157D01*
G01X292494Y686671D02*
Y683471D01*
G01Y690197D02*
Y686997D01*
G01X316722Y991220D02*
G03I-9950J0D01*
G01X302878Y1291806D02*
Y1335114D01*
G01X308219Y1291806D02*
X302878D01*
G01Y1335114D02*
X308219D01*
G01X301951Y1352416D02*
X305151D01*
G01X301951Y1346216D02*
Y1352416D01*
G01X305151Y1346216D02*
X301951D01*
G01X305151Y1352416D02*
Y1346216D01*
G01X305419Y1371137D02*
X308619D01*
G01X305419Y1364937D02*
Y1371137D01*
G01X308619Y1364937D02*
X305419D01*
G01X305173Y1356753D02*
X301973D01*
G01X305173Y1362953D02*
Y1356753D01*
G01X301973Y1362953D02*
X305173D01*
G01X301973Y1356753D02*
Y1362953D01*
G01X292520Y1769645D02*
Y1629488D01*
G01X304331Y1617677D02*
Y1668870D01*
G01X305938Y1642259D02*
X306130Y1641949D01*
X306360Y1641742D01*
X306628Y1641639D01*
X306935Y1641742D01*
X307165Y1641949D01*
X307395Y1642259D01*
X307472Y1642672D01*
Y1644739D01*
G01X309805Y1641639D02*
Y1644739D01*
X309345Y1644119D01*
G01Y1641639D02*
X310265D01*
G01X312905D02*
Y1644739D01*
X312445Y1644119D01*
G01Y1641639D02*
X313365D01*
G01X316005D02*
Y1644739D01*
X315545Y1644119D01*
G01Y1641639D02*
X316465D01*
G01X304774Y1656065D02*
X305004Y1656375D01*
X305272Y1656530D01*
X305579Y1656582D01*
X305962Y1656479D01*
X306230Y1656220D01*
X306307Y1655910D01*
X306269Y1655600D01*
X306115Y1655342D01*
X305349Y1654825D01*
X305004Y1654464D01*
X304774Y1653947D01*
X304697Y1653482D01*
X306307D01*
G01X297628D02*
Y1656582D01*
X297168Y1655962D01*
G01Y1653482D02*
X298088D01*
G01X292914Y1657834D02*
X359449D01*
G01X292914Y1769645D02*
Y1657834D01*
G01X289842Y1698961D02*
Y1702061D01*
G01X291452D02*
Y1698961D01*
G01Y1700511D02*
X289842D01*
G01X290877Y1705236D02*
X291644D01*
Y1704306D01*
X291414Y1703996D01*
X291145Y1703789D01*
X290762Y1703686D01*
X290379Y1703789D01*
X290110Y1703996D01*
X289880Y1704306D01*
X289727Y1704668D01*
X289650Y1705081D01*
Y1705443D01*
X289727Y1705753D01*
X289880Y1706114D01*
X290110Y1706424D01*
X290340Y1706631D01*
X290647Y1706786D01*
X290915D01*
X291222Y1706683D01*
X291452Y1706476D01*
G01X289919Y1708410D02*
Y1711510D01*
X291375D01*
G01X290839Y1710012D02*
X289919D01*
G01X291414Y1713134D02*
X289880D01*
Y1716234D01*
X291414D01*
G01X290800Y1714736D02*
X289880D01*
G01X291413Y1725444D02*
X291183Y1725599D01*
X290915Y1725702D01*
X290608D01*
X290263Y1725547D01*
X289995Y1725289D01*
X289803Y1724979D01*
X289650Y1724462D01*
X289612Y1723997D01*
X289688Y1723532D01*
X289803Y1723222D01*
X290033Y1722912D01*
X290302Y1722705D01*
X290570Y1722602D01*
X290838D01*
X291107Y1722705D01*
X291337Y1722860D01*
X291528Y1723067D01*
G01X290957Y1729155D02*
X291110Y1729310D01*
X291225Y1729569D01*
X291302Y1729930D01*
X291225Y1730240D01*
X291072Y1730447D01*
X290803Y1730602D01*
X289768D01*
Y1727502D01*
X291033D01*
X291302Y1727709D01*
X291455Y1728019D01*
X291532Y1728380D01*
X291455Y1728742D01*
X291225Y1729052D01*
X290957Y1729155D01*
X289768D01*
G01X289804Y1717859D02*
Y1720959D01*
X290570D01*
X290877Y1720804D01*
X291107Y1720597D01*
X291299Y1720287D01*
X291452Y1719926D01*
X291490Y1719409D01*
X291452Y1718892D01*
X291299Y1718531D01*
X291107Y1718221D01*
X290877Y1718014D01*
X290570Y1717859D01*
X289804D01*
G01X304331Y1738240D02*
Y1781456D01*
G01X304935Y1736412D02*
X305835Y1737312D01*
G01X299935Y1736412D02*
X304935D01*
G01X299935Y1739812D02*
Y1736412D01*
G01X301935Y1737812D02*
X299935Y1739812D01*
G01X297935Y1737812D02*
X301935D01*
G01X299935Y1739812D02*
X297935Y1737812D01*
G01X292914Y1740118D02*
X359449D01*
G01Y1769645D02*
X292914D01*
G01X319772Y43779D02*
X308622D01*
G01X320942Y68263D02*
Y71463D01*
G01X327142Y68263D02*
X320942D01*
G01X319415Y77379D02*
Y85567D01*
G01X320942Y71463D02*
X327142D01*
G01X315457Y90203D02*
Y93403D01*
G01X321657Y90203D02*
X315457D01*
G01X321657Y93403D02*
Y90203D01*
G01X315457Y93403D02*
X321657D01*
G01Y97403D02*
Y94203D01*
G01X315457Y97403D02*
X321657D01*
G01X315457Y94203D02*
Y97403D01*
G01X321657Y94203D02*
X315457D01*
G01X306757Y93367D02*
Y90167D01*
G01X321703Y101437D02*
Y98237D01*
G01X315503Y101437D02*
X321703D01*
G01X315503Y98237D02*
Y101437D01*
G01X321703Y98237D02*
X315503D01*
G01X306915Y100399D02*
Y94199D01*
G01X315013Y116052D02*
Y119152D01*
X315933D01*
X316240Y118997D01*
X316470Y118635D01*
X316547Y118222D01*
X316470Y117809D01*
X316278Y117499D01*
X315933Y117344D01*
X315013D01*
G01X318037Y116052D02*
Y119152D01*
X318803D01*
X319110Y118997D01*
X319340Y118790D01*
X319532Y118480D01*
X319685Y118119D01*
X319723Y117602D01*
X319685Y117085D01*
X319532Y116724D01*
X319340Y116414D01*
X319110Y116207D01*
X318803Y116052D01*
X318037D01*
G01X321980D02*
Y119152D01*
X321520Y118532D01*
G01Y116052D02*
X322440D01*
G01X325080Y119152D02*
X324773Y119049D01*
X324543Y118790D01*
X324390Y118480D01*
X324275Y118067D01*
X324237Y117602D01*
X324275Y117137D01*
X324390Y116724D01*
X324543Y116414D01*
X324773Y116155D01*
X325080Y116052D01*
X325387Y116155D01*
X325617Y116414D01*
X325770Y116724D01*
X325885Y117137D01*
X325923Y117602D01*
X325885Y118067D01*
X325770Y118480D01*
X325617Y118790D01*
X325387Y119049D01*
X325080Y119152D01*
G01X328103Y116052D02*
X328180Y116724D01*
X328295Y117292D01*
X328448Y117809D01*
X328640Y118377D01*
X328947Y119152D01*
X327413D01*
G01X310694Y108194D02*
Y127412D01*
G01X306957Y117053D02*
Y116053D01*
G01X308457Y120053D02*
X306957Y117053D01*
G01Y120053D02*
Y121153D01*
G01X311772Y145413D02*
Y143191D01*
X311925Y142726D01*
X312232Y142416D01*
X312615Y142313D01*
X312998Y142416D01*
X313305Y142726D01*
X313458Y143191D01*
Y145413D01*
G01X314987Y144896D02*
X315217Y145206D01*
X315485Y145361D01*
X315792Y145413D01*
X316175Y145310D01*
X316443Y145051D01*
X316520Y144741D01*
X316482Y144431D01*
X316328Y144173D01*
X315562Y143656D01*
X315217Y143295D01*
X314987Y142778D01*
X314910Y142313D01*
X316520D01*
G01X318815D02*
Y145413D01*
X318355Y144793D01*
G01Y142313D02*
X319275D01*
G01X321187Y143605D02*
X321455Y143966D01*
X321685Y144173D01*
X321992Y144276D01*
X322260Y144173D01*
X322452Y143966D01*
X322605Y143656D01*
X322643Y143295D01*
X322605Y142985D01*
X322452Y142675D01*
X322222Y142416D01*
X321953Y142313D01*
X321647Y142416D01*
X321378Y142726D01*
X321225Y143191D01*
X321187Y143708D01*
X321263Y144380D01*
X321378Y144741D01*
X321570Y145103D01*
X321838Y145361D01*
X322107Y145413D01*
X322375Y145310D01*
X322567Y145051D01*
G01X309877Y146432D02*
Y158244D01*
G01X323733Y146432D02*
X309877D01*
G01X309700Y148302D02*
Y145102D01*
G01X309877Y158244D02*
X323733D01*
G01X325500Y159962D02*
X319300D01*
Y163162D01*
X325500D01*
Y159962D01*
G01X320555Y230619D02*
Y236819D01*
G01X323755Y230619D02*
X320555D01*
G01X316395Y230649D02*
Y236849D01*
G01X319595Y230649D02*
X316395D01*
G01X319595Y236849D02*
Y230649D01*
G01X315595D02*
X312395D01*
G01X315595Y236849D02*
Y230649D01*
G01X312395D02*
Y236849D01*
G01X319574Y229858D02*
Y226658D01*
G01X313374Y229858D02*
X319574D01*
G01X313374Y226658D02*
Y229858D01*
G01X319574Y226658D02*
X313374D01*
G01X317660Y244064D02*
Y247164D01*
X318580D01*
X318887Y247009D01*
X319117Y246647D01*
X319194Y246234D01*
X319117Y245821D01*
X318925Y245511D01*
X318580Y245356D01*
X317660D01*
G01X320684Y244064D02*
Y247164D01*
X321450D01*
X321757Y247009D01*
X321987Y246802D01*
X322179Y246492D01*
X322332Y246131D01*
X322370Y245614D01*
X322332Y245097D01*
X322179Y244736D01*
X321987Y244426D01*
X321757Y244219D01*
X321450Y244064D01*
X320684D01*
G01X324627D02*
Y247164D01*
X324167Y246544D01*
G01Y244064D02*
X325087D01*
G01X327727Y247164D02*
X327420Y247061D01*
X327190Y246802D01*
X327037Y246492D01*
X326922Y246079D01*
X326884Y245614D01*
X326922Y245149D01*
X327037Y244736D01*
X327190Y244426D01*
X327420Y244167D01*
X327727Y244064D01*
X328034Y244167D01*
X328264Y244426D01*
X328417Y244736D01*
X328532Y245149D01*
X328570Y245614D01*
X328532Y246079D01*
X328417Y246492D01*
X328264Y246802D01*
X328034Y247061D01*
X327727Y247164D01*
G01X330175Y244426D02*
X330444Y244167D01*
X330750Y244064D01*
X331057Y244167D01*
X331325Y244477D01*
X331517Y244942D01*
X331594Y245407D01*
Y245976D01*
X331517Y246441D01*
X331325Y246854D01*
X331095Y247061D01*
X330827Y247164D01*
X330520Y247061D01*
X330290Y246854D01*
X330137Y246544D01*
X330060Y246131D01*
X330137Y245769D01*
X330329Y245407D01*
X330559Y245201D01*
X330827Y245149D01*
X331134Y245252D01*
X331364Y245511D01*
X331594Y245976D01*
G01X313390Y243337D02*
X310964D01*
G01X309850Y249385D02*
Y237889D01*
G01X320555Y236819D02*
X323755D01*
G01X316395Y236849D02*
X319595D01*
G01X312395D02*
X315595D01*
G01X306251Y259331D02*
Y253131D01*
G01X315529Y259331D02*
X318729D01*
G01X315529Y253131D02*
Y259331D01*
G01X318729Y253131D02*
X315529D01*
G01X318729Y259331D02*
Y253131D01*
G01X315254Y276785D02*
Y280535D01*
G01X322394Y276785D02*
X315254D01*
G01X315304Y280585D02*
X322394D01*
G01X322894Y276785D02*
X315704D01*
G01Y280585D02*
X322894D01*
G01X323394Y276785D02*
X316304D01*
G01Y280585D02*
X323394D01*
G01X309794D02*
Y276785D01*
G01X310294Y280585D02*
Y276785D01*
G01X310794Y280585D02*
Y276785D01*
G01X308336Y297988D02*
Y291788D01*
G01X314863Y297988D02*
X318063D01*
G01X314863Y291788D02*
Y297988D01*
G01X318063Y291788D02*
X314863D01*
G01X318063Y297988D02*
Y291788D01*
G01X314524Y309434D02*
Y313184D01*
G01X321664Y309434D02*
X314524D01*
G01X321664Y313234D02*
Y309434D01*
G01X314574Y313234D02*
X321664D01*
G01X322164Y309434D02*
X314974D01*
G01Y313234D02*
X322164D01*
G01X322664Y309434D02*
X315574D01*
G01Y313234D02*
X322664D01*
G01X309064D02*
Y309434D01*
G01X309564Y313234D02*
Y309434D01*
G01X310064Y313234D02*
Y309434D01*
G01X317684Y379040D02*
X317377Y379092D01*
X317109Y379298D01*
X316879Y379608D01*
X316726Y379970D01*
X316649Y380383D01*
Y380797D01*
X316726Y381210D01*
X316879Y381572D01*
X317109Y381882D01*
X317377Y382088D01*
X317684Y382140D01*
X317991Y382088D01*
X318259Y381882D01*
X318489Y381572D01*
X318642Y381210D01*
X318719Y380797D01*
Y380383D01*
X318642Y379970D01*
X318489Y379608D01*
X318259Y379298D01*
X317991Y379092D01*
X317684Y379040D01*
G01X317991Y379867D02*
X318451Y379040D01*
G01X320784D02*
X321052Y379092D01*
X321359Y379247D01*
X321551Y379505D01*
X321627Y379867D01*
X321551Y380228D01*
X321321Y380538D01*
X320976Y380693D01*
X320592D01*
X320362Y380797D01*
X320171Y381055D01*
X320094Y381417D01*
X320209Y381778D01*
X320477Y382037D01*
X320784Y382140D01*
X321091Y382037D01*
X321359Y381778D01*
X321474Y381417D01*
X321397Y381055D01*
X321206Y380797D01*
X320976Y380693D01*
X320592D01*
X320247Y380538D01*
X320017Y380228D01*
X319941Y379867D01*
X320017Y379505D01*
X320209Y379247D01*
X320516Y379092D01*
X320784Y379040D01*
G01X323041Y379505D02*
X323271Y379247D01*
X323539Y379092D01*
X323884Y379040D01*
X324229Y379143D01*
X324497Y379350D01*
X324689Y379712D01*
X324727Y380125D01*
X324651Y380538D01*
X324459Y380797D01*
X324191Y381003D01*
X323922Y381055D01*
X323654Y381003D01*
X323309Y380797D01*
X323424Y382140D01*
X324459D01*
G01X319804Y366809D02*
X319497Y366861D01*
X319229Y367067D01*
X318999Y367377D01*
X318846Y367739D01*
X318769Y368152D01*
Y368566D01*
X318846Y368979D01*
X318999Y369341D01*
X319229Y369651D01*
X319497Y369857D01*
X319804Y369909D01*
X320111Y369857D01*
X320379Y369651D01*
X320609Y369341D01*
X320762Y368979D01*
X320839Y368566D01*
Y368152D01*
X320762Y367739D01*
X320609Y367377D01*
X320379Y367067D01*
X320111Y366861D01*
X319804Y366809D01*
G01X320111Y367636D02*
X320571Y366809D01*
G01X322904D02*
X323172Y366861D01*
X323479Y367016D01*
X323671Y367274D01*
X323747Y367636D01*
X323671Y367997D01*
X323441Y368307D01*
X323096Y368462D01*
X322712D01*
X322482Y368566D01*
X322291Y368824D01*
X322214Y369186D01*
X322329Y369547D01*
X322597Y369806D01*
X322904Y369909D01*
X323211Y369806D01*
X323479Y369547D01*
X323594Y369186D01*
X323517Y368824D01*
X323326Y368566D01*
X323096Y368462D01*
X322712D01*
X322367Y368307D01*
X322137Y367997D01*
X322061Y367636D01*
X322137Y367274D01*
X322329Y367016D01*
X322636Y366861D01*
X322904Y366809D01*
G01X326004Y369909D02*
X325697Y369806D01*
X325467Y369547D01*
X325314Y369237D01*
X325199Y368824D01*
X325161Y368359D01*
X325199Y367894D01*
X325314Y367481D01*
X325467Y367171D01*
X325697Y366912D01*
X326004Y366809D01*
X326311Y366912D01*
X326541Y367171D01*
X326694Y367481D01*
X326809Y367894D01*
X326847Y368359D01*
X326809Y368824D01*
X326694Y369237D01*
X326541Y369547D01*
X326311Y369806D01*
X326004Y369909D01*
G01X319759Y403860D02*
X319452Y403912D01*
X319184Y404118D01*
X318954Y404428D01*
X318801Y404790D01*
X318724Y405203D01*
Y405617D01*
X318801Y406030D01*
X318954Y406392D01*
X319184Y406702D01*
X319452Y406908D01*
X319759Y406960D01*
X320066Y406908D01*
X320334Y406702D01*
X320564Y406392D01*
X320717Y406030D01*
X320794Y405617D01*
Y405203D01*
X320717Y404790D01*
X320564Y404428D01*
X320334Y404118D01*
X320066Y403912D01*
X319759Y403860D01*
G01X320066Y404687D02*
X320526Y403860D01*
G01X322859D02*
Y406960D01*
X322399Y406340D01*
G01Y403860D02*
X323319D01*
G01X325959Y406960D02*
X325652Y406857D01*
X325422Y406598D01*
X325269Y406288D01*
X325154Y405875D01*
X325116Y405410D01*
X325154Y404945D01*
X325269Y404532D01*
X325422Y404222D01*
X325652Y403963D01*
X325959Y403860D01*
X326266Y403963D01*
X326496Y404222D01*
X326649Y404532D01*
X326764Y404945D01*
X326802Y405410D01*
X326764Y405875D01*
X326649Y406288D01*
X326496Y406598D01*
X326266Y406857D01*
X325959Y406960D01*
G01X329059D02*
X328752Y406857D01*
X328522Y406598D01*
X328369Y406288D01*
X328254Y405875D01*
X328216Y405410D01*
X328254Y404945D01*
X328369Y404532D01*
X328522Y404222D01*
X328752Y403963D01*
X329059Y403860D01*
X329366Y403963D01*
X329596Y404222D01*
X329749Y404532D01*
X329864Y404945D01*
X329902Y405410D01*
X329864Y405875D01*
X329749Y406288D01*
X329596Y406598D01*
X329366Y406857D01*
X329059Y406960D01*
G01X324909Y557618D02*
X318709D01*
G01D02*
Y560818D01*
G01X308556Y564467D02*
Y558267D01*
G01X320547Y591211D02*
Y571605D01*
G01D02*
X306947D01*
G01D02*
Y591211D01*
G01X318709Y560818D02*
X324909D01*
G01X318705Y564776D02*
X324905D01*
G01Y561576D02*
X318705D01*
G01D02*
Y564776D01*
G01X316814Y591211D02*
X320547D01*
G01X306947D02*
X310680D01*
G01D02*
X313747Y588144D01*
G01D02*
X316814Y591211D01*
G01X310819Y600918D02*
Y597718D01*
G01Y596918D02*
Y593718D01*
G01X313115Y598326D02*
Y601526D01*
G01X319315Y598326D02*
X313115D01*
G01X319315Y601526D02*
Y598326D01*
G01X313115Y601526D02*
X319315D01*
G01X319325Y597598D02*
Y594398D01*
G01X313125Y597598D02*
X319325D01*
G01X313125Y594398D02*
Y597598D01*
G01X319325Y594398D02*
X313125D01*
G01X320592Y835708D02*
Y850235D01*
G01X320591Y835708D02*
Y850236D01*
G01X326497Y829802D02*
X320592Y835708D01*
G01X326497Y829803D02*
X320591Y835708D01*
G01X562697Y853424D02*
G03X560749Y851512I18J-1967D01*
G01Y829803D01*
X326496D01*
X320591Y835708D01*
Y851475D01*
G01D02*
G03X318622Y853424I-1968J-19D01*
G01X313701D01*
Y861299D01*
G01X320592Y851456D02*
G03X318623Y853424I-1969J-1D01*
G01X320592Y850235D02*
Y851456D01*
G01X320591D02*
G03X318622Y853425I-1969J0D01*
G01X320591Y850236D02*
Y851456D01*
G01Y861299D02*
Y1136896D01*
G01X313702Y853424D02*
X318623D01*
G01X313701Y853425D02*
X318622D01*
G01X313702Y861298D02*
Y853424D01*
G01X313701Y869960D02*
Y853425D01*
G01X324529Y861298D02*
X320591Y861299D01*
G01Y869960D02*
X313701D01*
G01X320592Y1116456D02*
Y1110157D01*
G01X320591Y1116456D02*
Y1110157D01*
G01X320592D02*
X324529D01*
G01X320591D02*
X324528D01*
G01X328662D02*
X320592D01*
G01X328662D02*
X320591D01*
G01X324529Y1116456D02*
X320592D01*
G01X324528D02*
X320591D01*
G01X313701Y1139645D02*
Y1145944D01*
G01Y1138857D02*
Y1139645D01*
G01X313702D02*
Y1145944D01*
G01X318623Y1138857D02*
X313702D01*
G01D02*
Y1139645D01*
G01X318622Y1138857D02*
X313701D01*
G01X320591Y1136896D02*
G03X318622Y1138857I-1968J-7D01*
G01X313701D01*
Y1146731D01*
X318639D01*
G01X320592Y1136889D02*
G03X318623Y1138857I-1969J-1D01*
G01X320591Y1136890D02*
G03X318622Y1138857I-1968J-1D01*
G01X320592Y1136889D02*
Y1132204D01*
G01X320591Y1136890D02*
Y1132205D01*
G01X320592Y1132204D02*
X324529D01*
G01X320591Y1132205D02*
X324528D01*
G01X318623Y1146731D02*
G03X320592Y1148700I0J1969D01*
G01X313702Y1146731D02*
X318623D01*
G01X313701Y1145944D02*
Y1146731D01*
G01X313702Y1145944D02*
Y1146731D01*
G01X318622D02*
G03X320591Y1148701I0J1969D01*
G01X320592Y1152637D02*
Y1148700D01*
G01X320591Y1152638D02*
Y1148701D01*
G01X313701Y1146731D02*
X318622D01*
G01X391458Y1152637D02*
X320592D01*
G01X391458Y1152638D02*
X320591D01*
G01X318639Y1146731D02*
G03X320591Y1148694I-17J1969D01*
G01Y1152637D01*
X560749D01*
Y1148692D01*
G01X308511Y1284914D02*
Y1288014D01*
X309431D01*
X309738Y1287859D01*
X309968Y1287497D01*
X310045Y1287084D01*
X309968Y1286671D01*
X309776Y1286361D01*
X309431Y1286206D01*
X308511D01*
G01X311611Y1288014D02*
Y1284914D01*
X313145D01*
G01X314750Y1287497D02*
X314980Y1287807D01*
X315248Y1287962D01*
X315555Y1288014D01*
X315938Y1287911D01*
X316206Y1287652D01*
X316283Y1287342D01*
X316245Y1287032D01*
X316091Y1286774D01*
X315325Y1286257D01*
X314980Y1285896D01*
X314750Y1285379D01*
X314673Y1284914D01*
X316283D01*
G01X317735Y1285379D02*
X317965Y1285121D01*
X318233Y1284966D01*
X318578Y1284914D01*
X318923Y1285017D01*
X319191Y1285224D01*
X319383Y1285586D01*
X319421Y1285999D01*
X319345Y1286412D01*
X319153Y1286671D01*
X318885Y1286877D01*
X318616Y1286929D01*
X318348Y1286877D01*
X318003Y1286671D01*
X318118Y1288014D01*
X319153D01*
G01X308575Y1338256D02*
X307782D01*
Y1340856D01*
G01Y1347467D02*
Y1349165D01*
G01Y1360024D02*
Y1361878D01*
X308790D01*
G01X308619Y1371137D02*
Y1364937D01*
G01X322214Y1365091D02*
X319014D01*
G01Y1371291D02*
X322214D01*
G01X319014Y1365091D02*
Y1371291D01*
G01X310546Y1368207D02*
Y1371407D01*
G01X316746Y1368207D02*
X310546D01*
G01X316746Y1371407D02*
Y1368207D01*
G01X310546Y1371407D02*
X316746D01*
G01X308735Y1410237D02*
Y1413337D01*
G01X310345D02*
Y1410237D01*
G01Y1411787D02*
X308735D01*
G01X313100Y1410237D02*
Y1413337D01*
X311682Y1411115D01*
X313598D01*
G01X315663Y1410237D02*
X315740Y1410909D01*
X315855Y1411477D01*
X316008Y1411994D01*
X316200Y1412562D01*
X316507Y1413337D01*
X314973D01*
G01X313765Y1623535D02*
X314685Y1622752D01*
X315720Y1622282D01*
X316640D01*
X317560Y1622752D01*
X318250Y1623535D01*
X318595Y1624632D01*
X318365Y1625729D01*
X317790Y1626669D01*
X316755Y1627295D01*
X315375Y1627609D01*
X314570Y1628235D01*
X314225Y1629332D01*
X314455Y1630429D01*
X315030Y1631212D01*
X315835Y1631682D01*
X316640D01*
X317445Y1631369D01*
X318135Y1630585D01*
G01X321930Y1631682D02*
X323540Y1622282D01*
X325380Y1631682D01*
X327220Y1622282D01*
X328830Y1631682D01*
G01X335500Y1627295D02*
X335960Y1627765D01*
X336305Y1628548D01*
X336535Y1629645D01*
X336305Y1630585D01*
X335845Y1631212D01*
X335040Y1631682D01*
X331935D01*
Y1622282D01*
X335730D01*
X336535Y1622909D01*
X336995Y1623849D01*
X337225Y1624945D01*
X336995Y1626042D01*
X336305Y1626982D01*
X335500Y1627295D01*
X331935D01*
G01X340330Y1619149D02*
X347230D01*
G01X353670Y1626982D02*
X355970D01*
Y1624162D01*
X355280Y1623222D01*
X354475Y1622595D01*
X353325Y1622282D01*
X352175Y1622595D01*
X351370Y1623222D01*
X350680Y1624162D01*
X350220Y1625259D01*
X349990Y1626512D01*
Y1627609D01*
X350220Y1628548D01*
X350680Y1629645D01*
X351370Y1630585D01*
X352060Y1631212D01*
X352980Y1631682D01*
X353785D01*
X354705Y1631369D01*
X355395Y1630742D01*
G01X321710Y1653482D02*
Y1656582D01*
X320292Y1654360D01*
X322208D01*
G01X312533Y1654102D02*
X312763Y1653740D01*
X313069Y1653534D01*
X313414Y1653482D01*
X313721Y1653534D01*
X314028Y1653792D01*
X314219Y1654102D01*
X314258Y1654412D01*
X314181Y1654774D01*
X313913Y1655032D01*
X313644Y1655135D01*
X313299D01*
G01X313644D02*
X313874Y1655290D01*
X314066Y1655549D01*
X314143Y1655859D01*
X314066Y1656169D01*
X313874Y1656427D01*
X313529Y1656582D01*
X313184Y1656530D01*
X312839Y1656324D01*
G01X308018Y1736629D02*
X306952D01*
Y1739129D01*
X308018D01*
G01X307592Y1737921D02*
X306952D01*
G01X309098Y1736629D02*
Y1739129D01*
X309632D01*
X309845Y1739004D01*
X310005Y1738837D01*
X310138Y1738587D01*
X310245Y1738296D01*
X310272Y1737879D01*
X310245Y1737462D01*
X310138Y1737171D01*
X310005Y1736921D01*
X309845Y1736754D01*
X309632Y1736629D01*
X309098D01*
G01X312045Y1737879D02*
X312578D01*
Y1737129D01*
X312418Y1736879D01*
X312232Y1736712D01*
X311965Y1736629D01*
X311698Y1736712D01*
X311512Y1736879D01*
X311352Y1737129D01*
X311245Y1737421D01*
X311192Y1737754D01*
Y1738046D01*
X311245Y1738296D01*
X311352Y1738587D01*
X311512Y1738837D01*
X311672Y1739004D01*
X311885Y1739129D01*
X312072D01*
X312285Y1739046D01*
X312445Y1738879D01*
G01X314618Y1736629D02*
X313552D01*
Y1739129D01*
X314618D01*
G01X314192Y1737921D02*
X313552D01*
G01X318485Y1736629D02*
X318272Y1736671D01*
X318085Y1736837D01*
X317925Y1737087D01*
X317818Y1737379D01*
X317765Y1737712D01*
Y1738046D01*
X317818Y1738379D01*
X317925Y1738671D01*
X318085Y1738921D01*
X318272Y1739087D01*
X318485Y1739129D01*
X318698Y1739087D01*
X318885Y1738921D01*
X319045Y1738671D01*
X319152Y1738379D01*
X319205Y1738046D01*
Y1737712D01*
X319152Y1737379D01*
X319045Y1737087D01*
X318885Y1736837D01*
X318698Y1736671D01*
X318485Y1736629D01*
G01X320178D02*
Y1739129D01*
X321192D01*
G01X320818Y1737921D02*
X320178D01*
G01X324498Y1736629D02*
Y1739129D01*
X325032D01*
X325245Y1739004D01*
X325405Y1738837D01*
X325538Y1738587D01*
X325645Y1738296D01*
X325672Y1737879D01*
X325645Y1737462D01*
X325538Y1737171D01*
X325405Y1736921D01*
X325245Y1736754D01*
X325032Y1736629D01*
X324498D01*
G01X326618D02*
X327285Y1739129D01*
X327952Y1736629D01*
G01X327712Y1737504D02*
X326858D01*
G01X328898Y1739129D02*
Y1737337D01*
X329005Y1736962D01*
X329218Y1736712D01*
X329485Y1736629D01*
X329752Y1736712D01*
X329965Y1736962D01*
X330072Y1737337D01*
Y1739129D01*
G01X331845Y1737879D02*
X332378D01*
Y1737129D01*
X332218Y1736879D01*
X332032Y1736712D01*
X331765Y1736629D01*
X331498Y1736712D01*
X331312Y1736879D01*
X331152Y1737129D01*
X331045Y1737421D01*
X330992Y1737754D01*
Y1738046D01*
X331045Y1738296D01*
X331152Y1738587D01*
X331312Y1738837D01*
X331472Y1739004D01*
X331685Y1739129D01*
X331872D01*
X332085Y1739046D01*
X332245Y1738879D01*
G01X333325Y1736629D02*
Y1739129D01*
G01X334445D02*
Y1736629D01*
G01Y1737879D02*
X333325D01*
G01X336085Y1739129D02*
Y1736629D01*
G01X335472Y1739129D02*
X336698D01*
G01X338818Y1736629D02*
X337752D01*
Y1739129D01*
X338818D01*
G01X338392Y1737921D02*
X337752D01*
G01X339952Y1736629D02*
Y1739129D01*
X340618D01*
X340832Y1739004D01*
X340965Y1738837D01*
X341018Y1738504D01*
X340965Y1738171D01*
X340805Y1737962D01*
X340618Y1737837D01*
X339952D01*
G01X340618D02*
X341018Y1736629D01*
G01X345472Y1738921D02*
X345312Y1739046D01*
X345125Y1739129D01*
X344912D01*
X344672Y1739004D01*
X344485Y1738796D01*
X344352Y1738546D01*
X344245Y1738129D01*
X344218Y1737754D01*
X344272Y1737379D01*
X344352Y1737129D01*
X344512Y1736879D01*
X344698Y1736712D01*
X344885Y1736629D01*
X345072D01*
X345258Y1736712D01*
X345418Y1736837D01*
X345552Y1737004D01*
G01X346418Y1736629D02*
X347085Y1739129D01*
X347752Y1736629D01*
G01X347512Y1737504D02*
X346658D01*
G01X348752Y1736629D02*
Y1739129D01*
X349418D01*
X349632Y1739004D01*
X349765Y1738837D01*
X349818Y1738504D01*
X349765Y1738171D01*
X349605Y1737962D01*
X349418Y1737837D01*
X348752D01*
G01X349418D02*
X349818Y1736629D01*
G01X350898D02*
Y1739129D01*
X351432D01*
X351645Y1739004D01*
X351805Y1738837D01*
X351938Y1738587D01*
X352045Y1738296D01*
X352072Y1737879D01*
X352045Y1737462D01*
X351938Y1737171D01*
X351805Y1736921D01*
X351645Y1736754D01*
X351432Y1736629D01*
X350898D01*
G01X326250Y-525312D02*
X326850Y-524512D01*
X327550Y-524112D01*
X328350Y-523979D01*
X329350Y-524246D01*
X330050Y-524912D01*
X330250Y-525712D01*
X330150Y-526513D01*
X329750Y-527179D01*
X327750Y-528512D01*
X326850Y-529446D01*
X326250Y-530779D01*
X326050Y-531979D01*
X330250D01*
G01X336150Y-523979D02*
X335350Y-524246D01*
X334750Y-524912D01*
X334350Y-525712D01*
X334050Y-526779D01*
X333950Y-527979D01*
X334050Y-529179D01*
X334350Y-530246D01*
X334750Y-531046D01*
X335350Y-531712D01*
X336150Y-531979D01*
X336950Y-531712D01*
X337550Y-531046D01*
X337950Y-530246D01*
X338250Y-529179D01*
X338350Y-527979D01*
X338250Y-526779D01*
X337950Y-525712D01*
X337550Y-524912D01*
X336950Y-524246D01*
X336150Y-523979D01*
G01X342250Y-525312D02*
X342850Y-524512D01*
X343550Y-524112D01*
X344350Y-523979D01*
X345350Y-524246D01*
X346050Y-524912D01*
X346250Y-525712D01*
X346150Y-526513D01*
X345750Y-527179D01*
X343750Y-528512D01*
X342850Y-529446D01*
X342250Y-530779D01*
X342050Y-531979D01*
X346250D01*
G01X349950Y-530379D02*
X350550Y-531312D01*
X351350Y-531846D01*
X352250Y-531979D01*
X353050Y-531846D01*
X353850Y-531179D01*
X354350Y-530379D01*
X354450Y-529579D01*
X354250Y-528646D01*
X353550Y-527979D01*
X352850Y-527712D01*
X351950D01*
G01X352850D02*
X353450Y-527312D01*
X353950Y-526646D01*
X354150Y-525846D01*
X353950Y-525046D01*
X353450Y-524379D01*
X352550Y-523979D01*
X351650Y-524112D01*
X350750Y-524646D01*
G01X358350Y-532246D02*
X361950Y-523979D01*
G01X368150D02*
X367350Y-524246D01*
X366750Y-524912D01*
X366350Y-525712D01*
X366050Y-526779D01*
X365950Y-527979D01*
X366050Y-529179D01*
X366350Y-530246D01*
X366750Y-531046D01*
X367350Y-531712D01*
X368150Y-531979D01*
X368950Y-531712D01*
X369550Y-531046D01*
X369950Y-530246D01*
X370250Y-529179D01*
X370350Y-527979D01*
X370250Y-526779D01*
X369950Y-525712D01*
X369550Y-524912D01*
X368950Y-524246D01*
X368150Y-523979D01*
G01X373950Y-530379D02*
X374550Y-531312D01*
X375350Y-531846D01*
X376250Y-531979D01*
X377050Y-531846D01*
X377850Y-531179D01*
X378350Y-530379D01*
X378450Y-529579D01*
X378250Y-528646D01*
X377550Y-527979D01*
X376850Y-527712D01*
X375950D01*
G01X376850D02*
X377450Y-527312D01*
X377950Y-526646D01*
X378150Y-525846D01*
X377950Y-525046D01*
X377450Y-524379D01*
X376550Y-523979D01*
X375650Y-524112D01*
X374750Y-524646D01*
G01X382350Y-532246D02*
X385950Y-523979D01*
G01X390250Y-525312D02*
X390850Y-524512D01*
X391550Y-524112D01*
X392350Y-523979D01*
X393350Y-524246D01*
X394050Y-524912D01*
X394250Y-525712D01*
X394150Y-526513D01*
X393750Y-527179D01*
X391750Y-528512D01*
X390850Y-529446D01*
X390250Y-530779D01*
X390050Y-531979D01*
X394250D01*
G01X401350D02*
Y-523979D01*
X397650Y-529712D01*
X402650D01*
G01X325950Y-506979D02*
Y-498979D01*
X327950D01*
X328750Y-499379D01*
X329350Y-499912D01*
X329850Y-500712D01*
X330250Y-501646D01*
X330350Y-502979D01*
X330250Y-504312D01*
X329850Y-505246D01*
X329350Y-506046D01*
X328750Y-506579D01*
X327950Y-506979D01*
X325950D01*
G01X333650D02*
X336150Y-498979D01*
X338650Y-506979D01*
G01X337750Y-504179D02*
X334550D01*
G01X344150Y-498979D02*
X343350Y-499246D01*
X342750Y-499912D01*
X342350Y-500712D01*
X342050Y-501779D01*
X341950Y-502979D01*
X342050Y-504179D01*
X342350Y-505246D01*
X342750Y-506046D01*
X343350Y-506712D01*
X344150Y-506979D01*
X344950Y-506712D01*
X345550Y-506046D01*
X345950Y-505246D01*
X346250Y-504179D01*
X346350Y-502979D01*
X346250Y-501779D01*
X345950Y-500712D01*
X345550Y-499912D01*
X344950Y-499246D01*
X344150Y-498979D01*
G01X350250Y-506979D02*
Y-498979D01*
X354050D01*
G01X352650Y-502846D02*
X350250D01*
G01X360150Y-498979D02*
X359350Y-499246D01*
X358750Y-499912D01*
X358350Y-500712D01*
X358050Y-501779D01*
X357950Y-502979D01*
X358050Y-504179D01*
X358350Y-505246D01*
X358750Y-506046D01*
X359350Y-506712D01*
X360150Y-506979D01*
X360950Y-506712D01*
X361550Y-506046D01*
X361950Y-505246D01*
X362250Y-504179D01*
X362350Y-502979D01*
X362250Y-501779D01*
X361950Y-500712D01*
X361550Y-499912D01*
X360950Y-499246D01*
X360150Y-498979D01*
G01X368150D02*
Y-506979D01*
G01X365850Y-498979D02*
X370450D01*
G01X373550Y-506979D02*
Y-498979D01*
X376150Y-505646D01*
X378750Y-498979D01*
Y-506979D01*
G01X384950Y-502712D02*
X385350Y-502312D01*
X385650Y-501646D01*
X385850Y-500712D01*
X385650Y-499912D01*
X385250Y-499379D01*
X384550Y-498979D01*
X381850D01*
Y-506979D01*
X385150D01*
X385850Y-506446D01*
X386250Y-505646D01*
X386450Y-504712D01*
X386250Y-503779D01*
X385650Y-502979D01*
X384950Y-502712D01*
X381850D01*
G01X390950Y-498979D02*
X393350D01*
G01X392150D02*
Y-506979D01*
G01X390950D02*
X393350D01*
G01X398150Y-505379D02*
X398650Y-506179D01*
X399250Y-506712D01*
X399950Y-506979D01*
X400750Y-506712D01*
X401350Y-506179D01*
X401950Y-505379D01*
X402150Y-504312D01*
Y-498979D01*
G01X408150D02*
X407350Y-499246D01*
X406750Y-499912D01*
X406350Y-500712D01*
X406050Y-501779D01*
X405950Y-502979D01*
X406050Y-504179D01*
X406350Y-505246D01*
X406750Y-506046D01*
X407350Y-506712D01*
X408150Y-506979D01*
X408950Y-506712D01*
X409550Y-506046D01*
X409950Y-505246D01*
X410250Y-504179D01*
X410350Y-502979D01*
X410250Y-501779D01*
X409950Y-500712D01*
X409550Y-499912D01*
X408950Y-499246D01*
X408150Y-498979D01*
G01X333953Y65501D02*
Y54005D01*
G01X337594Y60153D02*
X335354D01*
G01X336567Y58528D02*
Y61778D01*
G01X327142Y71463D02*
Y68263D01*
G01X324017Y78463D02*
X327217D01*
G01X324017Y72263D02*
Y78463D01*
G01X327217Y72263D02*
X324017D01*
G01X327217Y78463D02*
Y72263D01*
G01Y79643D02*
X324017D01*
G01X327217Y85843D02*
Y79643D01*
G01X324017Y85843D02*
X327217D01*
G01X324017Y79643D02*
Y85843D01*
G01X323733Y158244D02*
Y146432D01*
G01X329000Y152362D02*
X326398Y149760D01*
Y145538D01*
X338602D01*
Y159186D01*
X326398D01*
Y154964D01*
X329000Y152362D01*
G01X335100Y140262D02*
Y143462D01*
G01X341300Y140262D02*
X335100D01*
G01Y143462D02*
X341300D01*
G01X331100Y137262D02*
Y143462D01*
X334300D01*
Y137262D01*
X331100D01*
G01X327100D02*
Y143462D01*
X330300D01*
Y137262D01*
X327100D01*
G01X330807Y171462D02*
Y169240D01*
X330960Y168775D01*
X331267Y168465D01*
X331650Y168362D01*
X332033Y168465D01*
X332340Y168775D01*
X332493Y169240D01*
Y171462D01*
G01X333907Y168982D02*
X334137Y168620D01*
X334443Y168414D01*
X334788Y168362D01*
X335095Y168414D01*
X335402Y168672D01*
X335593Y168982D01*
X335632Y169292D01*
X335555Y169654D01*
X335287Y169912D01*
X335018Y170015D01*
X334673D01*
G01X335018D02*
X335248Y170170D01*
X335440Y170429D01*
X335517Y170739D01*
X335440Y171049D01*
X335248Y171307D01*
X334903Y171462D01*
X334558Y171410D01*
X334213Y171204D01*
G01X337122Y170945D02*
X337352Y171255D01*
X337620Y171410D01*
X337927Y171462D01*
X338310Y171359D01*
X338578Y171100D01*
X338655Y170790D01*
X338617Y170480D01*
X338463Y170222D01*
X337697Y169705D01*
X337352Y169344D01*
X337122Y168827D01*
X337045Y168362D01*
X338655D01*
G01X340107Y168982D02*
X340337Y168620D01*
X340643Y168414D01*
X340988Y168362D01*
X341295Y168414D01*
X341602Y168672D01*
X341793Y168982D01*
X341832Y169292D01*
X341755Y169654D01*
X341487Y169912D01*
X341218Y170015D01*
X340873D01*
G01X341218D02*
X341448Y170170D01*
X341640Y170429D01*
X341717Y170739D01*
X341640Y171049D01*
X341448Y171307D01*
X341103Y171462D01*
X340758Y171410D01*
X340413Y171204D01*
G01X323861Y211251D02*
X332049D01*
G01X323861Y225227D02*
Y211251D01*
G01X332049D02*
Y225227D01*
G01X336667Y215227D02*
X339867D01*
G01X336667Y209027D02*
Y215227D01*
G01X339867Y209027D02*
X336667D01*
G01X332049Y225227D02*
X323861D01*
G01X339849Y222409D02*
X336649D01*
G01Y228609D02*
X339849D01*
G01X336649Y222409D02*
Y228609D01*
G01X323755Y236819D02*
Y230619D01*
G01X330565Y230139D02*
X327365D01*
G01X330565Y236339D02*
Y230139D01*
G01X327365D02*
Y236339D01*
G01X334065Y230139D02*
X330865D01*
G01X334065Y236339D02*
Y230139D01*
G01X330865D02*
Y236339D01*
G01X327365D02*
X330565D01*
G01X330865D02*
X334065D01*
G01X328048Y259277D02*
X331248D01*
G01X328048Y253077D02*
Y259277D01*
G01X331248Y253077D02*
X328048D01*
G01X331248Y259277D02*
Y253077D01*
G01X327854Y276785D02*
Y280535D01*
G01X334994Y276785D02*
X327854D01*
G01X334994Y280585D02*
Y276785D01*
G01X327904Y280585D02*
X334994D01*
G01X335494Y276785D02*
X328304D01*
G01X335494Y280585D02*
Y276785D01*
G01X328304Y280585D02*
X335494D01*
G01X335994Y276785D02*
X328904D01*
G01X335994Y280585D02*
Y276785D01*
G01X328904Y280585D02*
X335994D01*
G01X322394D02*
Y276785D01*
G01X322894Y280585D02*
Y276785D01*
G01X323394Y280585D02*
Y276785D01*
G01X327402Y297988D02*
X330602D01*
G01X327402Y291788D02*
Y297988D01*
G01X330602Y291788D02*
X327402D01*
G01X330602Y297988D02*
Y291788D01*
G01X322164Y313234D02*
Y309434D01*
G01X322664Y313234D02*
Y309434D01*
G01X327124D02*
Y313184D01*
G01X334264Y309434D02*
X327124D01*
G01X334264Y313234D02*
Y309434D01*
G01X327174Y313234D02*
X334264D01*
G01X334764Y309434D02*
X327574D01*
G01X334764Y313234D02*
Y309434D01*
G01X327574Y313234D02*
X334764D01*
G01X335264Y309434D02*
X328174D01*
G01X335264Y313234D02*
Y309434D01*
G01X328174Y313234D02*
X335264D01*
G01X331667Y361371D02*
Y370033D01*
G01X342161Y361371D02*
X331667D01*
G01Y373592D02*
Y382254D01*
G01X342161Y373592D02*
X331667D01*
G01X336914Y380054D02*
X338814Y382254D01*
G01X335014D02*
X336914Y380054D01*
G01Y367833D02*
X338814Y370033D01*
G01X335014D02*
X336914Y367833D01*
G01X331667Y370033D02*
X335014D01*
G01X331667Y382254D02*
X335014D01*
G01X323149Y392878D02*
X322842Y392930D01*
X322574Y393136D01*
X322344Y393446D01*
X322191Y393808D01*
X322114Y394221D01*
Y394635D01*
X322191Y395048D01*
X322344Y395410D01*
X322574Y395720D01*
X322842Y395926D01*
X323149Y395978D01*
X323456Y395926D01*
X323724Y395720D01*
X323954Y395410D01*
X324107Y395048D01*
X324184Y394635D01*
Y394221D01*
X324107Y393808D01*
X323954Y393446D01*
X323724Y393136D01*
X323456Y392930D01*
X323149Y392878D01*
G01X323456Y393705D02*
X323916Y392878D01*
G01X325597Y393240D02*
X325866Y392981D01*
X326172Y392878D01*
X326479Y392981D01*
X326747Y393291D01*
X326939Y393756D01*
X327016Y394221D01*
Y394790D01*
X326939Y395255D01*
X326747Y395668D01*
X326517Y395875D01*
X326249Y395978D01*
X325942Y395875D01*
X325712Y395668D01*
X325559Y395358D01*
X325482Y394945D01*
X325559Y394583D01*
X325751Y394221D01*
X325981Y394015D01*
X326249Y393963D01*
X326556Y394066D01*
X326786Y394325D01*
X327016Y394790D01*
G01X328697Y393240D02*
X328966Y392981D01*
X329272Y392878D01*
X329579Y392981D01*
X329847Y393291D01*
X330039Y393756D01*
X330116Y394221D01*
Y394790D01*
X330039Y395255D01*
X329847Y395668D01*
X329617Y395875D01*
X329349Y395978D01*
X329042Y395875D01*
X328812Y395668D01*
X328659Y395358D01*
X328582Y394945D01*
X328659Y394583D01*
X328851Y394221D01*
X329081Y394015D01*
X329349Y393963D01*
X329656Y394066D01*
X329886Y394325D01*
X330116Y394790D01*
G01X335111Y386919D02*
X331693D01*
G01X337111Y388643D02*
X335111Y386919D01*
G01X339111D02*
X337111Y388643D01*
G01X331693Y396367D02*
X342529D01*
G01X331693Y386919D02*
Y396367D01*
G01X335111Y398857D02*
X331693D01*
G01X337111Y400581D02*
X335111Y398857D01*
G01X339111D02*
X337111Y400581D01*
G01X331693Y408305D02*
X342529D01*
G01X331693Y398857D02*
Y408305D01*
G01X324909Y560818D02*
Y557618D01*
G01X326074Y570378D02*
Y568156D01*
X326227Y567691D01*
X326534Y567381D01*
X326917Y567278D01*
X327300Y567381D01*
X327607Y567691D01*
X327760Y568156D01*
Y570378D01*
G01X330017Y567278D02*
Y570378D01*
X329557Y569758D01*
G01Y567278D02*
X330477D01*
G01X333577D02*
Y570378D01*
X332159Y568156D01*
X334075D01*
G01X324905Y564776D02*
Y561576D01*
G01X325706Y597773D02*
X322506D01*
G01X325706Y603973D02*
Y597773D01*
G01X322506Y603973D02*
X325706D01*
G01X322506Y597773D02*
Y603973D01*
G01X329706Y597773D02*
X326506D01*
G01X329706Y603973D02*
Y597773D01*
G01X326506Y603973D02*
X329706D01*
G01X326506Y597773D02*
Y603973D01*
G01X326458Y838621D02*
G03X329411Y835668I2953J0D01*
G01X333151Y835708D02*
Y838464D01*
G01Y835708D02*
Y835668D01*
G01D02*
X329411D01*
G01X326458Y838621D02*
G03X329410Y835668I2953J0D01*
G01X333150Y835708D02*
Y838464D01*
G01Y835708D02*
Y835668D01*
G01D02*
X329410D01*
G01X326497Y829802D02*
X391458D01*
G01X326497Y829803D02*
X391458D01*
G01X329253Y1143976D02*
Y838464D01*
G01X333151D02*
X341025D01*
G01X326458Y838621D02*
Y842361D01*
G01X329253D02*
X326497D01*
G01X329253Y850235D02*
Y842361D01*
G01X326497Y850235D02*
X329253D01*
G01X333150Y838464D02*
X341024D01*
G01X326458Y838621D02*
Y842362D01*
G01X329252D02*
X326497D01*
G01X329252Y850236D02*
Y842362D01*
G01X326497Y850236D02*
X329252D01*
G01X326497Y860511D02*
Y850235D01*
G01Y860512D02*
Y850236D01*
G01X329253Y838464D02*
X552087D01*
G01X324529Y979409D02*
Y861298D01*
G01X324528Y979410D02*
Y861299D01*
G01X326497Y861298D02*
Y860511D01*
G01X324529Y861298D02*
X326497D01*
G01X324528Y861299D02*
X326497D01*
G01D02*
Y860512D01*
G01X332600Y986102D02*
X324529Y979409D01*
G01X332599Y986103D02*
X324528Y979410D01*
G01X324529Y1003031D02*
X332600Y996338D01*
G01X324528Y1003031D02*
X332599Y996338D01*
G01X332600D02*
Y986102D01*
G01X332599Y996338D02*
Y986103D01*
G01X324529Y1110157D02*
Y1003031D01*
G01X324528Y1110157D02*
Y1003031D01*
G01X328662Y1110157D02*
G03Y1116456I0J3149D01*
G01Y1110157D02*
G03Y1116456I0J3149D01*
G01X324529Y1132204D02*
Y1116456D01*
G01X324528Y1132205D02*
Y1116456D01*
G01X324529D02*
X328662D01*
G01X324528D02*
X328662D01*
G01X329411Y1146771D02*
G03X326458Y1143818I0J-2953D01*
G01X333151Y1143976D02*
Y1146731D01*
G01X329253Y1140078D02*
X326458D01*
G01X326497D02*
X329253D01*
G01X341025Y1143976D02*
X333151D01*
G01X326458Y1140078D02*
Y1143818D01*
G01X329410Y1146771D02*
G03X326458Y1143818I0J-2952D01*
G01X329252Y1140079D02*
X326458D01*
G01X326497D02*
X329252D01*
G01X326458D02*
Y1143818D01*
G01X552087Y1143976D02*
X329253D01*
G01Y1132204D02*
Y1140078D01*
G01X323348Y1132204D02*
X326497D01*
G01X329253D02*
X326497D01*
G01X329252Y1132205D02*
Y1140079D01*
G01X323347Y1132205D02*
X326497D01*
G01X329252D02*
X326497D01*
G01X333151Y1146771D02*
Y1146731D01*
G01X329411Y1146771D02*
X333151D01*
G01X329410D02*
X333150D01*
G01X334899Y1261830D02*
Y1264930D01*
X335819D01*
X336126Y1264775D01*
X336356Y1264413D01*
X336433Y1264000D01*
X336356Y1263587D01*
X336164Y1263277D01*
X335819Y1263122D01*
X334899D01*
G01X337999Y1264930D02*
Y1261830D01*
X339533D01*
G01X341138Y1264413D02*
X341368Y1264723D01*
X341636Y1264878D01*
X341943Y1264930D01*
X342326Y1264827D01*
X342594Y1264568D01*
X342671Y1264258D01*
X342633Y1263948D01*
X342479Y1263690D01*
X341713Y1263173D01*
X341368Y1262812D01*
X341138Y1262295D01*
X341061Y1261830D01*
X342671D01*
G01X344238Y1263122D02*
X344506Y1263483D01*
X344736Y1263690D01*
X345043Y1263793D01*
X345311Y1263690D01*
X345503Y1263483D01*
X345656Y1263173D01*
X345694Y1262812D01*
X345656Y1262502D01*
X345503Y1262192D01*
X345273Y1261933D01*
X345004Y1261830D01*
X344698Y1261933D01*
X344429Y1262243D01*
X344276Y1262708D01*
X344238Y1263225D01*
X344314Y1263897D01*
X344429Y1264258D01*
X344621Y1264620D01*
X344889Y1264878D01*
X345158Y1264930D01*
X345426Y1264827D01*
X345618Y1264568D01*
G01X334886Y1268772D02*
Y1312080D01*
G01X340227Y1268772D02*
X334886D01*
G01X332406Y1291806D02*
Y1335114D01*
G01X327065Y1291806D02*
X332406D01*
G01X334886Y1312080D02*
X340227D01*
G01X334079Y1323418D02*
Y1329618D01*
G01X337279Y1323418D02*
X334079D01*
G01X337279Y1329618D02*
Y1323418D01*
G01X327468Y1340856D02*
Y1338256D01*
X326675D01*
G01X332406Y1335114D02*
X327065D01*
G01X337273Y1334453D02*
X334073D01*
G01X337273Y1340653D02*
Y1334453D01*
G01X334073D02*
Y1340653D01*
G01X334079Y1329618D02*
X337279D01*
G01X337317Y1348407D02*
X340517D01*
G01X337317Y1342207D02*
Y1348407D01*
G01X340517Y1342207D02*
X337317D01*
G01X334605Y1355447D02*
X337805D01*
G01X334605Y1349247D02*
Y1355447D01*
G01X337805Y1349247D02*
X334605D01*
G01X337805Y1355447D02*
Y1349247D01*
G01X330173Y1353553D02*
X333373D01*
G01X330173Y1347353D02*
Y1353553D01*
G01X333373Y1347353D02*
X330173D01*
G01X333373Y1353553D02*
Y1347353D01*
G01X334073Y1340653D02*
X337273D01*
G01X326735Y1361878D02*
X327468D01*
Y1359687D01*
G01X323056Y1371291D02*
X326256D01*
G01X323056Y1365091D02*
Y1371291D01*
G01X326256Y1365091D02*
X323056D01*
G01X326256Y1371291D02*
Y1365091D01*
G01X322214Y1371291D02*
Y1365091D01*
G01X336270Y1654774D02*
X336538Y1655135D01*
X336768Y1655342D01*
X337075Y1655445D01*
X337343Y1655342D01*
X337535Y1655135D01*
X337688Y1654825D01*
X337726Y1654464D01*
X337688Y1654154D01*
X337535Y1653844D01*
X337305Y1653585D01*
X337036Y1653482D01*
X336730Y1653585D01*
X336461Y1653895D01*
X336308Y1654360D01*
X336270Y1654877D01*
X336346Y1655549D01*
X336461Y1655910D01*
X336653Y1656272D01*
X336921Y1656530D01*
X337190Y1656582D01*
X337458Y1656479D01*
X337650Y1656220D01*
G01X328281Y1653947D02*
X328511Y1653689D01*
X328779Y1653534D01*
X329124Y1653482D01*
X329469Y1653585D01*
X329737Y1653792D01*
X329929Y1654154D01*
X329967Y1654567D01*
X329891Y1654980D01*
X329699Y1655239D01*
X329431Y1655445D01*
X329162Y1655497D01*
X328894Y1655445D01*
X328549Y1655239D01*
X328664Y1656582D01*
X329699D01*
G01X343750Y-481979D02*
Y-473979D01*
X347550D01*
G01X346150Y-477846D02*
X343750D01*
G01X353650Y-473979D02*
X352850Y-474246D01*
X352250Y-474912D01*
X351850Y-475712D01*
X351550Y-476779D01*
X351450Y-477979D01*
X351550Y-479179D01*
X351850Y-480246D01*
X352250Y-481046D01*
X352850Y-481712D01*
X353650Y-481979D01*
X354450Y-481712D01*
X355050Y-481046D01*
X355450Y-480246D01*
X355750Y-479179D01*
X355850Y-477979D01*
X355750Y-476779D01*
X355450Y-475712D01*
X355050Y-474912D01*
X354450Y-474246D01*
X353650Y-473979D01*
G01X361650D02*
Y-481979D01*
G01X359350Y-473979D02*
X363950D01*
G01X366650Y-484646D02*
X372650D01*
G01X375050Y-481979D02*
Y-473979D01*
X377650Y-480646D01*
X380250Y-473979D01*
Y-481979D01*
G01X386450Y-477712D02*
X386850Y-477312D01*
X387150Y-476646D01*
X387350Y-475712D01*
X387150Y-474912D01*
X386750Y-474379D01*
X386050Y-473979D01*
X383350D01*
Y-481979D01*
X386650D01*
X387350Y-481446D01*
X387750Y-480646D01*
X387950Y-479712D01*
X387750Y-478779D01*
X387150Y-477979D01*
X386450Y-477712D01*
X383350D01*
G01X390650Y-484646D02*
X396650D01*
G01X403650Y-481979D02*
X399650D01*
Y-473979D01*
X403650D01*
G01X402050Y-477846D02*
X399650D01*
G01X407050Y-481979D02*
Y-473979D01*
X409650Y-480646D01*
X412250Y-473979D01*
Y-481979D01*
G01X417650D02*
X418350Y-481846D01*
X419150Y-481446D01*
X419650Y-480779D01*
X419850Y-479846D01*
X419650Y-478913D01*
X419050Y-478112D01*
X418150Y-477712D01*
X417150D01*
X416550Y-477446D01*
X416050Y-476779D01*
X415850Y-475846D01*
X416150Y-474912D01*
X416850Y-474246D01*
X417650Y-473979D01*
X418450Y-474246D01*
X419150Y-474912D01*
X419450Y-475846D01*
X419250Y-476779D01*
X418750Y-477446D01*
X418150Y-477712D01*
X417150D01*
X416250Y-478112D01*
X415650Y-478913D01*
X415450Y-479846D01*
X415650Y-480779D01*
X416150Y-481446D01*
X416950Y-481846D01*
X417650Y-481979D01*
G01X423950Y-481046D02*
X424650Y-481712D01*
X425450Y-481979D01*
X426250Y-481712D01*
X426950Y-480913D01*
X427450Y-479712D01*
X427650Y-478512D01*
Y-477046D01*
X427450Y-475846D01*
X426950Y-474779D01*
X426350Y-474246D01*
X425650Y-473979D01*
X424850Y-474246D01*
X424250Y-474779D01*
X423850Y-475579D01*
X423650Y-476646D01*
X423850Y-477579D01*
X424350Y-478512D01*
X424950Y-479046D01*
X425650Y-479179D01*
X426450Y-478913D01*
X427050Y-478246D01*
X427650Y-477046D01*
G01X433650Y-473979D02*
X432850Y-474246D01*
X432250Y-474912D01*
X431850Y-475712D01*
X431550Y-476779D01*
X431450Y-477979D01*
X431550Y-479179D01*
X431850Y-480246D01*
X432250Y-481046D01*
X432850Y-481712D01*
X433650Y-481979D01*
X434450Y-481712D01*
X435050Y-481046D01*
X435450Y-480246D01*
X435750Y-479179D01*
X435850Y-477979D01*
X435750Y-476779D01*
X435450Y-475712D01*
X435050Y-474912D01*
X434450Y-474246D01*
X433650Y-473979D01*
G01X439450Y-481979D02*
Y-473979D01*
G01X443250D02*
X439450Y-478913D01*
G01X443850Y-481979D02*
X441150Y-476646D01*
G01X339906Y54708D02*
Y57808D01*
X340826D01*
X341133Y57653D01*
X341363Y57291D01*
X341440Y56878D01*
X341363Y56465D01*
X341171Y56155D01*
X340826Y56000D01*
X339906D01*
G01X342930Y54708D02*
Y57808D01*
X343696D01*
X344003Y57653D01*
X344233Y57446D01*
X344425Y57136D01*
X344578Y56775D01*
X344616Y56258D01*
X344578Y55741D01*
X344425Y55380D01*
X344233Y55070D01*
X344003Y54863D01*
X343696Y54708D01*
X342930D01*
G01X346873D02*
Y57808D01*
X346413Y57188D01*
G01Y54708D02*
X347333D01*
G01X349973Y57808D02*
X349666Y57705D01*
X349436Y57446D01*
X349283Y57136D01*
X349168Y56723D01*
X349130Y56258D01*
X349168Y55793D01*
X349283Y55380D01*
X349436Y55070D01*
X349666Y54811D01*
X349973Y54708D01*
X350280Y54811D01*
X350510Y55070D01*
X350663Y55380D01*
X350778Y55793D01*
X350816Y56258D01*
X350778Y56723D01*
X350663Y57136D01*
X350510Y57446D01*
X350280Y57705D01*
X349973Y57808D01*
G01X353073Y54708D02*
X353341Y54760D01*
X353648Y54915D01*
X353840Y55173D01*
X353916Y55535D01*
X353840Y55896D01*
X353610Y56206D01*
X353265Y56361D01*
X352881D01*
X352651Y56465D01*
X352460Y56723D01*
X352383Y57085D01*
X352498Y57446D01*
X352766Y57705D01*
X353073Y57808D01*
X353380Y57705D01*
X353648Y57446D01*
X353763Y57085D01*
X353686Y56723D01*
X353495Y56465D01*
X353265Y56361D01*
X352881D01*
X352536Y56206D01*
X352306Y55896D01*
X352230Y55535D01*
X352306Y55173D01*
X352498Y54915D01*
X352805Y54760D01*
X353073Y54708D01*
G01X349407Y104032D02*
Y107132D01*
G01X351017D02*
Y104032D01*
G01Y105582D02*
X349407D01*
G01X353312Y104032D02*
Y107132D01*
X352852Y106512D01*
G01Y104032D02*
X353772D01*
G01X356412Y107132D02*
X356105Y107029D01*
X355875Y106770D01*
X355722Y106460D01*
X355607Y106047D01*
X355569Y105582D01*
X355607Y105117D01*
X355722Y104704D01*
X355875Y104394D01*
X356105Y104135D01*
X356412Y104032D01*
X356719Y104135D01*
X356949Y104394D01*
X357102Y104704D01*
X357217Y105117D01*
X357255Y105582D01*
X357217Y106047D01*
X357102Y106460D01*
X356949Y106770D01*
X356719Y107029D01*
X356412Y107132D01*
G01X359512Y104032D02*
Y107132D01*
X359052Y106512D01*
G01Y104032D02*
X359972D01*
G01X338211Y121577D02*
Y127777D01*
X341411D01*
Y121577D01*
X338211D01*
G01X343907Y137229D02*
Y135007D01*
X344060Y134542D01*
X344367Y134232D01*
X344750Y134129D01*
X345133Y134232D01*
X345440Y134542D01*
X345593Y135007D01*
Y137229D01*
G01X347007Y134749D02*
X347237Y134387D01*
X347543Y134181D01*
X347888Y134129D01*
X348195Y134181D01*
X348502Y134439D01*
X348693Y134749D01*
X348732Y135059D01*
X348655Y135421D01*
X348387Y135679D01*
X348118Y135782D01*
X347773D01*
G01X348118D02*
X348348Y135937D01*
X348540Y136196D01*
X348617Y136506D01*
X348540Y136816D01*
X348348Y137074D01*
X348003Y137229D01*
X347658Y137177D01*
X347313Y136971D01*
G01X350222Y136712D02*
X350452Y137022D01*
X350720Y137177D01*
X351027Y137229D01*
X351410Y137126D01*
X351678Y136867D01*
X351755Y136557D01*
X351717Y136247D01*
X351563Y135989D01*
X350797Y135472D01*
X350452Y135111D01*
X350222Y134594D01*
X350145Y134129D01*
X351755D01*
G01X354050D02*
Y137229D01*
X353590Y136609D01*
G01Y134129D02*
X354510D01*
G01X360500Y132364D02*
Y120160D01*
X344500D01*
Y132364D01*
X360500D01*
G01X345776Y146100D02*
X359424D01*
G01X345776Y158304D02*
Y146100D01*
G01X352138Y144469D02*
Y141269D01*
G01X345938Y144469D02*
X352138D01*
G01X345938Y141269D02*
Y144469D01*
G01X352138Y141269D02*
X345938D01*
G01X341300Y143462D02*
Y140262D01*
G01X351787Y163959D02*
Y161737D01*
X351940Y161272D01*
X352247Y160962D01*
X352630Y160859D01*
X353013Y160962D01*
X353320Y161272D01*
X353473Y161737D01*
Y163959D01*
G01X354887Y161324D02*
X355117Y161066D01*
X355385Y160911D01*
X355730Y160859D01*
X356075Y160962D01*
X356343Y161169D01*
X356535Y161531D01*
X356573Y161944D01*
X356497Y162357D01*
X356305Y162616D01*
X356037Y162822D01*
X355768Y162874D01*
X355500Y162822D01*
X355155Y162616D01*
X355270Y163959D01*
X356305D01*
G01X357987Y161479D02*
X358217Y161117D01*
X358523Y160911D01*
X358868Y160859D01*
X359175Y160911D01*
X359482Y161169D01*
X359673Y161479D01*
X359712Y161789D01*
X359635Y162151D01*
X359367Y162409D01*
X359098Y162512D01*
X358753D01*
G01X359098D02*
X359328Y162667D01*
X359520Y162926D01*
X359597Y163236D01*
X359520Y163546D01*
X359328Y163804D01*
X358983Y163959D01*
X358638Y163907D01*
X358293Y163701D01*
G01X355202Y158304D02*
X352600Y155702D01*
G01X349998Y158304D02*
X345776D01*
G01X352600Y155702D02*
X349998Y158304D01*
G01X338400Y163462D02*
X344600D01*
Y160262D01*
X338400D01*
Y163462D01*
G01X343885Y209009D02*
X340685D01*
G01X343885Y215209D02*
Y209009D01*
G01X340685Y215209D02*
X343885D01*
G01X340685Y209009D02*
Y215209D01*
G01X339867Y215227D02*
Y209027D01*
G01X347803D02*
X344603D01*
G01X347803Y215227D02*
Y209027D01*
G01X344603Y215227D02*
X347803D01*
G01X344603Y209027D02*
Y215227D01*
G01X347849Y222409D02*
X344649D01*
G01X347849Y228609D02*
Y222409D01*
G01X344649Y228609D02*
X347849D01*
G01X344649Y222409D02*
Y228609D01*
G01X339849D02*
Y222409D01*
G01X343849D02*
X340649D01*
G01X343849Y228609D02*
Y222409D01*
G01X340649Y228609D02*
X343849D01*
G01X340649Y222409D02*
Y228609D01*
G01X351620Y227462D02*
X357820D01*
G01X351620Y224262D02*
Y227462D01*
G01X357820Y224262D02*
X351620D01*
G01Y220262D02*
Y223462D01*
G01X357820Y220262D02*
X351620D01*
G01Y223462D02*
X357820D01*
G01X353072Y259768D02*
X356272D01*
G01X353072Y253568D02*
Y259768D01*
G01X356272Y253568D02*
X353072D01*
G01X340400Y259687D02*
X343600D01*
G01X340400Y253487D02*
Y259687D01*
G01X343600Y253487D02*
X340400D01*
G01X343600Y259687D02*
Y253487D01*
G01X340454Y276785D02*
Y280535D01*
G01X347594Y276785D02*
X340454D01*
G01X347594Y280585D02*
Y276785D01*
G01X340504Y280585D02*
X347594D01*
G01X348094Y276785D02*
X340904D01*
G01X348094Y280585D02*
Y276785D01*
G01X340904Y280585D02*
X348094D01*
G01X348594Y276785D02*
X341504D01*
G01X348594Y280585D02*
Y276785D01*
G01X341504Y280585D02*
X348594D01*
G01X353054Y276785D02*
Y280535D01*
G01X360194Y276785D02*
X353054D01*
G01X353104Y280585D02*
X360194D01*
G01X360694Y276785D02*
X353504D01*
G01Y280585D02*
X360694D01*
G01X361194Y276785D02*
X354104D01*
G01Y280585D02*
X361194D01*
G01X352545Y297666D02*
X355745D01*
G01X352545Y291466D02*
Y297666D01*
G01X355745Y291466D02*
X352545D01*
G01X339695Y297314D02*
X342895D01*
G01X339695Y291114D02*
Y297314D01*
G01X342895Y291114D02*
X339695D01*
G01X342895Y297314D02*
Y291114D01*
G01X339724Y309434D02*
Y313184D01*
G01X346864Y309434D02*
X339724D01*
G01X346864Y313234D02*
Y309434D01*
G01X339774Y313234D02*
X346864D01*
G01X347364Y309434D02*
X340174D01*
G01X347364Y313234D02*
Y309434D01*
G01X340174Y313234D02*
X347364D01*
G01X347864Y309434D02*
X340774D01*
G01X347864Y313234D02*
Y309434D01*
G01X340774Y313234D02*
X347864D01*
G01X352324Y309434D02*
Y313184D01*
G01X359464Y309434D02*
X352324D01*
G01X352374Y313234D02*
X359464D01*
G01X359964Y309434D02*
X352774D01*
G01Y313234D02*
X359964D01*
G01X360464Y309434D02*
X353374D01*
G01Y313234D02*
X360464D01*
G01X342161Y370033D02*
Y361371D01*
G01Y382254D02*
Y373592D01*
G01X338814Y370033D02*
X342161D01*
G01X352817Y377386D02*
X352510Y377438D01*
X352242Y377644D01*
X352012Y377954D01*
X351859Y378316D01*
X351782Y378729D01*
Y379143D01*
X351859Y379556D01*
X352012Y379918D01*
X352242Y380228D01*
X352510Y380434D01*
X352817Y380486D01*
X353124Y380434D01*
X353392Y380228D01*
X353622Y379918D01*
X353775Y379556D01*
X353852Y379143D01*
Y378729D01*
X353775Y378316D01*
X353622Y377954D01*
X353392Y377644D01*
X353124Y377438D01*
X352817Y377386D01*
G01X353124Y378213D02*
X353584Y377386D01*
G01X355265Y377748D02*
X355534Y377489D01*
X355840Y377386D01*
X356147Y377489D01*
X356415Y377799D01*
X356607Y378264D01*
X356684Y378729D01*
Y379298D01*
X356607Y379763D01*
X356415Y380176D01*
X356185Y380383D01*
X355917Y380486D01*
X355610Y380383D01*
X355380Y380176D01*
X355227Y379866D01*
X355150Y379453D01*
X355227Y379091D01*
X355419Y378729D01*
X355649Y378523D01*
X355917Y378471D01*
X356224Y378574D01*
X356454Y378833D01*
X356684Y379298D01*
G01X358940Y377386D02*
X359017Y378058D01*
X359132Y378626D01*
X359285Y379143D01*
X359477Y379711D01*
X359784Y380486D01*
X358250D01*
G01X352949Y393154D02*
X352642Y393206D01*
X352374Y393412D01*
X352144Y393722D01*
X351991Y394084D01*
X351914Y394497D01*
Y394911D01*
X351991Y395324D01*
X352144Y395686D01*
X352374Y395996D01*
X352642Y396202D01*
X352949Y396254D01*
X353256Y396202D01*
X353524Y395996D01*
X353754Y395686D01*
X353907Y395324D01*
X353984Y394911D01*
Y394497D01*
X353907Y394084D01*
X353754Y393722D01*
X353524Y393412D01*
X353256Y393206D01*
X352949Y393154D01*
G01X353256Y393981D02*
X353716Y393154D01*
G01X356049D02*
X356317Y393206D01*
X356624Y393361D01*
X356816Y393619D01*
X356892Y393981D01*
X356816Y394342D01*
X356586Y394652D01*
X356241Y394807D01*
X355857D01*
X355627Y394911D01*
X355436Y395169D01*
X355359Y395531D01*
X355474Y395892D01*
X355742Y396151D01*
X356049Y396254D01*
X356356Y396151D01*
X356624Y395892D01*
X356739Y395531D01*
X356662Y395169D01*
X356471Y394911D01*
X356241Y394807D01*
X355857D01*
X355512Y394652D01*
X355282Y394342D01*
X355206Y393981D01*
X355282Y393619D01*
X355474Y393361D01*
X355781Y393206D01*
X356049Y393154D01*
G01X359609D02*
Y396254D01*
X358191Y394032D01*
X360107D01*
G01X338814Y382254D02*
X342161D01*
G01X342529Y386919D02*
X339111D01*
G01X342529Y396367D02*
Y386919D01*
G01Y398857D02*
X339111D01*
G01X342529Y408305D02*
Y398857D01*
G01X353443Y405190D02*
X353136Y405242D01*
X352868Y405448D01*
X352638Y405758D01*
X352485Y406120D01*
X352408Y406533D01*
Y406947D01*
X352485Y407360D01*
X352638Y407722D01*
X352868Y408032D01*
X353136Y408238D01*
X353443Y408290D01*
X353750Y408238D01*
X354018Y408032D01*
X354248Y407722D01*
X354401Y407360D01*
X354478Y406947D01*
Y406533D01*
X354401Y406120D01*
X354248Y405758D01*
X354018Y405448D01*
X353750Y405242D01*
X353443Y405190D01*
G01X353750Y406017D02*
X354210Y405190D01*
G01X356543D02*
Y408290D01*
X356083Y407670D01*
G01Y405190D02*
X357003D01*
G01X359643Y408290D02*
X359336Y408187D01*
X359106Y407928D01*
X358953Y407618D01*
X358838Y407205D01*
X358800Y406740D01*
X358838Y406275D01*
X358953Y405862D01*
X359106Y405552D01*
X359336Y405293D01*
X359643Y405190D01*
X359950Y405293D01*
X360180Y405552D01*
X360333Y405862D01*
X360448Y406275D01*
X360486Y406740D01*
X360448Y407205D01*
X360333Y407618D01*
X360180Y407928D01*
X359950Y408187D01*
X359643Y408290D01*
G01X361900Y405655D02*
X362130Y405397D01*
X362398Y405242D01*
X362743Y405190D01*
X363088Y405293D01*
X363356Y405500D01*
X363548Y405862D01*
X363586Y406275D01*
X363510Y406688D01*
X363318Y406947D01*
X363050Y407153D01*
X362781Y407205D01*
X362513Y407153D01*
X362168Y406947D01*
X362283Y408290D01*
X363318D01*
G01X351297Y707379D02*
Y704179D01*
G01X345097D02*
Y707379D01*
G01X351297Y704179D02*
X345097D01*
G01X345133Y708395D02*
Y711595D01*
G01X351333Y708395D02*
X345133D01*
G01X351333Y711595D02*
Y708395D01*
G01X345133Y711595D02*
X351333D01*
G01X345097Y707379D02*
X351297D01*
G01X349104Y794528D02*
Y797628D01*
G01X350714D02*
Y794528D01*
G01Y796078D02*
X349104D01*
G01X352281Y797111D02*
X352511Y797421D01*
X352779Y797576D01*
X353086Y797628D01*
X353469Y797525D01*
X353737Y797266D01*
X353814Y796956D01*
X353776Y796646D01*
X353622Y796388D01*
X352856Y795871D01*
X352511Y795510D01*
X352281Y794993D01*
X352204Y794528D01*
X353814D01*
G01X356109Y797628D02*
X355802Y797525D01*
X355572Y797266D01*
X355419Y796956D01*
X355304Y796543D01*
X355266Y796078D01*
X355304Y795613D01*
X355419Y795200D01*
X355572Y794890D01*
X355802Y794631D01*
X356109Y794528D01*
X356416Y794631D01*
X356646Y794890D01*
X356799Y795200D01*
X356914Y795613D01*
X356952Y796078D01*
X356914Y796543D01*
X356799Y796956D01*
X356646Y797266D01*
X356416Y797525D01*
X356109Y797628D01*
G01X360049Y811121D02*
G03I-9950J0D01*
G01X341025Y829802D02*
Y833556D01*
G01D02*
Y838464D01*
G01X341024Y833556D02*
Y838464D01*
G01Y829803D02*
Y833556D01*
G01X341025Y1143976D02*
Y1148883D01*
G01X341024Y1143977D02*
Y1148883D01*
G01X341025D02*
Y1152637D01*
G01X341024Y1148883D02*
Y1152638D01*
G01X366013Y1171318D02*
G03I-9950J0D01*
G01X342305Y1197132D02*
Y1200232D01*
G01X343915D02*
Y1197132D01*
G01Y1198682D02*
X342305D01*
G01X345482Y1199715D02*
X345712Y1200025D01*
X345980Y1200180D01*
X346287Y1200232D01*
X346670Y1200129D01*
X346938Y1199870D01*
X347015Y1199560D01*
X346977Y1199250D01*
X346823Y1198992D01*
X346057Y1198475D01*
X345712Y1198114D01*
X345482Y1197597D01*
X345405Y1197132D01*
X347015D01*
G01X348582Y1199715D02*
X348812Y1200025D01*
X349080Y1200180D01*
X349387Y1200232D01*
X349770Y1200129D01*
X350038Y1199870D01*
X350115Y1199560D01*
X350077Y1199250D01*
X349923Y1198992D01*
X349157Y1198475D01*
X348812Y1198114D01*
X348582Y1197597D01*
X348505Y1197132D01*
X350115D01*
G01X339910Y1315458D02*
Y1318058D01*
G01X340703Y1315458D02*
X339910D01*
G01Y1339080D02*
X340918D01*
G01X339910Y1337226D02*
Y1339080D01*
G01Y1324669D02*
Y1326367D01*
G01X341886Y1351149D02*
Y1354249D01*
X342806D01*
X343113Y1354094D01*
X343343Y1353732D01*
X343420Y1353319D01*
X343343Y1352906D01*
X343151Y1352596D01*
X342806Y1352441D01*
X341886D01*
G01X344910Y1354249D02*
Y1352027D01*
X345063Y1351562D01*
X345370Y1351252D01*
X345753Y1351149D01*
X346136Y1351252D01*
X346443Y1351562D01*
X346596Y1352027D01*
Y1354249D01*
G01X348125Y1353732D02*
X348355Y1354042D01*
X348623Y1354197D01*
X348930Y1354249D01*
X349313Y1354146D01*
X349581Y1353887D01*
X349658Y1353577D01*
X349620Y1353267D01*
X349466Y1353009D01*
X348700Y1352492D01*
X348355Y1352131D01*
X348125Y1351614D01*
X348048Y1351149D01*
X349658D01*
G01X351110Y1351614D02*
X351340Y1351356D01*
X351608Y1351201D01*
X351953Y1351149D01*
X352298Y1351252D01*
X352566Y1351459D01*
X352758Y1351821D01*
X352796Y1352234D01*
X352720Y1352647D01*
X352528Y1352906D01*
X352260Y1353112D01*
X351991Y1353164D01*
X351723Y1353112D01*
X351378Y1352906D01*
X351493Y1354249D01*
X352528D01*
G01X353903Y1350116D02*
X356203D01*
G01X357386Y1351149D02*
Y1354249D01*
X358306D01*
X358613Y1354094D01*
X358843Y1353732D01*
X358920Y1353319D01*
X358843Y1352906D01*
X358651Y1352596D01*
X358306Y1352441D01*
X357386D01*
G01X361253Y1351149D02*
Y1354249D01*
X360793Y1353629D01*
G01Y1351149D02*
X361713D01*
G01X363203Y1350116D02*
X365503D01*
G01X366725Y1352441D02*
X366993Y1352802D01*
X367223Y1353009D01*
X367530Y1353112D01*
X367798Y1353009D01*
X367990Y1352802D01*
X368143Y1352492D01*
X368181Y1352131D01*
X368143Y1351821D01*
X367990Y1351511D01*
X367760Y1351252D01*
X367491Y1351149D01*
X367185Y1351252D01*
X366916Y1351562D01*
X366763Y1352027D01*
X366725Y1352544D01*
X366801Y1353216D01*
X366916Y1353577D01*
X367108Y1353939D01*
X367376Y1354197D01*
X367645Y1354249D01*
X367913Y1354146D01*
X368105Y1353887D01*
G01X340517Y1348407D02*
Y1342207D01*
G01X354342Y1342293D02*
X351142D01*
G01X354342Y1348493D02*
Y1342293D01*
G01X351142Y1348493D02*
X354342D01*
G01X351142Y1342293D02*
Y1348493D01*
G01X341569Y1345921D02*
Y1349121D01*
G01X347769Y1345921D02*
X341569D01*
G01X347769Y1349121D02*
Y1345921D01*
G01X341569Y1349121D02*
X347769D01*
G01X349736Y1375253D02*
X356275D01*
G01X349736Y1414623D02*
Y1375253D01*
G01X356275Y1414623D02*
X349736D01*
G01X344795Y1653482D02*
X344872Y1654154D01*
X344987Y1654722D01*
X345140Y1655239D01*
X345332Y1655807D01*
X345639Y1656582D01*
X344105D01*
G01X352746Y1653482D02*
X353014Y1653534D01*
X353321Y1653689D01*
X353513Y1653947D01*
X353589Y1654309D01*
X353513Y1654670D01*
X353283Y1654980D01*
X352938Y1655135D01*
X352554D01*
X352324Y1655239D01*
X352133Y1655497D01*
X352056Y1655859D01*
X352171Y1656220D01*
X352439Y1656479D01*
X352746Y1656582D01*
X353053Y1656479D01*
X353321Y1656220D01*
X353436Y1655859D01*
X353359Y1655497D01*
X353168Y1655239D01*
X352938Y1655135D01*
X352554D01*
X352209Y1654980D01*
X351979Y1654670D01*
X351903Y1654309D01*
X351979Y1653947D01*
X352171Y1653689D01*
X352478Y1653534D01*
X352746Y1653482D01*
G01X362100Y131762D02*
X368300D01*
Y128562D01*
X362100D01*
Y131762D01*
G01X359424Y146100D02*
Y158304D01*
G01D02*
X355202D01*
G01X362717Y166862D02*
Y169962D01*
G01X364327D02*
Y166862D01*
G01Y168412D02*
X362717D01*
G01X366545Y166862D02*
X366622Y167534D01*
X366737Y168102D01*
X366890Y168619D01*
X367082Y169187D01*
X367389Y169962D01*
X365855D01*
G01X370182Y166862D02*
Y169962D01*
X368764Y167740D01*
X370680D01*
G01X362000Y154602D02*
Y157802D01*
G01X368200Y154602D02*
X362000D01*
G01X368200Y157802D02*
Y154602D01*
G01X362000Y157802D02*
X368200D01*
G01X374897Y215023D02*
X359543D01*
G01D02*
Y227701D01*
G01X357677Y232229D02*
Y230007D01*
X357830Y229542D01*
X358137Y229232D01*
X358520Y229129D01*
X358903Y229232D01*
X359210Y229542D01*
X359363Y230007D01*
Y232229D01*
G01X361620Y229129D02*
X361888Y229181D01*
X362195Y229336D01*
X362387Y229594D01*
X362463Y229956D01*
X362387Y230317D01*
X362157Y230627D01*
X361812Y230782D01*
X361428D01*
X361198Y230886D01*
X361007Y231144D01*
X360930Y231506D01*
X361045Y231867D01*
X361313Y232126D01*
X361620Y232229D01*
X361927Y232126D01*
X362195Y231867D01*
X362310Y231506D01*
X362233Y231144D01*
X362042Y230886D01*
X361812Y230782D01*
X361428D01*
X361083Y230627D01*
X360853Y230317D01*
X360777Y229956D01*
X360853Y229594D01*
X361045Y229336D01*
X361352Y229181D01*
X361620Y229129D01*
G01X364643D02*
X364720Y229801D01*
X364835Y230369D01*
X364988Y230886D01*
X365180Y231454D01*
X365487Y232229D01*
X363953D01*
G01X359543Y227701D02*
X374897D01*
G01X357820Y227462D02*
Y224262D01*
G01Y223462D02*
Y220262D01*
G01X365706Y259886D02*
X368906D01*
G01X365706Y253686D02*
Y259886D01*
G01X368906Y253686D02*
X365706D01*
G01X368906Y259886D02*
Y253686D01*
G01X356272Y259768D02*
Y253568D01*
G01X360194Y280585D02*
Y276785D01*
G01X360694Y280585D02*
Y276785D01*
G01X361194Y280585D02*
Y276785D01*
G01X365654D02*
Y280535D01*
G01X372794Y276785D02*
X365654D01*
G01X365704Y280585D02*
X372794D01*
G01X373294Y276785D02*
X366104D01*
G01Y280585D02*
X373294D01*
G01X373794Y276785D02*
X366704D01*
G01Y280585D02*
X373794D01*
G01X355745Y297666D02*
Y291466D01*
G01X364898Y297339D02*
X368098D01*
G01X364898Y291139D02*
Y297339D01*
G01X368098Y291139D02*
X364898D01*
G01X368098Y297339D02*
Y291139D01*
G01X364924Y309434D02*
Y313184D01*
G01X372064Y309434D02*
X364924D01*
G01X364974Y313234D02*
X372064D01*
G01X372564Y309434D02*
X365374D01*
G01Y313234D02*
X372564D01*
G01X373064Y309434D02*
X365974D01*
G01Y313234D02*
X373064D01*
G01X359464D02*
Y309434D01*
G01X359964Y313234D02*
Y309434D01*
G01X360464Y313234D02*
Y309434D01*
G01X369427Y357218D02*
X369120Y357270D01*
X368852Y357476D01*
X368622Y357786D01*
X368469Y358148D01*
X368392Y358561D01*
Y358975D01*
X368469Y359388D01*
X368622Y359750D01*
X368852Y360060D01*
X369120Y360266D01*
X369427Y360318D01*
X369734Y360266D01*
X370002Y360060D01*
X370232Y359750D01*
X370385Y359388D01*
X370462Y358975D01*
Y358561D01*
X370385Y358148D01*
X370232Y357786D01*
X370002Y357476D01*
X369734Y357270D01*
X369427Y357218D01*
G01X369734Y358045D02*
X370194Y357218D01*
G01X371875Y357580D02*
X372144Y357321D01*
X372450Y357218D01*
X372757Y357321D01*
X373025Y357631D01*
X373217Y358096D01*
X373294Y358561D01*
Y359130D01*
X373217Y359595D01*
X373025Y360008D01*
X372795Y360215D01*
X372527Y360318D01*
X372220Y360215D01*
X371990Y360008D01*
X371837Y359698D01*
X371760Y359285D01*
X371837Y358923D01*
X372029Y358561D01*
X372259Y358355D01*
X372527Y358303D01*
X372834Y358406D01*
X373064Y358665D01*
X373294Y359130D01*
G01X375627Y357218D02*
X375895Y357270D01*
X376202Y357425D01*
X376394Y357683D01*
X376470Y358045D01*
X376394Y358406D01*
X376164Y358716D01*
X375819Y358871D01*
X375435D01*
X375205Y358975D01*
X375014Y359233D01*
X374937Y359595D01*
X375052Y359956D01*
X375320Y360215D01*
X375627Y360318D01*
X375934Y360215D01*
X376202Y359956D01*
X376317Y359595D01*
X376240Y359233D01*
X376049Y358975D01*
X375819Y358871D01*
X375435D01*
X375090Y358716D01*
X374860Y358406D01*
X374784Y358045D01*
X374860Y357683D01*
X375052Y357425D01*
X375359Y357270D01*
X375627Y357218D01*
G01X364839Y361667D02*
Y371115D01*
G01X375675Y361667D02*
X364839D01*
G01X370257Y369391D02*
X372257Y371115D01*
G01X368257D02*
X370257Y369391D01*
G01X364839Y371115D02*
X368257D01*
G01X364839Y373925D02*
Y383373D01*
G01X375675Y373925D02*
X364839D01*
G01X365172Y387706D02*
Y396368D01*
G01X375666Y387706D02*
X365172D01*
G01X370419Y394168D02*
X372319Y396368D01*
G01X368519D02*
X370419Y394168D01*
G01X365172Y396368D02*
X368519D01*
G01X370257Y381649D02*
X372257Y383373D01*
G01X368257D02*
X370257Y381649D01*
G01X364839Y383373D02*
X368257D01*
G01Y398857D02*
X364839D01*
G01X370257Y400581D02*
X368257Y398857D01*
G01X372257D02*
X370257Y400581D01*
G01X364839Y408305D02*
X375675D01*
G01X364839Y398857D02*
Y408305D01*
G01X365324Y1249776D02*
X362224D01*
Y1250696D01*
X362379Y1251003D01*
X362741Y1251233D01*
X363154Y1251310D01*
X363567Y1251233D01*
X363877Y1251041D01*
X364032Y1250696D01*
Y1249776D01*
G01X362224Y1252876D02*
X365324D01*
Y1254410D01*
G01X364704Y1255900D02*
X365066Y1256130D01*
X365272Y1256436D01*
X365324Y1256781D01*
X365272Y1257088D01*
X365014Y1257395D01*
X364704Y1257586D01*
X364394Y1257625D01*
X364032Y1257548D01*
X363774Y1257280D01*
X363671Y1257011D01*
Y1256666D01*
G01Y1257011D02*
X363516Y1257241D01*
X363257Y1257433D01*
X362947Y1257510D01*
X362637Y1257433D01*
X362379Y1257241D01*
X362224Y1256896D01*
X362276Y1256551D01*
X362482Y1256206D01*
G01X362224Y1259843D02*
X362327Y1259536D01*
X362586Y1259306D01*
X362896Y1259153D01*
X363309Y1259038D01*
X363774Y1259000D01*
X364239Y1259038D01*
X364652Y1259153D01*
X364962Y1259306D01*
X365221Y1259536D01*
X365324Y1259843D01*
X365221Y1260150D01*
X364962Y1260380D01*
X364652Y1260533D01*
X364239Y1260648D01*
X363774Y1260686D01*
X363309Y1260648D01*
X362896Y1260533D01*
X362586Y1260380D01*
X362327Y1260150D01*
X362224Y1259843D01*
G01X360444Y1249898D02*
X357344D01*
Y1250818D01*
X357499Y1251125D01*
X357861Y1251355D01*
X358274Y1251432D01*
X358687Y1251355D01*
X358997Y1251163D01*
X359152Y1250818D01*
Y1249898D01*
G01X357344Y1252998D02*
X360444D01*
Y1254532D01*
G01X359824Y1256022D02*
X360186Y1256252D01*
X360392Y1256558D01*
X360444Y1256903D01*
X360392Y1257210D01*
X360134Y1257517D01*
X359824Y1257708D01*
X359514Y1257747D01*
X359152Y1257670D01*
X358894Y1257402D01*
X358791Y1257133D01*
Y1256788D01*
G01Y1257133D02*
X358636Y1257363D01*
X358377Y1257555D01*
X358067Y1257632D01*
X357757Y1257555D01*
X357499Y1257363D01*
X357344Y1257018D01*
X357396Y1256673D01*
X357602Y1256328D01*
G01X360444Y1259965D02*
X357344D01*
X357964Y1259505D01*
G01X360444D02*
Y1260425D01*
G01X366967Y1255690D02*
Y1298998D01*
G01X372308Y1255690D02*
X366967D01*
G01X364414Y1268772D02*
Y1312080D01*
G01X359073Y1268772D02*
X364414D01*
G01X366967Y1298998D02*
X372308D01*
G01X359596Y1315458D02*
X358803D01*
G01X359596Y1318058D02*
Y1315458D01*
G01X364414Y1312080D02*
X359073D01*
G01X366117Y1316192D02*
X369317D01*
G01X366117Y1309992D02*
Y1316192D01*
G01X369317Y1309992D02*
X366117D01*
G01X369317Y1316192D02*
Y1309992D01*
G01X369407Y1320492D02*
X366207D01*
G01X369407Y1326692D02*
Y1320492D01*
G01X366207D02*
Y1326692D01*
G01X359596Y1339080D02*
Y1336889D01*
G01X358863Y1339080D02*
X359596D01*
G01X365303Y1339775D02*
X368503D01*
G01X365303Y1333575D02*
Y1339775D01*
G01X368503Y1333575D02*
X365303D01*
G01X368503Y1339775D02*
Y1333575D01*
G01X369274Y1334983D02*
X372474D01*
G01X369274Y1328783D02*
Y1334983D01*
G01X372474Y1328783D02*
X369274D01*
G01X362205Y1330717D02*
X365405D01*
G01X362205Y1324517D02*
Y1330717D01*
G01X365405Y1324517D02*
X362205D01*
G01X365405Y1330717D02*
Y1324517D01*
G01X366207Y1326692D02*
X369407D01*
G01X355184Y1348493D02*
X358384D01*
G01X355184Y1342293D02*
Y1348493D01*
G01X358384Y1342293D02*
X355184D01*
G01X358384Y1348493D02*
Y1342293D01*
G01X361030Y1422705D02*
Y1425805D01*
X361950D01*
X362257Y1425650D01*
X362487Y1425288D01*
X362564Y1424875D01*
X362487Y1424462D01*
X362295Y1424152D01*
X361950Y1423997D01*
X361030D01*
G01X364130Y1425805D02*
Y1422705D01*
X365664D01*
G01X367154Y1423325D02*
X367384Y1422963D01*
X367690Y1422757D01*
X368035Y1422705D01*
X368342Y1422757D01*
X368649Y1423015D01*
X368840Y1423325D01*
X368879Y1423635D01*
X368802Y1423997D01*
X368534Y1424255D01*
X368265Y1424358D01*
X367920D01*
G01X368265D02*
X368495Y1424513D01*
X368687Y1424772D01*
X368764Y1425082D01*
X368687Y1425392D01*
X368495Y1425650D01*
X368150Y1425805D01*
X367805Y1425753D01*
X367460Y1425547D01*
G01X370369Y1425288D02*
X370599Y1425598D01*
X370867Y1425753D01*
X371174Y1425805D01*
X371557Y1425702D01*
X371825Y1425443D01*
X371902Y1425133D01*
X371864Y1424823D01*
X371710Y1424565D01*
X370944Y1424048D01*
X370599Y1423687D01*
X370369Y1423170D01*
X370292Y1422705D01*
X371902D01*
G01X375221Y1625535D02*
X366559D01*
G01Y1632682D02*
Y1636029D01*
G01X368759Y1630782D02*
X366559Y1632682D01*
G01Y1628882D02*
X368759Y1630782D01*
G01X366559Y1625535D02*
Y1628882D01*
G01X360820Y1641932D02*
X360513Y1641984D01*
X360245Y1642190D01*
X360015Y1642500D01*
X359862Y1642862D01*
X359785Y1643275D01*
Y1643689D01*
X359862Y1644102D01*
X360015Y1644464D01*
X360245Y1644774D01*
X360513Y1644980D01*
X360820Y1645032D01*
X361127Y1644980D01*
X361395Y1644774D01*
X361625Y1644464D01*
X361778Y1644102D01*
X361855Y1643689D01*
Y1643275D01*
X361778Y1642862D01*
X361625Y1642500D01*
X361395Y1642190D01*
X361127Y1641984D01*
X360820Y1641932D01*
G01X361127Y1642759D02*
X361587Y1641932D01*
G01X363920D02*
Y1645032D01*
X363460Y1644412D01*
G01Y1641932D02*
X364380D01*
G01X367020Y1645032D02*
X366713Y1644929D01*
X366483Y1644670D01*
X366330Y1644360D01*
X366215Y1643947D01*
X366177Y1643482D01*
X366215Y1643017D01*
X366330Y1642604D01*
X366483Y1642294D01*
X366713Y1642035D01*
X367020Y1641932D01*
X367327Y1642035D01*
X367557Y1642294D01*
X367710Y1642604D01*
X367825Y1643017D01*
X367863Y1643482D01*
X367825Y1643947D01*
X367710Y1644360D01*
X367557Y1644670D01*
X367327Y1644929D01*
X367020Y1645032D01*
G01X370120Y1641932D02*
X370388Y1641984D01*
X370695Y1642139D01*
X370887Y1642397D01*
X370963Y1642759D01*
X370887Y1643120D01*
X370657Y1643430D01*
X370312Y1643585D01*
X369928D01*
X369698Y1643689D01*
X369507Y1643947D01*
X369430Y1644309D01*
X369545Y1644670D01*
X369813Y1644929D01*
X370120Y1645032D01*
X370427Y1644929D01*
X370695Y1644670D01*
X370810Y1644309D01*
X370733Y1643947D01*
X370542Y1643689D01*
X370312Y1643585D01*
X369928D01*
X369583Y1643430D01*
X369353Y1643120D01*
X369277Y1642759D01*
X369353Y1642397D01*
X369545Y1642139D01*
X369852Y1641984D01*
X370120Y1641932D01*
G01X366559Y1636029D02*
X375221D01*
G01X359449Y1657834D02*
Y1769645D01*
G01X369087Y1670099D02*
X361587D01*
Y1672339D01*
X361962Y1673086D01*
X362837Y1673646D01*
X363837Y1673833D01*
X364837Y1673646D01*
X365587Y1673179D01*
X365962Y1672339D01*
Y1670099D01*
G01X369087Y1677599D02*
X361587D01*
Y1679933D01*
X361962Y1680679D01*
X362462Y1681146D01*
X363462Y1681333D01*
X364462Y1681146D01*
X365087Y1680586D01*
X365462Y1679933D01*
Y1677599D01*
G01Y1679933D02*
X369087Y1681333D01*
G01Y1688833D02*
Y1685099D01*
X361587D01*
Y1688833D01*
G01X365212Y1687339D02*
Y1685099D01*
G01X368087Y1692506D02*
X368712Y1693253D01*
X369087Y1694093D01*
Y1694839D01*
X368712Y1695586D01*
X368087Y1696146D01*
X367212Y1696426D01*
X366337Y1696239D01*
X365587Y1695773D01*
X365087Y1694933D01*
X364837Y1693813D01*
X364337Y1693159D01*
X363462Y1692879D01*
X362587Y1693066D01*
X361962Y1693533D01*
X361587Y1694186D01*
Y1694839D01*
X361837Y1695493D01*
X362462Y1696053D01*
G01X368087Y1700006D02*
X368712Y1700753D01*
X369087Y1701593D01*
Y1702339D01*
X368712Y1703086D01*
X368087Y1703646D01*
X367212Y1703926D01*
X366337Y1703739D01*
X365587Y1703273D01*
X365087Y1702433D01*
X364837Y1701313D01*
X364337Y1700659D01*
X363462Y1700379D01*
X362587Y1700566D01*
X361962Y1701033D01*
X361587Y1701686D01*
Y1702339D01*
X361837Y1702993D01*
X362462Y1703553D01*
G01X366587Y1708253D02*
Y1710679D01*
G01X369087Y1715193D02*
X361587D01*
Y1718739D01*
G01X365212Y1717433D02*
Y1715193D01*
G01X361587Y1723346D02*
Y1725586D01*
G01Y1724466D02*
X369087D01*
G01Y1723346D02*
Y1725586D01*
G01X361587Y1731966D02*
X369087D01*
G01X361587Y1729819D02*
Y1734113D01*
G01X384060Y118222D02*
Y121422D01*
G01X390260Y118222D02*
X384060D01*
G01Y121422D02*
X390260D01*
G01X374620Y126852D02*
Y130052D01*
G01X380820Y126852D02*
X374620D01*
G01X380820Y130052D02*
Y126852D01*
G01X374620Y130052D02*
X380820D01*
G01X374640Y122712D02*
Y125912D01*
G01X380840Y122712D02*
X374640D01*
G01X380840Y125912D02*
Y122712D01*
G01X374640Y125912D02*
X380840D01*
G01X384060Y122722D02*
Y125922D01*
G01X390260Y122722D02*
X384060D01*
G01Y125922D02*
X390260D01*
G01X383975Y126891D02*
Y130091D01*
G01X390175Y126891D02*
X383975D01*
G01Y130091D02*
X390175D01*
G01X384060Y134422D02*
X390260D01*
G01X384060Y131222D02*
Y134422D01*
G01X390260Y131222D02*
X384060D01*
G01X374897Y227504D02*
Y215023D01*
G01X383320Y218962D02*
Y215762D01*
G01X377120D02*
Y218962D01*
G01X383320Y215762D02*
X377120D01*
G01X383320Y210462D02*
Y207262D01*
G01X377120Y210462D02*
X383320D01*
G01X377120Y207262D02*
Y210462D01*
G01X383320Y207262D02*
X377120D01*
G01X383320Y214462D02*
Y211262D01*
G01X377120Y214462D02*
X383320D01*
G01X377120Y211262D02*
Y214462D01*
G01X383320Y211262D02*
X377120D01*
G01Y218962D02*
X383320D01*
G01Y222962D02*
Y219762D01*
G01X377120Y222962D02*
X383320D01*
G01X377120Y219762D02*
Y222962D01*
G01X383320Y219762D02*
X377120D01*
G01X383320Y226962D02*
Y223762D01*
G01X377120Y226962D02*
X383320D01*
G01X377120Y223762D02*
Y226962D01*
G01X383320Y223762D02*
X377120D01*
G01X378260Y259571D02*
X381460D01*
G01X378260Y253371D02*
Y259571D01*
G01X381460Y253371D02*
X378260D01*
G01X381460Y259571D02*
Y253371D01*
G01X372794Y280585D02*
Y276785D01*
G01X373294Y280585D02*
Y276785D01*
G01X373794Y280585D02*
Y276785D01*
G01X378254D02*
Y280535D01*
G01X385394Y276785D02*
X378254D01*
G01X385394Y280585D02*
Y276785D01*
G01X378304Y280585D02*
X385394D01*
G01X385894Y276785D02*
X378704D01*
G01X385894Y280585D02*
Y276785D01*
G01X378704Y280585D02*
X385894D01*
G01X386394Y276785D02*
X379304D01*
G01X386394Y280585D02*
Y276785D01*
G01X379304Y280585D02*
X386394D01*
G01X377512Y297461D02*
X380712D01*
G01X377512Y291261D02*
Y297461D01*
G01X380712Y291261D02*
X377512D01*
G01X380712Y297461D02*
Y291261D01*
G01X372064Y313234D02*
Y309434D01*
G01X372564Y313234D02*
Y309434D01*
G01X373064Y313234D02*
Y309434D01*
G01X377524D02*
Y313184D01*
G01X384664Y309434D02*
X377524D01*
G01X384664Y313234D02*
Y309434D01*
G01X377574Y313234D02*
X384664D01*
G01X385164Y309434D02*
X377974D01*
G01X385164Y313234D02*
Y309434D01*
G01X377974Y313234D02*
X385164D01*
G01X385664Y309434D02*
X378574D01*
G01X385664Y313234D02*
Y309434D01*
G01X378574Y313234D02*
X385664D01*
G01X386973Y316871D02*
Y325533D01*
G01X397467Y316871D02*
X386973D01*
G01Y325533D02*
X390320D01*
G01X375675Y371115D02*
Y361667D01*
G01X372257Y371115D02*
X375675D01*
G01Y383373D02*
Y373925D01*
G01X375666Y396368D02*
Y387706D01*
G01X372319Y396368D02*
X375666D01*
G01X372257Y383373D02*
X375675D01*
G01Y398857D02*
X372257D01*
G01X375675Y408305D02*
Y398857D01*
G01X402661Y1242785D02*
G03I-10827J0D01*
G01X372038Y1302032D02*
Y1304632D01*
G01X372831Y1302032D02*
X372038D01*
G01Y1311243D02*
Y1312941D01*
G01X371690Y1337335D02*
Y1340435D01*
X372610D01*
X372917Y1340280D01*
X373147Y1339918D01*
X373224Y1339505D01*
X373147Y1339092D01*
X372955Y1338782D01*
X372610Y1338627D01*
X371690D01*
G01X374714Y1340435D02*
Y1338213D01*
X374867Y1337748D01*
X375174Y1337438D01*
X375557Y1337335D01*
X375940Y1337438D01*
X376247Y1337748D01*
X376400Y1338213D01*
Y1340435D01*
G01X377814Y1337955D02*
X378044Y1337593D01*
X378350Y1337387D01*
X378695Y1337335D01*
X379002Y1337387D01*
X379309Y1337645D01*
X379500Y1337955D01*
X379539Y1338265D01*
X379462Y1338627D01*
X379194Y1338885D01*
X378925Y1338988D01*
X378580D01*
G01X378925D02*
X379155Y1339143D01*
X379347Y1339402D01*
X379424Y1339712D01*
X379347Y1340022D01*
X379155Y1340280D01*
X378810Y1340435D01*
X378465Y1340383D01*
X378120Y1340177D01*
G01X381757Y1337335D02*
Y1340435D01*
X381297Y1339815D01*
G01Y1337335D02*
X382217D01*
G01X383707Y1336302D02*
X386007D01*
G01X387190Y1337335D02*
Y1340435D01*
X388110D01*
X388417Y1340280D01*
X388647Y1339918D01*
X388724Y1339505D01*
X388647Y1339092D01*
X388455Y1338782D01*
X388110Y1338627D01*
X387190D01*
G01X391057Y1337335D02*
Y1340435D01*
X390597Y1339815D01*
G01Y1337335D02*
X391517D01*
G01X393007Y1336302D02*
X395307D01*
G01X397257Y1337335D02*
Y1340435D01*
X396797Y1339815D01*
G01Y1337335D02*
X397717D01*
G01X372038Y1325654D02*
X373046D01*
G01X372038Y1323800D02*
Y1325654D01*
G01X372474Y1334983D02*
Y1328783D01*
G01X373697Y1332495D02*
Y1335695D01*
G01X379897Y1332495D02*
X373697D01*
G01X379897Y1335695D02*
Y1332495D01*
G01X373697Y1335695D02*
X379897D01*
G01X387604Y1328318D02*
X384404D01*
G01Y1334518D02*
X387604D01*
G01X384404Y1328318D02*
Y1334518D01*
G01X401531Y1354446D02*
G03I-13386J0D01*
G01X382414Y1375253D02*
Y1414623D01*
G01X375875Y1375253D02*
X382414D01*
G01X384197Y1400285D02*
X387397D01*
G01X384197Y1394085D02*
Y1400285D01*
G01X387397Y1394085D02*
X384197D01*
G01X382414Y1414623D02*
X375875D01*
G01X371900Y1621419D02*
X371593Y1621471D01*
X371325Y1621677D01*
X371095Y1621987D01*
X370942Y1622349D01*
X370865Y1622762D01*
Y1623176D01*
X370942Y1623589D01*
X371095Y1623951D01*
X371325Y1624261D01*
X371593Y1624467D01*
X371900Y1624519D01*
X372207Y1624467D01*
X372475Y1624261D01*
X372705Y1623951D01*
X372858Y1623589D01*
X372935Y1623176D01*
Y1622762D01*
X372858Y1622349D01*
X372705Y1621987D01*
X372475Y1621677D01*
X372207Y1621471D01*
X371900Y1621419D01*
G01X372207Y1622246D02*
X372667Y1621419D01*
G01X375000D02*
Y1624519D01*
X374540Y1623899D01*
G01Y1621419D02*
X375460D01*
G01X378560D02*
Y1624519D01*
X377142Y1622297D01*
X379058D01*
G01X381200Y1621419D02*
X381468Y1621471D01*
X381775Y1621626D01*
X381967Y1621884D01*
X382043Y1622246D01*
X381967Y1622607D01*
X381737Y1622917D01*
X381392Y1623072D01*
X381008D01*
X380778Y1623176D01*
X380587Y1623434D01*
X380510Y1623796D01*
X380625Y1624157D01*
X380893Y1624416D01*
X381200Y1624519D01*
X381507Y1624416D01*
X381775Y1624157D01*
X381890Y1623796D01*
X381813Y1623434D01*
X381622Y1623176D01*
X381392Y1623072D01*
X381008D01*
X380663Y1622917D01*
X380433Y1622607D01*
X380357Y1622246D01*
X380433Y1621884D01*
X380625Y1621626D01*
X380932Y1621471D01*
X381200Y1621419D01*
G01X375221Y1636029D02*
Y1625535D01*
G01X383523Y1629859D02*
Y1636059D01*
G01X386723Y1629859D02*
X383523D01*
G01X386723Y1636059D02*
Y1629859D01*
G01X376897Y1629795D02*
Y1635995D01*
G01X380097Y1629795D02*
X376897D01*
G01X380097Y1635995D02*
Y1629795D01*
G01X383250Y1625462D02*
Y1628662D01*
G01X389450Y1625462D02*
X383250D01*
G01Y1628662D02*
X389450D01*
G01X383240Y1624322D02*
X389440D01*
G01X383240Y1621122D02*
Y1624322D01*
G01X389440Y1621122D02*
X383240D01*
G01X371260Y1781456D02*
Y1646023D01*
G01X386723Y1641649D02*
X383523D01*
G01X386723Y1647849D02*
Y1641649D01*
G01X383523Y1647849D02*
X386723D01*
G01X383523Y1641649D02*
Y1647849D01*
G01Y1636059D02*
X386723D01*
G01X380147Y1641655D02*
X376947D01*
G01X380147Y1647855D02*
Y1641655D01*
G01X376947Y1647855D02*
X380147D01*
G01X376947Y1641655D02*
Y1647855D01*
G01X376897Y1635995D02*
X380097D01*
G01X372900Y1647522D02*
X376100D01*
G01X372900Y1641322D02*
Y1647522D01*
G01X376100Y1641322D02*
X372900D01*
G01X376100Y1647522D02*
Y1641322D01*
G01X373778Y1663337D02*
Y1673831D01*
G01X382440Y1663337D02*
X373778D01*
G01X382440Y1666684D02*
Y1663337D01*
G01X375991Y1649351D02*
X372791D01*
G01X375991Y1655551D02*
Y1649351D01*
G01X372791Y1655551D02*
X375991D01*
G01X372791Y1649351D02*
Y1655551D01*
G01X384481Y1654063D02*
X404167D01*
G01X384481Y1681211D02*
Y1654063D01*
G01X373778Y1673831D02*
X382440D01*
G01X380240Y1668584D02*
X382440Y1666684D01*
G01Y1670484D02*
X380240Y1668584D01*
G01X382440Y1673831D02*
Y1670484D01*
G01X376909Y1681059D02*
Y1687259D01*
G01X380109Y1681059D02*
X376909D01*
G01X380109Y1687259D02*
Y1681059D01*
G01X376109D02*
X372909D01*
G01X376109Y1687259D02*
Y1681059D01*
G01X372909D02*
Y1687259D01*
G01X404167Y1681211D02*
X384481D01*
G01X376909Y1687259D02*
X380109D01*
G01X372909D02*
X376109D01*
G01X376275Y1732048D02*
Y1735148D01*
G01X377885D02*
Y1732048D01*
G01Y1733598D02*
X376275D01*
G01X379528Y1732410D02*
X379797Y1732151D01*
X380103Y1732048D01*
X380410Y1732151D01*
X380678Y1732461D01*
X380870Y1732926D01*
X380947Y1733391D01*
Y1733960D01*
X380870Y1734425D01*
X380678Y1734838D01*
X380448Y1735045D01*
X380180Y1735148D01*
X379873Y1735045D01*
X379643Y1734838D01*
X379490Y1734528D01*
X379413Y1734115D01*
X379490Y1733753D01*
X379682Y1733391D01*
X379912Y1733185D01*
X380180Y1733133D01*
X380487Y1733236D01*
X380717Y1733495D01*
X380947Y1733960D01*
G01X382552Y1734631D02*
X382782Y1734941D01*
X383050Y1735096D01*
X383357Y1735148D01*
X383740Y1735045D01*
X384008Y1734786D01*
X384085Y1734476D01*
X384047Y1734166D01*
X383893Y1733908D01*
X383127Y1733391D01*
X382782Y1733030D01*
X382552Y1732513D01*
X382475Y1732048D01*
X384085D01*
G01X402897Y115934D02*
Y113712D01*
X403050Y113247D01*
X403357Y112937D01*
X403740Y112834D01*
X404123Y112937D01*
X404430Y113247D01*
X404583Y113712D01*
Y115934D01*
G01X406112Y115417D02*
X406342Y115727D01*
X406610Y115882D01*
X406917Y115934D01*
X407300Y115831D01*
X407568Y115572D01*
X407645Y115262D01*
X407607Y114952D01*
X407453Y114694D01*
X406687Y114177D01*
X406342Y113816D01*
X406112Y113299D01*
X406035Y112834D01*
X407645D01*
G01X409097Y113454D02*
X409327Y113092D01*
X409633Y112886D01*
X409978Y112834D01*
X410285Y112886D01*
X410592Y113144D01*
X410783Y113454D01*
X410822Y113764D01*
X410745Y114126D01*
X410477Y114384D01*
X410208Y114487D01*
X409863D01*
G01X410208D02*
X410438Y114642D01*
X410630Y114901D01*
X410707Y115211D01*
X410630Y115521D01*
X410438Y115779D01*
X410093Y115934D01*
X409748Y115882D01*
X409403Y115676D01*
G01X412197Y113299D02*
X412427Y113041D01*
X412695Y112886D01*
X413040Y112834D01*
X413385Y112937D01*
X413653Y113144D01*
X413845Y113506D01*
X413883Y113919D01*
X413807Y114332D01*
X413615Y114591D01*
X413347Y114797D01*
X413078Y114849D01*
X412810Y114797D01*
X412465Y114591D01*
X412580Y115934D01*
X413615D01*
G01X403118Y118825D02*
Y131029D01*
G01X405880Y118825D02*
X403118D01*
G01X390260Y121422D02*
Y118222D01*
G01X403118Y131029D02*
X414642D01*
G01X390260Y125922D02*
Y122722D01*
G01X390175Y130091D02*
Y126891D01*
G01X390260Y134422D02*
Y131222D01*
G01X391807Y167259D02*
Y165037D01*
X391960Y164572D01*
X392267Y164262D01*
X392650Y164159D01*
X393033Y164262D01*
X393340Y164572D01*
X393493Y165037D01*
Y167259D01*
G01X395022Y166742D02*
X395252Y167052D01*
X395520Y167207D01*
X395827Y167259D01*
X396210Y167156D01*
X396478Y166897D01*
X396555Y166587D01*
X396517Y166277D01*
X396363Y166019D01*
X395597Y165502D01*
X395252Y165141D01*
X395022Y164624D01*
X394945Y164159D01*
X396555D01*
G01X398850Y167259D02*
X398543Y167156D01*
X398313Y166897D01*
X398160Y166587D01*
X398045Y166174D01*
X398007Y165709D01*
X398045Y165244D01*
X398160Y164831D01*
X398313Y164521D01*
X398543Y164262D01*
X398850Y164159D01*
X399157Y164262D01*
X399387Y164521D01*
X399540Y164831D01*
X399655Y165244D01*
X399693Y165709D01*
X399655Y166174D01*
X399540Y166587D01*
X399387Y166897D01*
X399157Y167156D01*
X398850Y167259D01*
G01X401873Y164159D02*
X401950Y164831D01*
X402065Y165399D01*
X402218Y165916D01*
X402410Y166484D01*
X402717Y167259D01*
X401183D01*
G01X391823Y153963D02*
Y162821D01*
G01X405177Y153963D02*
X391823D01*
G01Y162821D02*
X405177D01*
G01X397015Y207576D02*
Y227676D01*
G01X412815Y207576D02*
X397015D01*
G01X393722Y236756D02*
Y234534D01*
X393875Y234069D01*
X394182Y233759D01*
X394565Y233656D01*
X394948Y233759D01*
X395255Y234069D01*
X395408Y234534D01*
Y236756D01*
G01X397665Y233656D02*
X397933Y233708D01*
X398240Y233863D01*
X398432Y234121D01*
X398508Y234483D01*
X398432Y234844D01*
X398202Y235154D01*
X397857Y235309D01*
X397473D01*
X397243Y235413D01*
X397052Y235671D01*
X396975Y236033D01*
X397090Y236394D01*
X397358Y236653D01*
X397665Y236756D01*
X397972Y236653D01*
X398240Y236394D01*
X398355Y236033D01*
X398278Y235671D01*
X398087Y235413D01*
X397857Y235309D01*
X397473D01*
X397128Y235154D01*
X396898Y234844D01*
X396822Y234483D01*
X396898Y234121D01*
X397090Y233863D01*
X397397Y233708D01*
X397665Y233656D01*
G01X399922Y234121D02*
X400152Y233863D01*
X400420Y233708D01*
X400765Y233656D01*
X401110Y233759D01*
X401378Y233966D01*
X401570Y234328D01*
X401608Y234741D01*
X401532Y235154D01*
X401340Y235413D01*
X401072Y235619D01*
X400803Y235671D01*
X400535Y235619D01*
X400190Y235413D01*
X400305Y236756D01*
X401340D01*
G01X397222Y232226D02*
Y230004D01*
X397375Y229539D01*
X397682Y229229D01*
X398065Y229126D01*
X398448Y229229D01*
X398755Y229539D01*
X398908Y230004D01*
Y232226D01*
G01X401165Y229126D02*
X401433Y229178D01*
X401740Y229333D01*
X401932Y229591D01*
X402008Y229953D01*
X401932Y230314D01*
X401702Y230624D01*
X401357Y230779D01*
X400973D01*
X400743Y230883D01*
X400552Y231141D01*
X400475Y231503D01*
X400590Y231864D01*
X400858Y232123D01*
X401165Y232226D01*
X401472Y232123D01*
X401740Y231864D01*
X401855Y231503D01*
X401778Y231141D01*
X401587Y230883D01*
X401357Y230779D01*
X400973D01*
X400628Y230624D01*
X400398Y230314D01*
X400322Y229953D01*
X400398Y229591D01*
X400590Y229333D01*
X400897Y229178D01*
X401165Y229126D01*
G01X403537Y230418D02*
X403805Y230779D01*
X404035Y230986D01*
X404342Y231089D01*
X404610Y230986D01*
X404802Y230779D01*
X404955Y230469D01*
X404993Y230108D01*
X404955Y229798D01*
X404802Y229488D01*
X404572Y229229D01*
X404303Y229126D01*
X403997Y229229D01*
X403728Y229539D01*
X403575Y230004D01*
X403537Y230521D01*
X403613Y231193D01*
X403728Y231554D01*
X403920Y231916D01*
X404188Y232174D01*
X404457Y232226D01*
X404725Y232123D01*
X404917Y231864D01*
G01X402665Y227676D02*
X404915Y225426D01*
G01X397015Y227676D02*
X402665D01*
G01X391016Y259561D02*
X394216D01*
G01X391016Y253361D02*
Y259561D01*
G01X394216Y253361D02*
X391016D01*
G01X394216Y259561D02*
Y253361D01*
G01X390854Y276785D02*
Y280535D01*
G01X397994Y276785D02*
X390854D01*
G01X397994Y280585D02*
Y276785D01*
G01X390904Y280585D02*
X397994D01*
G01X398494Y276785D02*
X391304D01*
G01X398494Y280585D02*
Y276785D01*
G01X391304Y280585D02*
X398494D01*
G01X398994Y276785D02*
X391904D01*
G01X398994Y280585D02*
Y276785D01*
G01X391904Y280585D02*
X398994D01*
G01X402615Y298215D02*
X405815D01*
G01X402615Y292015D02*
Y298215D01*
G01X405815Y292015D02*
X402615D01*
G01X390483Y298029D02*
X393683D01*
G01X390483Y291829D02*
Y298029D01*
G01X393683Y291829D02*
X390483D01*
G01X393683Y298029D02*
Y291829D01*
G01X390124Y309434D02*
Y313184D01*
G01X397264Y309434D02*
X390124D01*
G01X397264Y313234D02*
Y309434D01*
G01X390174Y313234D02*
X397264D01*
G01X397764Y309434D02*
X390574D01*
G01X397764Y313234D02*
Y309434D01*
G01X390574Y313234D02*
X397764D01*
G01X398264Y309434D02*
X391174D01*
G01X398264Y313234D02*
Y309434D01*
G01X391174Y313234D02*
X398264D01*
G01X402724Y309434D02*
Y313184D01*
G01X409864Y309434D02*
X402724D01*
G01X402774Y313234D02*
X409864D01*
G01X410364Y309434D02*
X403174D01*
G01Y313234D02*
X410364D01*
G01X391500Y327702D02*
X391287Y327744D01*
X391100Y327910D01*
X390940Y328160D01*
X390833Y328452D01*
X390780Y328785D01*
Y329119D01*
X390833Y329452D01*
X390940Y329744D01*
X391100Y329994D01*
X391287Y330160D01*
X391500Y330202D01*
X391713Y330160D01*
X391900Y329994D01*
X392060Y329744D01*
X392167Y329452D01*
X392220Y329119D01*
Y328785D01*
X392167Y328452D01*
X392060Y328160D01*
X391900Y327910D01*
X391713Y327744D01*
X391500Y327702D01*
G01X391713Y328369D02*
X392033Y327702D01*
G01X393700D02*
X393887Y327744D01*
X394100Y327869D01*
X394233Y328077D01*
X394287Y328369D01*
X394233Y328660D01*
X394073Y328910D01*
X393833Y329035D01*
X393567D01*
X393407Y329119D01*
X393273Y329327D01*
X393220Y329619D01*
X393300Y329910D01*
X393487Y330119D01*
X393700Y330202D01*
X393913Y330119D01*
X394100Y329910D01*
X394180Y329619D01*
X394127Y329327D01*
X393993Y329119D01*
X393833Y329035D01*
X393567D01*
X393327Y328910D01*
X393167Y328660D01*
X393113Y328369D01*
X393167Y328077D01*
X393300Y327869D01*
X393513Y327744D01*
X393700Y327702D01*
G01X395313Y328202D02*
X395473Y327910D01*
X395687Y327744D01*
X395927Y327702D01*
X396140Y327744D01*
X396353Y327952D01*
X396487Y328202D01*
X396513Y328452D01*
X396460Y328744D01*
X396273Y328952D01*
X396087Y329035D01*
X395847D01*
G01X396087D02*
X396247Y329160D01*
X396380Y329369D01*
X396433Y329619D01*
X396380Y329869D01*
X396247Y330077D01*
X396007Y330202D01*
X395767Y330160D01*
X395527Y329994D01*
G01X397467Y325533D02*
Y316871D01*
G01X394120Y325533D02*
X397467D01*
G01X392220Y323333D02*
X394120Y325533D01*
G01X390320D02*
X392220Y323333D01*
G01X392188Y361309D02*
Y369971D01*
G01X402682Y361309D02*
X392188D01*
G01X402682Y369971D02*
Y361309D01*
G01X392094Y374108D02*
Y382770D01*
G01X402588Y374108D02*
X392094D01*
G01X402588Y382770D02*
Y374108D01*
G01X399335Y369971D02*
X402682D01*
G01X397435Y367771D02*
X399335Y369971D01*
G01X395535D02*
X397435Y367771D01*
G01X392188Y369971D02*
X395535D01*
G01X392083Y387102D02*
Y395764D01*
G01X402577Y387102D02*
X392083D01*
G01X402577Y395764D02*
Y387102D01*
G01X399230Y395764D02*
X402577D01*
G01X397330Y393564D02*
X399230Y395764D01*
G01X395430D02*
X397330Y393564D01*
G01X392083Y395764D02*
X395430D01*
G01X399241Y382770D02*
X402588D01*
G01X397341Y380570D02*
X399241Y382770D01*
G01X395441D02*
X397341Y380570D01*
G01X392094Y382770D02*
X395441D01*
G01X392142Y399973D02*
Y408635D01*
G01X402636Y399973D02*
X392142D01*
G01X402636Y408635D02*
Y399973D01*
G01X399289Y408635D02*
X402636D01*
G01X397389Y406435D02*
X399289Y408635D01*
G01X395489D02*
X397389Y406435D01*
G01X392142Y408635D02*
X395489D01*
G01X391458Y829802D02*
X409174Y833739D01*
G01X391458Y829803D02*
X409173Y833740D01*
G01X409174Y1148700D02*
X391458Y1152637D01*
G01X409173Y1148701D02*
X391458Y1152638D01*
G01X391834Y1253612D02*
Y1231958D01*
G01X399145Y1255690D02*
Y1298998D01*
G01X404486Y1255690D02*
X399145D01*
G01X396495D02*
Y1298998D01*
G01X391154Y1255690D02*
X396495D01*
G01X391724Y1302032D02*
X390931D01*
G01X391724Y1304632D02*
Y1302032D01*
G01X399145Y1298998D02*
X404486D01*
G01X396495D02*
X391154D01*
G01X391724Y1325654D02*
Y1323463D01*
G01X398335Y1316192D02*
X401535D01*
G01X398335Y1309992D02*
Y1316192D01*
G01X401535Y1309992D02*
X398335D01*
G01X401535Y1316192D02*
Y1309992D01*
G01Y1320492D02*
X398335D01*
G01X401535Y1326692D02*
Y1320492D01*
G01X398335D02*
Y1326692D01*
G01X394333Y1317291D02*
X397533D01*
G01X394333Y1311091D02*
Y1317291D01*
G01X397533Y1311091D02*
X394333D01*
G01X397533Y1317291D02*
Y1311091D01*
G01X390991Y1325654D02*
X391724D01*
G01X401373Y1334953D02*
X404573D01*
G01X401373Y1328753D02*
Y1334953D01*
G01X404573Y1328753D02*
X401373D01*
G01X388429Y1334518D02*
X391629D01*
G01X388429Y1328318D02*
Y1334518D01*
G01X391629Y1328318D02*
X388429D01*
G01X391629Y1334518D02*
Y1328318D01*
G01X394496Y1328542D02*
Y1331742D01*
G01X400696Y1328542D02*
X394496D01*
G01X400696Y1331742D02*
Y1328542D01*
G01X394496Y1331742D02*
X400696D01*
G01X398335Y1326692D02*
X401535D01*
G01X387604Y1334518D02*
Y1328318D01*
G01X388145Y1341060D02*
Y1367832D01*
G01X397360Y1379755D02*
Y1382855D01*
X398280D01*
X398587Y1382700D01*
X398817Y1382338D01*
X398894Y1381925D01*
X398817Y1381512D01*
X398625Y1381202D01*
X398280Y1381047D01*
X397360D01*
G01X400460Y1380375D02*
X400652Y1380065D01*
X400882Y1379858D01*
X401150Y1379755D01*
X401457Y1379858D01*
X401687Y1380065D01*
X401917Y1380375D01*
X401994Y1380788D01*
Y1382855D01*
G01X403484Y1380220D02*
X403714Y1379962D01*
X403982Y1379807D01*
X404327Y1379755D01*
X404672Y1379858D01*
X404940Y1380065D01*
X405132Y1380427D01*
X405170Y1380840D01*
X405094Y1381253D01*
X404902Y1381512D01*
X404634Y1381718D01*
X404365Y1381770D01*
X404097Y1381718D01*
X403752Y1381512D01*
X403867Y1382855D01*
X404902D01*
G01X406699Y1382338D02*
X406929Y1382648D01*
X407197Y1382803D01*
X407504Y1382855D01*
X407887Y1382752D01*
X408155Y1382493D01*
X408232Y1382183D01*
X408194Y1381873D01*
X408040Y1381615D01*
X407274Y1381098D01*
X406929Y1380737D01*
X406699Y1380220D01*
X406622Y1379755D01*
X408232D01*
G01X395519Y1400908D02*
Y1411108D01*
G01X400119Y1400908D02*
X395519D01*
G01X400119Y1411108D02*
Y1400908D01*
G01X392099Y1400938D02*
Y1407138D01*
G01X395299Y1400938D02*
X392099D01*
G01X395299Y1407138D02*
Y1400938D01*
G01X387397Y1400285D02*
Y1394085D01*
G01X400032Y1400253D02*
Y1397053D01*
G01X393832Y1400253D02*
X400032D01*
G01X393832Y1397053D02*
Y1400253D01*
G01X400032Y1397053D02*
X393832D01*
G01X401804Y1402607D02*
Y1405807D01*
G01X408004Y1402607D02*
X401804D01*
G01Y1399084D02*
Y1402284D01*
G01X408004Y1399084D02*
X401804D01*
G01Y1402284D02*
X408004D01*
G01X401731Y1395438D02*
Y1398638D01*
G01X407931Y1395438D02*
X401731D01*
G01Y1398638D02*
X407931D01*
G01X395519Y1411108D02*
X400119D01*
G01Y1406008D02*
X395519D01*
G01X401799Y1412831D02*
X407999D01*
G01X401799Y1409631D02*
Y1412831D01*
G01X407999Y1409631D02*
X401799D01*
G01X392099Y1407138D02*
X395299D01*
G01X401525Y1417903D02*
Y1424103D01*
G01X404725Y1417903D02*
X401525D01*
G01X401799Y1406127D02*
Y1409327D01*
G01X407999Y1406127D02*
X401799D01*
G01Y1409327D02*
X407999D01*
G01X397534Y1417881D02*
Y1424081D01*
G01X400734Y1417881D02*
X397534D01*
G01X400734Y1424081D02*
Y1417881D01*
G01X393225Y1412019D02*
Y1415219D01*
G01X399425Y1412019D02*
X393225D01*
G01X399425Y1415219D02*
Y1412019D01*
G01X393225Y1415219D02*
X399425D01*
G01X401804Y1405807D02*
X408004D01*
G01X401525Y1424103D02*
X404725D01*
G01X394818Y1430971D02*
Y1434171D01*
G01X401018Y1430971D02*
X394818D01*
G01X401018Y1434171D02*
Y1430971D01*
G01X394818Y1434171D02*
X401018D01*
G01X394818Y1425969D02*
Y1429169D01*
G01X401018Y1425969D02*
X394818D01*
G01X401018Y1429169D02*
Y1425969D01*
G01X394818Y1429169D02*
X401018D01*
G01X397534Y1424081D02*
X400734D01*
G01X402950Y1548342D02*
Y1551542D01*
G01X409150Y1548342D02*
X402950D01*
G01X397821Y1539410D02*
X404021D01*
G01X397821Y1536210D02*
Y1539410D01*
G01X404021Y1536210D02*
X397821D01*
G01Y1547410D02*
X404021D01*
G01X397821Y1544210D02*
Y1547410D01*
G01X404021Y1544210D02*
X397821D01*
G01Y1540210D02*
Y1543410D01*
G01X404021Y1540210D02*
X397821D01*
G01Y1543410D02*
X404021D01*
G01X402950Y1551542D02*
X409150D01*
G01X397821Y1562410D02*
X404021D01*
G01X397821Y1559210D02*
Y1562410D01*
G01X404021Y1559210D02*
X397821D01*
G01Y1555210D02*
Y1558410D01*
G01X404021Y1555210D02*
X397821D01*
G01Y1558410D02*
X404021D01*
G01X397821Y1566410D02*
X404021D01*
G01X397821Y1563210D02*
Y1566410D01*
G01X404021Y1563210D02*
X397821D01*
G01X389693Y1629879D02*
Y1636079D01*
G01X392893Y1629879D02*
X389693D01*
G01X392893Y1636079D02*
Y1629879D01*
G01X389450Y1628662D02*
Y1625462D01*
G01X389440Y1624322D02*
Y1621122D01*
G01X393163Y1641119D02*
X389963D01*
G01X393163Y1647319D02*
Y1641119D01*
G01X389963Y1647319D02*
X393163D01*
G01X389963Y1641119D02*
Y1647319D01*
G01X389693Y1636079D02*
X392893D01*
G01X404167Y1661794D02*
X398324Y1667637D01*
G01D02*
X404167Y1673480D01*
G01X414650Y-534979D02*
Y-526979D01*
X413450Y-528579D01*
G01Y-534979D02*
X415850D01*
G01X420750Y-531646D02*
X421450Y-530712D01*
X422050Y-530179D01*
X422850Y-529912D01*
X423550Y-530179D01*
X424050Y-530712D01*
X424450Y-531512D01*
X424550Y-532446D01*
X424450Y-533246D01*
X424050Y-534046D01*
X423450Y-534712D01*
X422750Y-534979D01*
X421950Y-534712D01*
X421250Y-533913D01*
X420850Y-532712D01*
X420750Y-531379D01*
X420950Y-529646D01*
X421250Y-528712D01*
X421750Y-527779D01*
X422450Y-527112D01*
X423150Y-526979D01*
X423850Y-527246D01*
X424350Y-527912D01*
G01X430650Y-535246D02*
X430450Y-535112D01*
Y-534846D01*
X430650Y-534712D01*
X430850Y-534846D01*
Y-535112D01*
X430650Y-535246D01*
G01X436750Y-531646D02*
X437450Y-530712D01*
X438050Y-530179D01*
X438850Y-529912D01*
X439550Y-530179D01*
X440050Y-530712D01*
X440450Y-531512D01*
X440550Y-532446D01*
X440450Y-533246D01*
X440050Y-534046D01*
X439450Y-534712D01*
X438750Y-534979D01*
X437950Y-534712D01*
X437250Y-533913D01*
X436850Y-532712D01*
X436750Y-531379D01*
X436950Y-529646D01*
X437250Y-528712D01*
X437750Y-527779D01*
X438450Y-527112D01*
X439150Y-526979D01*
X439850Y-527246D01*
X440350Y-527912D01*
G01X418237Y65865D02*
Y69065D01*
G01X424437Y65865D02*
X418237D01*
G01Y69065D02*
X424437D01*
G01X418237Y61065D02*
Y64265D01*
G01X424437Y61065D02*
X418237D01*
G01Y64265D02*
X424437D01*
G01X414642Y131029D02*
Y118825D01*
G01X408880Y121927D02*
X405880Y118825D01*
G01X411982D02*
X408880Y121927D01*
G01X414642Y118825D02*
X411982D01*
G01X416097Y147773D02*
Y150973D01*
G01X422297Y147773D02*
X416097D01*
G01Y150973D02*
X422297D01*
G01X416097Y151877D02*
Y155077D01*
G01X422297Y151877D02*
X416097D01*
G01X405177Y162821D02*
Y153963D01*
G01X406759Y159562D02*
Y162762D01*
G01X412959Y159562D02*
X406759D01*
G01X412959Y162762D02*
Y159562D01*
G01X406759Y162762D02*
X412959D01*
G01X416097Y159066D02*
X422297D01*
G01X416097Y155866D02*
Y159066D01*
G01X422297Y155866D02*
X416097D01*
G01Y159866D02*
Y163066D01*
G01X422297Y159866D02*
X416097D01*
G01Y163066D02*
X422297D01*
G01X416097Y155077D02*
X422297D01*
G01X412815Y227676D02*
Y207576D01*
G01X406315Y232326D02*
Y241126D01*
G01X419915Y232326D02*
X406315D01*
G01X407165Y227676D02*
X412815D01*
G01X404915Y225426D02*
X407165Y227676D01*
G01X411883Y246482D02*
X412075Y246172D01*
X412305Y245965D01*
X412573Y245862D01*
X412880Y245965D01*
X413110Y246172D01*
X413340Y246482D01*
X413417Y246895D01*
Y248962D01*
G01X415750D02*
Y245862D01*
G01X414868Y248962D02*
X416632D01*
G01X417892Y245862D02*
X418850Y248962D01*
X419808Y245862D01*
G01X419463Y246947D02*
X418237D01*
G01X422180Y247412D02*
X422947D01*
Y246482D01*
X422717Y246172D01*
X422448Y245965D01*
X422065Y245862D01*
X421682Y245965D01*
X421413Y246172D01*
X421183Y246482D01*
X421030Y246844D01*
X420953Y247257D01*
Y247619D01*
X421030Y247929D01*
X421183Y248290D01*
X421413Y248600D01*
X421643Y248807D01*
X421950Y248962D01*
X422218D01*
X422525Y248859D01*
X422755Y248652D01*
G01X427345Y246275D02*
X427652Y246017D01*
X427997Y245862D01*
X428303D01*
X428610Y246017D01*
X428840Y246275D01*
X428955Y246637D01*
X428878Y246999D01*
X428687Y247309D01*
X428342Y247515D01*
X427882Y247619D01*
X427613Y247825D01*
X427498Y248187D01*
X427575Y248549D01*
X427767Y248807D01*
X428035Y248962D01*
X428303D01*
X428572Y248859D01*
X428802Y248600D01*
G01X430100Y248962D02*
X430637Y245862D01*
X431250Y248962D01*
X431863Y245862D01*
X432400Y248962D01*
G01X433890D02*
X434810D01*
G01X434350D02*
Y245862D01*
G01X433890D02*
X434810D01*
G01X437450Y248962D02*
Y245862D01*
G01X436568Y248962D02*
X438332D01*
G01X441393Y248704D02*
X441163Y248859D01*
X440895Y248962D01*
X440588D01*
X440243Y248807D01*
X439975Y248549D01*
X439783Y248239D01*
X439630Y247722D01*
X439592Y247257D01*
X439668Y246792D01*
X439783Y246482D01*
X440013Y246172D01*
X440282Y245965D01*
X440550Y245862D01*
X440818D01*
X441087Y245965D01*
X441317Y246120D01*
X441508Y246327D01*
G01X442845Y245862D02*
Y248962D01*
G01X444455D02*
Y245862D01*
G01Y247412D02*
X442845D01*
G01X449083Y246482D02*
X449275Y246172D01*
X449505Y245965D01*
X449773Y245862D01*
X450080Y245965D01*
X450310Y246172D01*
X450540Y246482D01*
X450617Y246895D01*
Y248962D01*
G01X452107D02*
Y246740D01*
X452260Y246275D01*
X452567Y245965D01*
X452950Y245862D01*
X453333Y245965D01*
X453640Y246275D01*
X453793Y246740D01*
Y248962D01*
G01X455053Y245862D02*
Y248962D01*
X456050Y246379D01*
X457047Y248962D01*
Y245862D01*
G01X458383D02*
Y248962D01*
X459303D01*
X459610Y248807D01*
X459840Y248445D01*
X459917Y248032D01*
X459840Y247619D01*
X459648Y247309D01*
X459303Y247154D01*
X458383D01*
G01X463017Y245862D02*
X461483D01*
Y248962D01*
X463017D01*
G01X462403Y247464D02*
X461483D01*
G01X464583Y245862D02*
Y248962D01*
X465542D01*
X465848Y248807D01*
X466040Y248600D01*
X466117Y248187D01*
X466040Y247774D01*
X465810Y247515D01*
X465542Y247360D01*
X464583D01*
G01X465542D02*
X466117Y245862D01*
G01X414115Y241126D02*
X413115Y239626D01*
G01X419915Y241126D02*
X414115D01*
G01X413115Y239626D02*
X412115Y241126D01*
G01D02*
X406315D01*
G01X416165Y259880D02*
X419365D01*
G01X416165Y253680D02*
Y259880D01*
G01X419365Y253680D02*
X416165D01*
G01X419365Y259880D02*
Y253680D01*
G01X403385Y259490D02*
X406585D01*
G01X403385Y253290D02*
Y259490D01*
G01X406585Y253290D02*
X403385D01*
G01X406585Y259490D02*
Y253290D01*
G01X403454Y276785D02*
Y280535D01*
G01X410594Y276785D02*
X403454D01*
G01X410594Y280585D02*
Y276785D01*
G01X403504Y280585D02*
X410594D01*
G01X411094Y276785D02*
X403904D01*
G01X411094Y280585D02*
Y276785D01*
G01X403904Y280585D02*
X411094D01*
G01X411594Y276785D02*
X404504D01*
G01X411594Y280585D02*
Y276785D01*
G01X404504Y280585D02*
X411594D01*
G01X416054Y276785D02*
Y280535D01*
G01X423194Y276785D02*
X416054D01*
G01X416104Y280585D02*
X423194D01*
G01X423694Y276785D02*
X416504D01*
G01Y280585D02*
X423694D01*
G01X424194Y276785D02*
X417104D01*
G01Y280585D02*
X424194D01*
G01X415618Y298349D02*
X418818D01*
G01X415618Y292149D02*
Y298349D01*
G01X418818Y292149D02*
X415618D01*
G01X418818Y298349D02*
Y292149D01*
G01X405815Y298215D02*
Y292015D01*
G01X409864Y313234D02*
Y309434D01*
G01X410364Y313234D02*
Y309434D01*
G01X410864D02*
X403774D01*
G01X410864Y313234D02*
Y309434D01*
G01X403774Y313234D02*
X410864D01*
G01X415324Y309434D02*
Y313184D01*
G01X422464Y309434D02*
X415324D01*
G01X415374Y313234D02*
X422464D01*
G01X422964Y309434D02*
X415774D01*
G01Y313234D02*
X422964D01*
G01X423464Y309434D02*
X416374D01*
G01Y313234D02*
X423464D01*
G01X404781Y380056D02*
X404474Y380108D01*
X404206Y380314D01*
X403976Y380624D01*
X403823Y380986D01*
X403746Y381399D01*
Y381813D01*
X403823Y382226D01*
X403976Y382588D01*
X404206Y382898D01*
X404474Y383104D01*
X404781Y383156D01*
X405088Y383104D01*
X405356Y382898D01*
X405586Y382588D01*
X405739Y382226D01*
X405816Y381813D01*
Y381399D01*
X405739Y380986D01*
X405586Y380624D01*
X405356Y380314D01*
X405088Y380108D01*
X404781Y380056D01*
G01X405088Y380883D02*
X405548Y380056D01*
G01X407881D02*
X408149Y380108D01*
X408456Y380263D01*
X408648Y380521D01*
X408724Y380883D01*
X408648Y381244D01*
X408418Y381554D01*
X408073Y381709D01*
X407689D01*
X407459Y381813D01*
X407268Y382071D01*
X407191Y382433D01*
X407306Y382794D01*
X407574Y383053D01*
X407881Y383156D01*
X408188Y383053D01*
X408456Y382794D01*
X408571Y382433D01*
X408494Y382071D01*
X408303Y381813D01*
X408073Y381709D01*
X407689D01*
X407344Y381554D01*
X407114Y381244D01*
X407038Y380883D01*
X407114Y380521D01*
X407306Y380263D01*
X407613Y380108D01*
X407881Y380056D01*
G01X410904D02*
X410981Y380728D01*
X411096Y381296D01*
X411249Y381813D01*
X411441Y382381D01*
X411748Y383156D01*
X410214D01*
G01X404945Y367247D02*
X404638Y367299D01*
X404370Y367505D01*
X404140Y367815D01*
X403987Y368177D01*
X403910Y368590D01*
Y369004D01*
X403987Y369417D01*
X404140Y369779D01*
X404370Y370089D01*
X404638Y370295D01*
X404945Y370347D01*
X405252Y370295D01*
X405520Y370089D01*
X405750Y369779D01*
X405903Y369417D01*
X405980Y369004D01*
Y368590D01*
X405903Y368177D01*
X405750Y367815D01*
X405520Y367505D01*
X405252Y367299D01*
X404945Y367247D01*
G01X405252Y368074D02*
X405712Y367247D01*
G01X407968D02*
X408045Y367919D01*
X408160Y368487D01*
X408313Y369004D01*
X408505Y369572D01*
X408812Y370347D01*
X407278D01*
G01X411145Y367247D02*
X411413Y367299D01*
X411720Y367454D01*
X411912Y367712D01*
X411988Y368074D01*
X411912Y368435D01*
X411682Y368745D01*
X411337Y368900D01*
X410953D01*
X410723Y369004D01*
X410532Y369262D01*
X410455Y369624D01*
X410570Y369985D01*
X410838Y370244D01*
X411145Y370347D01*
X411452Y370244D01*
X411720Y369985D01*
X411835Y369624D01*
X411758Y369262D01*
X411567Y369004D01*
X411337Y368900D01*
X410953D01*
X410608Y368745D01*
X410378Y368435D01*
X410302Y368074D01*
X410378Y367712D01*
X410570Y367454D01*
X410877Y367299D01*
X411145Y367247D01*
G01X404890Y392960D02*
X404583Y393012D01*
X404315Y393218D01*
X404085Y393528D01*
X403932Y393890D01*
X403855Y394303D01*
Y394717D01*
X403932Y395130D01*
X404085Y395492D01*
X404315Y395802D01*
X404583Y396008D01*
X404890Y396060D01*
X405197Y396008D01*
X405465Y395802D01*
X405695Y395492D01*
X405848Y395130D01*
X405925Y394717D01*
Y394303D01*
X405848Y393890D01*
X405695Y393528D01*
X405465Y393218D01*
X405197Y393012D01*
X404890Y392960D01*
G01X405197Y393787D02*
X405657Y392960D01*
G01X407990D02*
X408258Y393012D01*
X408565Y393167D01*
X408757Y393425D01*
X408833Y393787D01*
X408757Y394148D01*
X408527Y394458D01*
X408182Y394613D01*
X407798D01*
X407568Y394717D01*
X407377Y394975D01*
X407300Y395337D01*
X407415Y395698D01*
X407683Y395957D01*
X407990Y396060D01*
X408297Y395957D01*
X408565Y395698D01*
X408680Y395337D01*
X408603Y394975D01*
X408412Y394717D01*
X408182Y394613D01*
X407798D01*
X407453Y394458D01*
X407223Y394148D01*
X407147Y393787D01*
X407223Y393425D01*
X407415Y393167D01*
X407722Y393012D01*
X407990Y392960D01*
G01X411090D02*
X411358Y393012D01*
X411665Y393167D01*
X411857Y393425D01*
X411933Y393787D01*
X411857Y394148D01*
X411627Y394458D01*
X411282Y394613D01*
X410898D01*
X410668Y394717D01*
X410477Y394975D01*
X410400Y395337D01*
X410515Y395698D01*
X410783Y395957D01*
X411090Y396060D01*
X411397Y395957D01*
X411665Y395698D01*
X411780Y395337D01*
X411703Y394975D01*
X411512Y394717D01*
X411282Y394613D01*
X410898D01*
X410553Y394458D01*
X410323Y394148D01*
X410247Y393787D01*
X410323Y393425D01*
X410515Y393167D01*
X410822Y393012D01*
X411090Y392960D01*
G01X405389Y406121D02*
X405082Y406173D01*
X404814Y406379D01*
X404584Y406689D01*
X404431Y407051D01*
X404354Y407464D01*
Y407878D01*
X404431Y408291D01*
X404584Y408653D01*
X404814Y408963D01*
X405082Y409169D01*
X405389Y409221D01*
X405696Y409169D01*
X405964Y408963D01*
X406194Y408653D01*
X406347Y408291D01*
X406424Y407878D01*
Y407464D01*
X406347Y407051D01*
X406194Y406689D01*
X405964Y406379D01*
X405696Y406173D01*
X405389Y406121D01*
G01X405696Y406948D02*
X406156Y406121D01*
G01X408412D02*
X408489Y406793D01*
X408604Y407361D01*
X408757Y407878D01*
X408949Y408446D01*
X409256Y409221D01*
X407722D01*
G01X410937Y406483D02*
X411206Y406224D01*
X411512Y406121D01*
X411819Y406224D01*
X412087Y406534D01*
X412279Y406999D01*
X412356Y407464D01*
Y408033D01*
X412279Y408498D01*
X412087Y408911D01*
X411857Y409118D01*
X411589Y409221D01*
X411282Y409118D01*
X411052Y408911D01*
X410899Y408601D01*
X410822Y408188D01*
X410899Y407826D01*
X411091Y407464D01*
X411321Y407258D01*
X411589Y407206D01*
X411896Y407309D01*
X412126Y407568D01*
X412356Y408033D01*
G01X419270Y417832D02*
X418963Y417884D01*
X418695Y418090D01*
X418465Y418400D01*
X418312Y418762D01*
X418235Y419175D01*
Y419589D01*
X418312Y420002D01*
X418465Y420364D01*
X418695Y420674D01*
X418963Y420880D01*
X419270Y420932D01*
X419577Y420880D01*
X419845Y420674D01*
X420075Y420364D01*
X420228Y420002D01*
X420305Y419589D01*
Y419175D01*
X420228Y418762D01*
X420075Y418400D01*
X419845Y418090D01*
X419577Y417884D01*
X419270Y417832D01*
G01X419577Y418659D02*
X420037Y417832D01*
G01X422293D02*
X422370Y418504D01*
X422485Y419072D01*
X422638Y419589D01*
X422830Y420157D01*
X423137Y420932D01*
X421603D01*
G01X425393Y417832D02*
X425470Y418504D01*
X425585Y419072D01*
X425738Y419589D01*
X425930Y420157D01*
X426237Y420932D01*
X424703D01*
G01X409174Y833739D02*
X430336D01*
G01X409173Y833740D02*
X430335D01*
G01X407521Y1032021D02*
Y931195D01*
G01X425718D02*
X407521D01*
G01X416195Y942873D02*
X412995D01*
G01X416195Y949073D02*
Y942873D01*
G01X412995Y949073D02*
X416195D01*
G01X412995Y942873D02*
Y949073D01*
G01X409195Y949565D02*
Y955765D01*
G01X412395Y949565D02*
X409195D01*
G01X412395Y955765D02*
Y949565D01*
G01X417016Y940748D02*
X420216D01*
G01X417016Y934548D02*
Y940748D01*
G01X420216Y934548D02*
X417016D01*
G01X412995Y949565D02*
Y955765D01*
G01X416195Y949565D02*
X412995D01*
G01X416195Y955765D02*
Y949565D01*
G01X416995Y942873D02*
Y949073D01*
X420195D01*
Y942873D01*
X416995D01*
G01X420195Y955765D02*
Y949565D01*
X416995D01*
Y955765D01*
X420195D01*
G01X412416Y940748D02*
Y934548D01*
X409216D01*
Y940748D01*
X412416D01*
G01X409195Y942873D02*
Y949073D01*
X412395D01*
Y942873D01*
X409195D01*
G01X413016Y934548D02*
Y940748D01*
X416216D01*
Y934548D01*
X413016D01*
G01X409195Y955765D02*
X412395D01*
G01X412995D02*
X416195D01*
G01X416226Y957656D02*
X413026D01*
G01X416226Y963856D02*
Y957656D01*
G01X413026Y963856D02*
X416226D01*
G01X413026Y957656D02*
Y963856D01*
G01X412426Y957656D02*
X409226D01*
G01X412426Y963856D02*
Y957656D01*
G01X409226Y963856D02*
X412426D01*
G01X409226Y957656D02*
Y963856D01*
G01X413026Y963964D02*
Y970164D01*
G01X416226Y963964D02*
X413026D01*
G01X416226Y970164D02*
Y963964D01*
G01X417026Y957656D02*
Y963856D01*
X420226D01*
Y957656D01*
X417026D01*
G01X420226Y970164D02*
Y963964D01*
X417026D01*
Y970164D01*
X420226D01*
G01X412426D02*
Y963964D01*
X409226D01*
Y970164D01*
X412426D01*
G01X413000Y978477D02*
Y984677D01*
G01X416200Y978477D02*
X413000D01*
G01X416200Y984677D02*
Y978477D01*
G01X409200D02*
Y984677D01*
G01X412400Y978477D02*
X409200D01*
G01X412400Y984677D02*
Y978477D01*
G01X420271Y972157D02*
X417071D01*
G01Y978357D02*
X420271D01*
G01X417071Y972157D02*
Y978357D01*
G01X413026Y970164D02*
X416226D01*
G01Y972157D02*
X413026D01*
G01X416226Y978357D02*
Y972157D01*
G01X413026Y978357D02*
X416226D01*
G01X413026Y972157D02*
Y978357D01*
G01X420200Y984677D02*
Y978477D01*
X417000D01*
Y984677D01*
X420200D01*
G01X409271Y972157D02*
Y978357D01*
X412471D01*
Y972157D01*
X409271D01*
G01X413000Y984677D02*
X416200D01*
G01X412400Y986568D02*
X409200D01*
G01X412400Y992768D02*
Y986568D01*
G01X409200Y992768D02*
X412400D01*
G01X409200Y986568D02*
Y992768D01*
G01Y984677D02*
X412400D01*
G01X416200Y986568D02*
X413000D01*
G01X416200Y992768D02*
Y986568D01*
G01X413000Y992768D02*
X416200D01*
G01X413000Y986568D02*
Y992768D01*
G01Y992792D02*
Y998992D01*
G01X416200Y992792D02*
X413000D01*
G01X416200Y998992D02*
Y992792D01*
G01X409200D02*
Y998992D01*
G01X412400Y992792D02*
X409200D01*
G01X412400Y998992D02*
Y992792D01*
G01X417000Y986568D02*
Y992768D01*
X420200D01*
Y986568D01*
X417000D01*
G01X420200Y998992D02*
Y992792D01*
X417000D01*
Y998992D01*
X420200D01*
G01X416950Y1013550D02*
X420150D01*
G01X416950Y1007350D02*
Y1013550D01*
G01X420150Y1007350D02*
X416950D01*
G01X413000Y998992D02*
X416200D01*
G01X409200D02*
X412400D01*
G01X416150Y1001050D02*
X412950D01*
G01X416150Y1007250D02*
Y1001050D01*
G01X412950Y1007250D02*
X416150D01*
G01X412950Y1001050D02*
Y1007250D01*
G01X412438Y1001050D02*
X409238D01*
G01X412438Y1007250D02*
Y1001050D01*
G01X409238Y1007250D02*
X412438D01*
G01X409238Y1001050D02*
Y1007250D01*
G01X412438Y1013550D02*
Y1007350D01*
X409238D01*
Y1013550D01*
X412438D01*
G01X416150D02*
Y1007350D01*
X412950D01*
Y1013550D01*
X416150D01*
G01X416950Y1001050D02*
Y1007250D01*
X420150D01*
Y1001050D01*
X416950D01*
G01X420191Y1015510D02*
X416991D01*
G01Y1021710D02*
X420191D01*
G01X416991Y1015510D02*
Y1021710D01*
G01X412416Y1028160D02*
Y1021960D01*
X409216D01*
Y1028160D01*
X412416D01*
G01X416191D02*
Y1021960D01*
X412991D01*
Y1028160D01*
X416191D01*
G01X420191D02*
Y1021960D01*
X416991D01*
Y1028160D01*
X420191D01*
G01X409216Y1015510D02*
Y1021710D01*
X412416D01*
Y1015510D01*
X409216D01*
G01X412991D02*
Y1021710D01*
X416191D01*
Y1015510D01*
X412991D01*
G01X407521Y1032021D02*
X425718D01*
G01X420930Y1154520D02*
X408930D01*
G01Y1160520D02*
X420930D01*
G01X408930Y1154520D02*
Y1160520D01*
G01X430336Y1148700D02*
X409174D01*
G01X430335Y1148701D02*
X409173D01*
G01X420930Y1162570D02*
X408930D01*
G01Y1168570D02*
X420930D01*
G01X408930Y1162570D02*
Y1168570D01*
G01X416234Y1253612D02*
Y1231958D01*
G01X427061Y1242785D02*
G03I-10827J0D01*
G01X404166Y1302032D02*
Y1304632D01*
G01X404959Y1302032D02*
X404166D01*
G01Y1311243D02*
Y1312941D01*
G01X403880Y1337335D02*
Y1340435D01*
X404800D01*
X405107Y1340280D01*
X405337Y1339918D01*
X405414Y1339505D01*
X405337Y1339092D01*
X405145Y1338782D01*
X404800Y1338627D01*
X403880D01*
G01X406904Y1340435D02*
Y1338213D01*
X407057Y1337748D01*
X407364Y1337438D01*
X407747Y1337335D01*
X408130Y1337438D01*
X408437Y1337748D01*
X408590Y1338213D01*
Y1340435D01*
G01X410004Y1337955D02*
X410234Y1337593D01*
X410540Y1337387D01*
X410885Y1337335D01*
X411192Y1337387D01*
X411499Y1337645D01*
X411690Y1337955D01*
X411729Y1338265D01*
X411652Y1338627D01*
X411384Y1338885D01*
X411115Y1338988D01*
X410770D01*
G01X411115D02*
X411345Y1339143D01*
X411537Y1339402D01*
X411614Y1339712D01*
X411537Y1340022D01*
X411345Y1340280D01*
X411000Y1340435D01*
X410655Y1340383D01*
X410310Y1340177D01*
G01X413947Y1340435D02*
X413640Y1340332D01*
X413410Y1340073D01*
X413257Y1339763D01*
X413142Y1339350D01*
X413104Y1338885D01*
X413142Y1338420D01*
X413257Y1338007D01*
X413410Y1337697D01*
X413640Y1337438D01*
X413947Y1337335D01*
X414254Y1337438D01*
X414484Y1337697D01*
X414637Y1338007D01*
X414752Y1338420D01*
X414790Y1338885D01*
X414752Y1339350D01*
X414637Y1339763D01*
X414484Y1340073D01*
X414254Y1340332D01*
X413947Y1340435D01*
G01X415897Y1336302D02*
X418197D01*
G01X419380Y1337335D02*
Y1340435D01*
X420300D01*
X420607Y1340280D01*
X420837Y1339918D01*
X420914Y1339505D01*
X420837Y1339092D01*
X420645Y1338782D01*
X420300Y1338627D01*
X419380D01*
G01X423247Y1337335D02*
Y1340435D01*
X422787Y1339815D01*
G01Y1337335D02*
X423707D01*
G01X425197Y1336302D02*
X427497D01*
G01X428719Y1339918D02*
X428949Y1340228D01*
X429217Y1340383D01*
X429524Y1340435D01*
X429907Y1340332D01*
X430175Y1340073D01*
X430252Y1339763D01*
X430214Y1339453D01*
X430060Y1339195D01*
X429294Y1338678D01*
X428949Y1338317D01*
X428719Y1337800D01*
X428642Y1337335D01*
X430252D01*
G01X404166Y1325654D02*
X405174D01*
G01X404166Y1323800D02*
Y1325654D01*
G01X404573Y1334953D02*
Y1328753D01*
G01X407443Y1332495D02*
Y1335695D01*
G01X413643Y1332495D02*
X407443D01*
G01X413643Y1335695D02*
Y1332495D01*
G01X407443Y1335695D02*
X413643D01*
G01X418704Y1328318D02*
X415504D01*
G01X418704Y1334518D02*
Y1328318D01*
G01X415504Y1334518D02*
X418704D01*
G01X415504Y1328318D02*
Y1334518D01*
G01X417911Y1341060D02*
Y1367832D01*
G01X431297Y1354446D02*
G03I-13386J0D01*
G01X413877Y1388706D02*
Y1391906D01*
G01X420077Y1388706D02*
X413877D01*
G01X407215Y1388725D02*
Y1391925D01*
G01X413415Y1388725D02*
X407215D01*
G01X413415Y1391925D02*
Y1388725D01*
G01X408662Y1402923D02*
X408892Y1403233D01*
X409160Y1403388D01*
X409467Y1403440D01*
X409850Y1403337D01*
X410118Y1403078D01*
X410195Y1402768D01*
X410157Y1402458D01*
X410003Y1402200D01*
X409237Y1401683D01*
X408892Y1401322D01*
X408662Y1400805D01*
X408585Y1400340D01*
X410195D01*
G01X412950D02*
Y1403440D01*
X411532Y1401218D01*
X413448D01*
G01X412352Y1399153D02*
X412582Y1399463D01*
X412850Y1399618D01*
X413157Y1399670D01*
X413540Y1399567D01*
X413808Y1399308D01*
X413885Y1398998D01*
X413847Y1398688D01*
X413693Y1398430D01*
X412927Y1397913D01*
X412582Y1397552D01*
X412352Y1397035D01*
X412275Y1396570D01*
X413885D01*
G01X415337Y1397035D02*
X415567Y1396777D01*
X415835Y1396622D01*
X416180Y1396570D01*
X416525Y1396673D01*
X416793Y1396880D01*
X416985Y1397242D01*
X417023Y1397655D01*
X416947Y1398068D01*
X416755Y1398327D01*
X416487Y1398533D01*
X416218Y1398585D01*
X415950Y1398533D01*
X415605Y1398327D01*
X415720Y1399670D01*
X416755D01*
G01X418813Y1399489D02*
Y1397489D01*
G01X417667Y1400978D02*
X415663D01*
G01D02*
Y1403064D01*
G01X413877Y1391906D02*
X420077D01*
G01X408380Y1398553D02*
X411580D01*
G01X408380Y1392353D02*
Y1398553D01*
G01X411580Y1392353D02*
X408380D01*
G01X411580Y1398553D02*
Y1392353D01*
G01X407215Y1391925D02*
X413415D01*
G01X408004Y1405807D02*
Y1402607D01*
G01Y1402284D02*
Y1399084D01*
G01X407931Y1398638D02*
Y1395438D01*
G01X410050Y1421292D02*
Y1424392D01*
X409590Y1423772D01*
G01Y1421292D02*
X410510D01*
G01X412307Y1421912D02*
X412537Y1421550D01*
X412843Y1421344D01*
X413188Y1421292D01*
X413495Y1421344D01*
X413802Y1421602D01*
X413993Y1421912D01*
X414032Y1422222D01*
X413955Y1422584D01*
X413687Y1422842D01*
X413418Y1422945D01*
X413073D01*
G01X413418D02*
X413648Y1423100D01*
X413840Y1423359D01*
X413917Y1423669D01*
X413840Y1423979D01*
X413648Y1424237D01*
X413303Y1424392D01*
X412958Y1424340D01*
X412613Y1424134D01*
G01X414222Y1410427D02*
X410722D01*
G01X412239Y1418301D02*
X414239D01*
G01X408725Y1417903D02*
X405525D01*
G01X408725Y1424103D02*
Y1417903D01*
G01X405525D02*
Y1424103D01*
G01X407999Y1412831D02*
Y1409631D01*
G01X404725Y1424103D02*
Y1417903D01*
G01X407999Y1409327D02*
Y1406127D01*
G01X418210Y1427142D02*
Y1430242D01*
X417750Y1429622D01*
G01Y1427142D02*
X418670D01*
G01X420582Y1429725D02*
X420812Y1430035D01*
X421080Y1430190D01*
X421387Y1430242D01*
X421770Y1430139D01*
X422038Y1429880D01*
X422115Y1429570D01*
X422077Y1429260D01*
X421923Y1429002D01*
X421157Y1428485D01*
X420812Y1428124D01*
X420582Y1427607D01*
X420505Y1427142D01*
X422115D01*
G01X415663Y1422703D02*
Y1424600D01*
G01D02*
X417667D01*
G01X405525Y1424103D02*
X408725D01*
G01X403618Y1425969D02*
Y1429169D01*
G01X409818Y1425969D02*
X403618D01*
G01X409818Y1429169D02*
Y1425969D01*
G01X403618Y1429169D02*
X409818D01*
G01X403618Y1430971D02*
Y1434171D01*
G01X409818Y1430971D02*
X403618D01*
G01X409818Y1434171D02*
Y1430971D01*
G01X403618Y1434171D02*
X409818D01*
G01X409347Y1539832D02*
Y1537610D01*
X409500Y1537145D01*
X409807Y1536835D01*
X410190Y1536732D01*
X410573Y1536835D01*
X410880Y1537145D01*
X411033Y1537610D01*
Y1539832D01*
G01X412562Y1539315D02*
X412792Y1539625D01*
X413060Y1539780D01*
X413367Y1539832D01*
X413750Y1539729D01*
X414018Y1539470D01*
X414095Y1539160D01*
X414057Y1538850D01*
X413903Y1538592D01*
X413137Y1538075D01*
X412792Y1537714D01*
X412562Y1537197D01*
X412485Y1536732D01*
X414095D01*
G01X415547Y1537197D02*
X415777Y1536939D01*
X416045Y1536784D01*
X416390Y1536732D01*
X416735Y1536835D01*
X417003Y1537042D01*
X417195Y1537404D01*
X417233Y1537817D01*
X417157Y1538230D01*
X416965Y1538489D01*
X416697Y1538695D01*
X416428Y1538747D01*
X416160Y1538695D01*
X415815Y1538489D01*
X415930Y1539832D01*
X416965D01*
G01X418647Y1537197D02*
X418877Y1536939D01*
X419145Y1536784D01*
X419490Y1536732D01*
X419835Y1536835D01*
X420103Y1537042D01*
X420295Y1537404D01*
X420333Y1537817D01*
X420257Y1538230D01*
X420065Y1538489D01*
X419797Y1538695D01*
X419528Y1538747D01*
X419260Y1538695D01*
X418915Y1538489D01*
X419030Y1539832D01*
X420065D01*
G01X410686Y1545715D02*
X413795D01*
G01X410686Y1554377D02*
Y1545715D01*
G01X418457D02*
X421566D01*
G01X409150Y1551542D02*
Y1548342D01*
G01X404021Y1539410D02*
Y1536210D01*
G01Y1547410D02*
Y1544210D01*
G01Y1543410D02*
Y1540210D01*
G01X414330Y1554377D02*
X410686D01*
G01X421566D02*
X417330D01*
G01X404021Y1562410D02*
Y1559210D01*
G01Y1558410D02*
Y1555210D01*
G01Y1566410D02*
Y1563210D01*
G01X417453Y1613331D02*
X420800D01*
X422700Y1611131D01*
X424600Y1613331D01*
X427947D01*
Y1604669D01*
X417453D01*
Y1613331D01*
G01X415800Y1601900D02*
X409600D01*
Y1605100D01*
X415800D01*
Y1601900D01*
G01X409600Y1612900D02*
X415800D01*
Y1609700D01*
X409600D01*
Y1612900D01*
G01Y1609000D02*
X415800D01*
Y1605800D01*
X409600D01*
Y1609000D01*
G01X415800Y1613600D02*
X409600D01*
Y1616800D01*
X415800D01*
Y1613600D01*
G01X423300Y1615000D02*
X417100D01*
Y1618200D01*
X423300D01*
Y1615000D01*
G01X417050Y1622002D02*
X423250D01*
G01X417050Y1618802D02*
Y1622002D01*
G01X423250Y1618802D02*
X417050D01*
G01X423215Y1623092D02*
X417015D01*
G01D02*
Y1624662D01*
G01X418410Y1626292D02*
X422050D01*
G01X417015Y1630292D02*
X423215D01*
G01X417015Y1628732D02*
Y1630292D01*
G01X421720Y1627092D02*
X418370D01*
G01X423215Y1631242D02*
X417015D01*
G01D02*
Y1633202D01*
G01X417610Y1644759D02*
X423810D01*
G01X417610Y1641559D02*
Y1644759D01*
G01X423810Y1641559D02*
X417610D01*
G01X417630Y1648816D02*
X423830D01*
G01X417630Y1645616D02*
Y1648816D01*
G01X423830Y1645616D02*
X417630D01*
G01X417015Y1638442D02*
X423215D01*
G01X417015Y1636292D02*
Y1638442D01*
G01X421870Y1635242D02*
X418250D01*
G01X418430Y1634442D02*
X421740D01*
G01X409157Y1653785D02*
X405957D01*
G01X409157Y1659985D02*
Y1653785D01*
G01X405957Y1659985D02*
X409157D01*
G01X405957Y1653785D02*
Y1659985D01*
G01X407227Y1664772D02*
Y1662550D01*
X407380Y1662085D01*
X407687Y1661775D01*
X408070Y1661672D01*
X408453Y1661775D01*
X408760Y1662085D01*
X408913Y1662550D01*
Y1664772D01*
G01X410442Y1664255D02*
X410672Y1664565D01*
X410940Y1664720D01*
X411247Y1664772D01*
X411630Y1664669D01*
X411898Y1664410D01*
X411975Y1664100D01*
X411937Y1663790D01*
X411783Y1663532D01*
X411017Y1663015D01*
X410672Y1662654D01*
X410442Y1662137D01*
X410365Y1661672D01*
X411975D01*
G01X414193D02*
X414270Y1662344D01*
X414385Y1662912D01*
X414538Y1663429D01*
X414730Y1663997D01*
X415037Y1664772D01*
X413503D01*
G01X416642Y1664255D02*
X416872Y1664565D01*
X417140Y1664720D01*
X417447Y1664772D01*
X417830Y1664669D01*
X418098Y1664410D01*
X418175Y1664100D01*
X418137Y1663790D01*
X417983Y1663532D01*
X417217Y1663015D01*
X416872Y1662654D01*
X416642Y1662137D01*
X416565Y1661672D01*
X418175D01*
G01X404167Y1654063D02*
Y1661794D01*
G01X408332Y1678667D02*
Y1681867D01*
G01X414532Y1678667D02*
X408332D01*
G01X414532Y1681867D02*
Y1678667D01*
G01X417320Y1673962D02*
Y1670762D01*
G01X411120Y1673962D02*
X417320D01*
G01X411120Y1670762D02*
Y1673962D01*
G01X417320Y1670762D02*
X411120D01*
G01X417320Y1677962D02*
Y1674762D01*
G01X411120Y1677962D02*
X417320D01*
G01X411120Y1674762D02*
Y1677962D01*
G01X417320Y1674762D02*
X411120D01*
G01X417320Y1669962D02*
Y1666762D01*
G01X411120Y1669962D02*
X417320D01*
G01X411120Y1666762D02*
Y1669962D01*
G01X417320Y1666762D02*
X411120D01*
G01X404167Y1673480D02*
Y1681211D01*
G01X408332Y1681867D02*
X414532D01*
G01X432121Y52673D02*
X459269D01*
G01X432121Y72359D02*
Y52673D01*
G01X424437Y69065D02*
Y65865D01*
G01Y64265D02*
Y61065D01*
G01X435847Y84802D02*
Y82580D01*
X436000Y82115D01*
X436307Y81805D01*
X436690Y81702D01*
X437073Y81805D01*
X437380Y82115D01*
X437533Y82580D01*
Y84802D01*
G01X439062Y84285D02*
X439292Y84595D01*
X439560Y84750D01*
X439867Y84802D01*
X440250Y84699D01*
X440518Y84440D01*
X440595Y84130D01*
X440557Y83820D01*
X440403Y83562D01*
X439637Y83045D01*
X439292Y82684D01*
X439062Y82167D01*
X438985Y81702D01*
X440595D01*
G01X442813D02*
X442890Y82374D01*
X443005Y82942D01*
X443158Y83459D01*
X443350Y84027D01*
X443657Y84802D01*
X442123D01*
G01X445147Y82322D02*
X445377Y81960D01*
X445683Y81754D01*
X446028Y81702D01*
X446335Y81754D01*
X446642Y82012D01*
X446833Y82322D01*
X446872Y82632D01*
X446795Y82994D01*
X446527Y83252D01*
X446258Y83355D01*
X445913D01*
G01X446258D02*
X446488Y83510D01*
X446680Y83769D01*
X446757Y84079D01*
X446680Y84389D01*
X446488Y84647D01*
X446143Y84802D01*
X445798Y84750D01*
X445453Y84544D01*
G01X439852Y72359D02*
X432121D01*
G01X427227Y113422D02*
Y111200D01*
X427380Y110735D01*
X427687Y110425D01*
X428070Y110322D01*
X428453Y110425D01*
X428760Y110735D01*
X428913Y111200D01*
Y113422D01*
G01X430442Y112905D02*
X430672Y113215D01*
X430940Y113370D01*
X431247Y113422D01*
X431630Y113319D01*
X431898Y113060D01*
X431975Y112750D01*
X431937Y112440D01*
X431783Y112182D01*
X431017Y111665D01*
X430672Y111304D01*
X430442Y110787D01*
X430365Y110322D01*
X431975D01*
G01X434270D02*
Y113422D01*
X433810Y112802D01*
G01Y110322D02*
X434730D01*
G01X437370D02*
X437638Y110374D01*
X437945Y110529D01*
X438137Y110787D01*
X438213Y111149D01*
X438137Y111510D01*
X437907Y111820D01*
X437562Y111975D01*
X437178D01*
X436948Y112079D01*
X436757Y112337D01*
X436680Y112699D01*
X436795Y113060D01*
X437063Y113319D01*
X437370Y113422D01*
X437677Y113319D01*
X437945Y113060D01*
X438060Y112699D01*
X437983Y112337D01*
X437792Y112079D01*
X437562Y111975D01*
X437178D01*
X436833Y111820D01*
X436603Y111510D01*
X436527Y111149D01*
X436603Y110787D01*
X436795Y110529D01*
X437102Y110374D01*
X437370Y110322D01*
G01X421975Y115891D02*
Y119091D01*
G01X428175Y115891D02*
X421975D01*
G01X428175Y119091D02*
Y115891D01*
G01X421975Y119091D02*
X428175D01*
G01X427364Y126915D02*
Y130115D01*
G01X433564Y126915D02*
X427364D01*
G01X433564Y130115D02*
Y126915D01*
G01X427364Y130115D02*
X433564D01*
G01X427364Y122415D02*
Y125615D01*
G01X433564Y122415D02*
X427364D01*
G01X433564Y125615D02*
Y122415D01*
G01X427364Y125615D02*
X433564D01*
G01X422297Y150973D02*
Y147773D01*
G01Y155077D02*
Y151877D01*
G01Y159066D02*
Y155866D01*
G01Y163066D02*
Y159866D01*
G01X426620Y213262D02*
Y216462D01*
G01X432820Y213262D02*
X426620D01*
G01X432820Y216462D02*
Y213262D01*
G01X426620Y216462D02*
X432820D01*
G01X426620Y208262D02*
Y211462D01*
G01X432820Y208262D02*
X426620D01*
G01X432820Y211462D02*
Y208262D01*
G01X426620Y211462D02*
X432820D01*
G01X430722Y236945D02*
X430952Y237255D01*
X431220Y237410D01*
X431527Y237462D01*
X431910Y237359D01*
X432178Y237100D01*
X432255Y236790D01*
X432217Y236480D01*
X432063Y236222D01*
X431297Y235705D01*
X430952Y235344D01*
X430722Y234827D01*
X430645Y234362D01*
X432255D01*
G01X434052Y235395D02*
X435048D01*
G01X436807Y234982D02*
X437037Y234620D01*
X437343Y234414D01*
X437688Y234362D01*
X437995Y234414D01*
X438302Y234672D01*
X438493Y234982D01*
X438532Y235292D01*
X438455Y235654D01*
X438187Y235912D01*
X437918Y236015D01*
X437573D01*
G01X437918D02*
X438148Y236170D01*
X438340Y236429D01*
X438417Y236739D01*
X438340Y237049D01*
X438148Y237307D01*
X437803Y237462D01*
X437458Y237410D01*
X437113Y237204D01*
G01X443007Y234362D02*
Y237462D01*
X443773D01*
X444080Y237307D01*
X444310Y237100D01*
X444502Y236790D01*
X444655Y236429D01*
X444693Y235912D01*
X444655Y235395D01*
X444502Y235034D01*
X444310Y234724D01*
X444080Y234517D01*
X443773Y234362D01*
X443007D01*
G01X446490Y237462D02*
X447410D01*
G01X446950D02*
Y234362D01*
G01X446490D02*
X447410D01*
G01X449245Y234775D02*
X449552Y234517D01*
X449897Y234362D01*
X450203D01*
X450510Y234517D01*
X450740Y234775D01*
X450855Y235137D01*
X450778Y235499D01*
X450587Y235809D01*
X450242Y236015D01*
X449782Y236119D01*
X449513Y236325D01*
X449398Y236687D01*
X449475Y237049D01*
X449667Y237307D01*
X449935Y237462D01*
X450203D01*
X450472Y237359D01*
X450702Y237100D01*
G01X452192Y234362D02*
X453150Y237462D01*
X454108Y234362D01*
G01X453763Y235447D02*
X452537D01*
G01X456557Y236015D02*
X456710Y236170D01*
X456825Y236429D01*
X456902Y236790D01*
X456825Y237100D01*
X456672Y237307D01*
X456403Y237462D01*
X455368D01*
Y234362D01*
X456633D01*
X456902Y234569D01*
X457055Y234879D01*
X457132Y235240D01*
X457055Y235602D01*
X456825Y235912D01*
X456557Y236015D01*
X455368D01*
G01X458583Y237462D02*
Y234362D01*
X460117D01*
G01X463217D02*
X461683D01*
Y237462D01*
X463217D01*
G01X462603Y235964D02*
X461683D01*
G01X419915Y241126D02*
Y232326D01*
G01X421620Y223762D02*
Y226962D01*
G01X427820Y223762D02*
X421620D01*
G01X427820Y226962D02*
Y223762D01*
G01X421620Y226962D02*
X427820D01*
G01X422320Y230962D02*
Y234162D01*
G01X428520Y230962D02*
X422320D01*
G01X428520Y234162D02*
Y230962D01*
G01X431450Y240362D02*
Y243462D01*
X430990Y242842D01*
G01Y240362D02*
X431910D01*
G01X434052Y241395D02*
X435048D01*
G01X436922Y242945D02*
X437152Y243255D01*
X437420Y243410D01*
X437727Y243462D01*
X438110Y243359D01*
X438378Y243100D01*
X438455Y242790D01*
X438417Y242480D01*
X438263Y242222D01*
X437497Y241705D01*
X437152Y241344D01*
X436922Y240827D01*
X436845Y240362D01*
X438455D01*
G01X444617D02*
X443083D01*
Y243462D01*
X444617D01*
G01X444003Y241964D02*
X443083D01*
G01X446068Y240362D02*
Y243462D01*
X447832Y240362D01*
Y243462D01*
G01X449092Y240362D02*
X450050Y243462D01*
X451008Y240362D01*
G01X450663Y241447D02*
X449437D01*
G01X453457Y242015D02*
X453610Y242170D01*
X453725Y242429D01*
X453802Y242790D01*
X453725Y243100D01*
X453572Y243307D01*
X453303Y243462D01*
X452268D01*
Y240362D01*
X453533D01*
X453802Y240569D01*
X453955Y240879D01*
X454032Y241240D01*
X453955Y241602D01*
X453725Y241912D01*
X453457Y242015D01*
X452268D01*
G01X455483Y243462D02*
Y240362D01*
X457017D01*
G01X460117D02*
X458583D01*
Y243462D01*
X460117D01*
G01X459503Y241964D02*
X458583D01*
G01X422320Y234162D02*
X428520D01*
G01X422320Y234962D02*
Y238162D01*
G01X428520Y234962D02*
X422320D01*
G01X428520Y238162D02*
Y234962D01*
G01X422320Y238162D02*
X428520D01*
G01X422320Y242162D02*
X428520D01*
G01X422320Y238962D02*
Y242162D01*
G01X428520Y238962D02*
X422320D01*
G01X428520Y242162D02*
Y238962D01*
G01X430273Y259880D02*
X433473D01*
G01X430273Y253680D02*
Y259880D01*
G01X433473Y253680D02*
X430273D01*
G01X433473Y259880D02*
Y253680D01*
G01X430214Y276815D02*
Y280565D01*
G01X437354Y276815D02*
X430214D01*
G01X430264Y280615D02*
X437354D01*
G01X437854Y276815D02*
X430664D01*
G01Y280615D02*
X437854D01*
G01X438354Y276815D02*
X431264D01*
G01Y280615D02*
X438354D01*
G01X423194Y280585D02*
Y276785D01*
G01X423694Y280585D02*
Y276785D01*
G01X424194Y280585D02*
Y276785D01*
G01X428102Y297838D02*
X431302D01*
G01X428102Y291638D02*
Y297838D01*
G01X431302Y291638D02*
X428102D01*
G01X431302Y297838D02*
Y291638D01*
G01X422464Y313234D02*
Y309434D01*
G01X422964Y313234D02*
Y309434D01*
G01X423464Y313234D02*
Y309434D01*
G01X427924D02*
Y313184D01*
G01X435064Y309434D02*
X427924D01*
G01X435064Y313234D02*
Y309434D01*
G01X427974Y313234D02*
X435064D01*
G01X435564Y309434D02*
X428374D01*
G01X435564Y313234D02*
Y309434D01*
G01X428374Y313234D02*
X435564D01*
G01X436064Y309434D02*
X428974D01*
G01Y313234D02*
X436064D01*
G01X421969Y357550D02*
X421662Y357602D01*
X421394Y357808D01*
X421164Y358118D01*
X421011Y358480D01*
X420934Y358893D01*
Y359307D01*
X421011Y359720D01*
X421164Y360082D01*
X421394Y360392D01*
X421662Y360598D01*
X421969Y360650D01*
X422276Y360598D01*
X422544Y360392D01*
X422774Y360082D01*
X422927Y359720D01*
X423004Y359307D01*
Y358893D01*
X422927Y358480D01*
X422774Y358118D01*
X422544Y357808D01*
X422276Y357602D01*
X421969Y357550D01*
G01X422276Y358377D02*
X422736Y357550D01*
G01X425069D02*
X425337Y357602D01*
X425644Y357757D01*
X425836Y358015D01*
X425912Y358377D01*
X425836Y358738D01*
X425606Y359048D01*
X425261Y359203D01*
X424877D01*
X424647Y359307D01*
X424456Y359565D01*
X424379Y359927D01*
X424494Y360288D01*
X424762Y360547D01*
X425069Y360650D01*
X425376Y360547D01*
X425644Y360288D01*
X425759Y359927D01*
X425682Y359565D01*
X425491Y359307D01*
X425261Y359203D01*
X424877D01*
X424532Y359048D01*
X424302Y358738D01*
X424226Y358377D01*
X424302Y358015D01*
X424494Y357757D01*
X424801Y357602D01*
X425069Y357550D01*
G01X428169D02*
Y360650D01*
X427709Y360030D01*
G01Y357550D02*
X428629D01*
G01X420262Y361872D02*
Y370534D01*
G01X430756Y361872D02*
X420262D01*
G01X430756Y370534D02*
Y361872D01*
G01X420016Y374870D02*
Y383532D01*
G01X430510Y374870D02*
X420016D01*
G01X430510Y383532D02*
Y374870D01*
G01X427409Y370534D02*
X430756D01*
G01X425509Y368334D02*
X427409Y370534D01*
G01X423609D02*
X425509Y368334D01*
G01X420262Y370534D02*
X423609D01*
G01X434460Y385322D02*
X434153Y385374D01*
X433885Y385580D01*
X433655Y385890D01*
X433502Y386252D01*
X433425Y386665D01*
Y387079D01*
X433502Y387492D01*
X433655Y387854D01*
X433885Y388164D01*
X434153Y388370D01*
X434460Y388422D01*
X434767Y388370D01*
X435035Y388164D01*
X435265Y387854D01*
X435418Y387492D01*
X435495Y387079D01*
Y386665D01*
X435418Y386252D01*
X435265Y385890D01*
X435035Y385580D01*
X434767Y385374D01*
X434460Y385322D01*
G01X434767Y386149D02*
X435227Y385322D01*
G01X437483D02*
X437560Y385994D01*
X437675Y386562D01*
X437828Y387079D01*
X438020Y387647D01*
X438327Y388422D01*
X436793D01*
G01X439932Y386614D02*
X440200Y386975D01*
X440430Y387182D01*
X440737Y387285D01*
X441005Y387182D01*
X441197Y386975D01*
X441350Y386665D01*
X441388Y386304D01*
X441350Y385994D01*
X441197Y385684D01*
X440967Y385425D01*
X440698Y385322D01*
X440392Y385425D01*
X440123Y385735D01*
X439970Y386200D01*
X439932Y386717D01*
X440008Y387389D01*
X440123Y387750D01*
X440315Y388112D01*
X440583Y388370D01*
X440852Y388422D01*
X441120Y388319D01*
X441312Y388060D01*
G01X427163Y383532D02*
X430510D01*
G01X425263Y381332D02*
X427163Y383532D01*
G01X423363D02*
X425263Y381332D01*
G01X420016Y383532D02*
X423363D01*
G01X419852Y387832D02*
Y396494D01*
G01X430346Y387832D02*
X419852D01*
G01X430346Y396494D02*
Y387832D01*
G01X426999Y396494D02*
X430346D01*
G01X425099Y394294D02*
X426999Y396494D01*
G01X423199D02*
X425099Y394294D01*
G01X419852Y396494D02*
X423199D01*
G01X419975Y400957D02*
Y409619D01*
G01X430469Y400957D02*
X419975D01*
G01X430469Y409619D02*
Y400957D01*
G01X427122Y409619D02*
X430469D01*
G01X425222Y407419D02*
X427122Y409619D01*
G01X423322D02*
X425222Y407419D01*
G01X419975Y409619D02*
X423322D01*
G01X434650Y398382D02*
X434343Y398434D01*
X434075Y398640D01*
X433845Y398950D01*
X433692Y399312D01*
X433615Y399725D01*
Y400139D01*
X433692Y400552D01*
X433845Y400914D01*
X434075Y401224D01*
X434343Y401430D01*
X434650Y401482D01*
X434957Y401430D01*
X435225Y401224D01*
X435455Y400914D01*
X435608Y400552D01*
X435685Y400139D01*
Y399725D01*
X435608Y399312D01*
X435455Y398950D01*
X435225Y398640D01*
X434957Y398434D01*
X434650Y398382D01*
G01X434957Y399209D02*
X435417Y398382D01*
G01X437750D02*
X438018Y398434D01*
X438325Y398589D01*
X438517Y398847D01*
X438593Y399209D01*
X438517Y399570D01*
X438287Y399880D01*
X437942Y400035D01*
X437558D01*
X437328Y400139D01*
X437137Y400397D01*
X437060Y400759D01*
X437175Y401120D01*
X437443Y401379D01*
X437750Y401482D01*
X438057Y401379D01*
X438325Y401120D01*
X438440Y400759D01*
X438363Y400397D01*
X438172Y400139D01*
X437942Y400035D01*
X437558D01*
X437213Y399880D01*
X436983Y399570D01*
X436907Y399209D01*
X436983Y398847D01*
X437175Y398589D01*
X437482Y398434D01*
X437750Y398382D01*
G01X440122Y399674D02*
X440390Y400035D01*
X440620Y400242D01*
X440927Y400345D01*
X441195Y400242D01*
X441387Y400035D01*
X441540Y399725D01*
X441578Y399364D01*
X441540Y399054D01*
X441387Y398744D01*
X441157Y398485D01*
X440888Y398382D01*
X440582Y398485D01*
X440313Y398795D01*
X440160Y399260D01*
X440122Y399777D01*
X440198Y400449D01*
X440313Y400810D01*
X440505Y401172D01*
X440773Y401430D01*
X441042Y401482D01*
X441310Y401379D01*
X441502Y401120D01*
G01X435218Y497133D02*
Y500333D01*
G01X441418Y497133D02*
X435218D01*
G01Y500333D02*
X441418D01*
G01X435218Y502633D02*
Y505833D01*
G01X441418Y502633D02*
X435218D01*
G01Y505833D02*
X441418D01*
G01X435218Y508133D02*
Y511333D01*
G01X441418Y508133D02*
X435218D01*
G01Y511333D02*
X441418D01*
G01X435218Y513633D02*
Y516833D01*
G01X441418Y513633D02*
X435218D01*
G01Y516833D02*
X441418D01*
G01X435218Y519133D02*
Y522333D01*
G01X441418Y519133D02*
X435218D01*
G01Y522333D02*
X441418D01*
G01X435218Y524633D02*
Y527833D01*
G01X441418Y524633D02*
X435218D01*
G01Y527833D02*
X441418D01*
G01X435218Y541133D02*
Y544333D01*
G01X441418Y541133D02*
X435218D01*
G01Y544333D02*
X441418D01*
G01X435218Y546169D02*
Y549369D01*
G01X441418Y546169D02*
X435218D01*
G01Y549369D02*
X441418D01*
G01X435218Y551169D02*
Y554369D01*
G01X441418Y551169D02*
X435218D01*
G01Y554369D02*
X441418D01*
G01X430336Y833739D02*
X434568Y841613D01*
G01X430335Y833740D02*
X434567Y841614D01*
G01X434568Y841613D02*
X446773D01*
G01X434567Y841614D02*
X446772D01*
G01X425718Y931195D02*
Y1032021D01*
G01X420216Y940748D02*
Y934548D01*
G01X423995Y940748D02*
Y934548D01*
X420795D01*
Y940748D01*
X423995D01*
G01X420795Y942873D02*
Y949073D01*
X423995D01*
Y942873D01*
X420795D01*
G01X423995Y955765D02*
Y949565D01*
X420795D01*
Y955765D01*
X423995D01*
G01X420826Y957656D02*
Y963856D01*
X424026D01*
Y957656D01*
X420826D01*
G01X424026Y970164D02*
Y963964D01*
X420826D01*
Y970164D01*
X424026D01*
G01X420271Y978357D02*
Y972157D01*
G01X424000Y984677D02*
Y978477D01*
X420800D01*
Y984677D01*
X424000D01*
G01X420871Y972157D02*
Y978357D01*
X424071D01*
Y972157D01*
X420871D01*
G01X420800Y986568D02*
Y992768D01*
X424000D01*
Y986568D01*
X420800D01*
G01X423950Y998992D02*
Y992792D01*
X420750D01*
Y998992D01*
X423950D01*
G01X420150Y1013550D02*
Y1007350D01*
G01X423950Y1013550D02*
Y1007350D01*
X420750D01*
Y1013550D01*
X423950D01*
G01X420750Y1001050D02*
Y1007250D01*
X423950D01*
Y1001050D01*
X420750D01*
G01X420191Y1021710D02*
Y1015510D01*
G01X423991D02*
X420791D01*
G01X423991Y1021710D02*
Y1015510D01*
G01X420791Y1021710D02*
X423991D01*
G01X420791Y1015510D02*
Y1021710D01*
G01X423991Y1028160D02*
Y1021960D01*
X420791D01*
Y1028160D01*
X423991D01*
G01X434568Y1140826D02*
X430336Y1148700D01*
G01X434567Y1140827D02*
X430335Y1148701D01*
G01X446773Y1140826D02*
X434568D01*
G01X446772Y1140827D02*
X434567D01*
G01X420930Y1160520D02*
Y1154520D01*
G01X421430Y1160520D02*
X433430D01*
G01X421430Y1154520D02*
Y1160520D01*
G01X433430Y1154520D02*
X421430D01*
G01X433430Y1160520D02*
Y1154520D01*
G01X445930D02*
X433930D01*
G01Y1160520D02*
X445930D01*
G01X433930Y1154520D02*
Y1160520D01*
G01X420930Y1168570D02*
Y1162570D01*
G01X445930D02*
X433930D01*
G01Y1168570D02*
X445930D01*
G01X433930Y1162570D02*
Y1168570D01*
G01X421430D02*
X433430D01*
G01X421430Y1162570D02*
Y1168570D01*
G01X433430Y1162570D02*
X421430D01*
G01X433430Y1168570D02*
Y1162570D01*
G01X451383Y1242785D02*
G03I-10827J0D01*
G01X431492Y1255690D02*
Y1298998D01*
G01X436833Y1255690D02*
X431492D01*
G01X428673D02*
Y1298998D01*
G01X423332Y1255690D02*
X428673D01*
G01X423852Y1302032D02*
X423059D01*
G01X423852Y1304632D02*
Y1302032D01*
G01X431492Y1298998D02*
X436833D01*
G01X428673D02*
X423332D01*
G01X423852Y1325654D02*
Y1323463D01*
G01X430463Y1316192D02*
X433663D01*
G01X430463Y1309992D02*
Y1316192D01*
G01X433663Y1309992D02*
X430463D01*
G01X433663Y1316192D02*
Y1309992D01*
G01Y1320492D02*
X430463D01*
G01X433663Y1326692D02*
Y1320492D01*
G01X430463D02*
Y1326692D01*
G01X426461Y1317291D02*
X429661D01*
G01X426461Y1311091D02*
Y1317291D01*
G01X429661Y1311091D02*
X426461D01*
G01X429661Y1317291D02*
Y1311091D01*
G01X423119Y1325654D02*
X423852D01*
G01X433383Y1334982D02*
X436583D01*
G01X433383Y1328782D02*
Y1334982D01*
G01X436583Y1328782D02*
X433383D01*
G01X426055Y1328442D02*
Y1331642D01*
G01X432255Y1328442D02*
X426055D01*
G01X432255Y1331642D02*
Y1328442D01*
G01X426055Y1331642D02*
X432255D01*
G01X419624Y1334518D02*
X422824D01*
G01X419624Y1328318D02*
Y1334518D01*
G01X422824Y1328318D02*
X419624D01*
G01X422824Y1334518D02*
Y1328318D01*
G01X430463Y1326692D02*
X433663D01*
G01X461633Y1354446D02*
G03I-13386J0D01*
G01X434273Y1378032D02*
Y1381132D01*
X435193D01*
X435500Y1380977D01*
X435730Y1380615D01*
X435807Y1380202D01*
X435730Y1379789D01*
X435538Y1379479D01*
X435193Y1379324D01*
X434273D01*
G01X437297Y1381132D02*
Y1378910D01*
X437450Y1378445D01*
X437757Y1378135D01*
X438140Y1378032D01*
X438523Y1378135D01*
X438830Y1378445D01*
X438983Y1378910D01*
Y1381132D01*
G01X440512Y1380615D02*
X440742Y1380925D01*
X441010Y1381080D01*
X441317Y1381132D01*
X441700Y1381029D01*
X441968Y1380770D01*
X442045Y1380460D01*
X442007Y1380150D01*
X441853Y1379892D01*
X441087Y1379375D01*
X440742Y1379014D01*
X440512Y1378497D01*
X440435Y1378032D01*
X442045D01*
G01X443688Y1378394D02*
X443957Y1378135D01*
X444263Y1378032D01*
X444570Y1378135D01*
X444838Y1378445D01*
X445030Y1378910D01*
X445107Y1379375D01*
Y1379944D01*
X445030Y1380409D01*
X444838Y1380822D01*
X444608Y1381029D01*
X444340Y1381132D01*
X444033Y1381029D01*
X443803Y1380822D01*
X443650Y1380512D01*
X443573Y1380099D01*
X443650Y1379737D01*
X443842Y1379375D01*
X444072Y1379169D01*
X444340Y1379117D01*
X444647Y1379220D01*
X444877Y1379479D01*
X445107Y1379944D01*
G01X420077Y1391906D02*
Y1388706D01*
G01X434561Y1399589D02*
Y1397589D01*
G01X426687Y1399589D02*
Y1396089D01*
G01X421962Y1426089D02*
Y1429589D01*
G01X429836Y1426089D02*
Y1427589D01*
G01X421566Y1545715D02*
Y1554377D01*
G01X428321Y1542210D02*
Y1545410D01*
G01X434521Y1542210D02*
X428321D01*
G01X434521Y1545410D02*
Y1542210D01*
G01X428321Y1545410D02*
X434521D01*
G01Y1549410D02*
Y1546210D01*
G01X428321Y1549410D02*
X434521D01*
G01X428321Y1546210D02*
Y1549410D01*
G01X434521Y1546210D02*
X428321D01*
G01X434521Y1553410D02*
Y1550210D01*
G01X428321D02*
Y1553410D01*
G01X434521Y1550210D02*
X428321D01*
G01Y1553410D02*
X434521D01*
G01X428321Y1554210D02*
Y1557410D01*
G01X434521Y1554210D02*
X428321D01*
G01X434521Y1557410D02*
Y1554210D01*
G01X428321Y1557410D02*
X434521D01*
G01X435688Y1577809D02*
X444350D01*
G01X435688Y1580918D02*
Y1577809D01*
G01X438019Y1583249D02*
X435688Y1580918D01*
G01X431645Y1581066D02*
Y1577866D01*
G01X425445D02*
Y1581066D01*
G01X431645Y1577866D02*
X425445D01*
G01Y1581066D02*
X431645D01*
G01Y1585066D02*
Y1581866D01*
G01X425445D02*
Y1585066D01*
G01X431645Y1581866D02*
X425445D01*
G01X422477Y1591342D02*
Y1589120D01*
X422630Y1588655D01*
X422937Y1588345D01*
X423320Y1588242D01*
X423703Y1588345D01*
X424010Y1588655D01*
X424163Y1589120D01*
Y1591342D01*
G01X425692Y1590825D02*
X425922Y1591135D01*
X426190Y1591290D01*
X426497Y1591342D01*
X426880Y1591239D01*
X427148Y1590980D01*
X427225Y1590670D01*
X427187Y1590360D01*
X427033Y1590102D01*
X426267Y1589585D01*
X425922Y1589224D01*
X425692Y1588707D01*
X425615Y1588242D01*
X427225D01*
G01X428677Y1588707D02*
X428907Y1588449D01*
X429175Y1588294D01*
X429520Y1588242D01*
X429865Y1588345D01*
X430133Y1588552D01*
X430325Y1588914D01*
X430363Y1589327D01*
X430287Y1589740D01*
X430095Y1589999D01*
X429827Y1590205D01*
X429558Y1590257D01*
X429290Y1590205D01*
X428945Y1589999D01*
X429060Y1591342D01*
X430095D01*
G01X432543Y1588242D02*
X432620Y1588914D01*
X432735Y1589482D01*
X432888Y1589999D01*
X433080Y1590567D01*
X433387Y1591342D01*
X431853D01*
G01X435688Y1585580D02*
X438019Y1583249D01*
G01X435688Y1588689D02*
Y1585580D01*
G01X444350Y1588689D02*
X435688D01*
G01X430983Y1595554D02*
X427783D01*
G01X430983Y1601754D02*
Y1595554D01*
G01X427783D02*
Y1601754D01*
G01X435783Y1595554D02*
Y1601754D01*
G01X438983Y1595554D02*
X435783D01*
G01X434983D02*
X431783D01*
G01X434983Y1601754D02*
Y1595554D01*
G01X431783D02*
Y1601754D01*
G01X425445Y1585066D02*
X431645D01*
G01X437030Y1608660D02*
Y1610010D01*
X434640Y1612400D01*
X429190D01*
X429910Y1613120D01*
X429930D01*
Y1611810D01*
X429920Y1611800D01*
X429840D01*
X429230Y1612410D01*
G01X434720Y1604697D02*
X434413Y1604749D01*
X434145Y1604955D01*
X433915Y1605265D01*
X433762Y1605627D01*
X433685Y1606040D01*
Y1606454D01*
X433762Y1606867D01*
X433915Y1607229D01*
X434145Y1607539D01*
X434413Y1607745D01*
X434720Y1607797D01*
X435027Y1607745D01*
X435295Y1607539D01*
X435525Y1607229D01*
X435678Y1606867D01*
X435755Y1606454D01*
Y1606040D01*
X435678Y1605627D01*
X435525Y1605265D01*
X435295Y1604955D01*
X435027Y1604749D01*
X434720Y1604697D01*
G01X435027Y1605524D02*
X435487Y1604697D01*
G01X437820D02*
Y1607797D01*
X437360Y1607177D01*
G01Y1604697D02*
X438280D01*
G01X440077Y1605162D02*
X440307Y1604904D01*
X440575Y1604749D01*
X440920Y1604697D01*
X441265Y1604800D01*
X441533Y1605007D01*
X441725Y1605369D01*
X441763Y1605782D01*
X441687Y1606195D01*
X441495Y1606454D01*
X441227Y1606660D01*
X440958Y1606712D01*
X440690Y1606660D01*
X440345Y1606454D01*
X440460Y1607797D01*
X441495D01*
G01X444020Y1604697D02*
Y1607797D01*
X443560Y1607177D01*
G01Y1604697D02*
X444480D01*
G01X427783Y1601754D02*
X430983D01*
G01X435783D02*
X438983D01*
G01X431783D02*
X434983D01*
G01X423250Y1622002D02*
Y1618802D01*
G01X423215Y1624922D02*
Y1623092D01*
G01Y1630292D02*
Y1628552D01*
G01Y1632972D02*
Y1631242D01*
G01X432147Y1617749D02*
X434050D01*
G01X432147Y1619652D02*
Y1617749D01*
G01X423810Y1644759D02*
Y1641559D01*
G01X423830Y1648816D02*
Y1645616D01*
G01X423215Y1638442D02*
Y1636202D01*
G01X432147Y1637435D02*
Y1635532D01*
G01X434050Y1637435D02*
X432147D01*
G01X423317Y1653742D02*
Y1651520D01*
X423470Y1651055D01*
X423777Y1650745D01*
X424160Y1650642D01*
X424543Y1650745D01*
X424850Y1651055D01*
X425003Y1651520D01*
Y1653742D01*
G01X426417Y1651262D02*
X426647Y1650900D01*
X426953Y1650694D01*
X427298Y1650642D01*
X427605Y1650694D01*
X427912Y1650952D01*
X428103Y1651262D01*
X428142Y1651572D01*
X428065Y1651934D01*
X427797Y1652192D01*
X427528Y1652295D01*
X427183D01*
G01X427528D02*
X427758Y1652450D01*
X427950Y1652709D01*
X428027Y1653019D01*
X427950Y1653329D01*
X427758Y1653587D01*
X427413Y1653742D01*
X427068Y1653690D01*
X426723Y1653484D01*
G01X430360Y1650642D02*
Y1653742D01*
X429900Y1653122D01*
G01Y1650642D02*
X430820D01*
G01X433920D02*
Y1653742D01*
X432502Y1651520D01*
X434418D01*
G01X427165Y1707482D02*
Y1656969D01*
G01D02*
X454921D01*
G01X427165Y1782166D02*
Y1726422D01*
G01X454921Y1740118D02*
X427165D01*
G01X454921Y1782166D02*
X427165D01*
G01X451538Y72359D02*
X445695Y66516D01*
G01D02*
X439852Y72359D01*
G01X449893Y74385D02*
Y77585D01*
G01X456093Y74385D02*
X449893D01*
G01Y77585D02*
X456093D01*
G01X459269Y72359D02*
X451538D01*
G01X440538Y115073D02*
X443140Y112471D01*
G01X440538Y119295D02*
Y115073D01*
G01X452742Y119295D02*
X440538D01*
G01Y105647D02*
X452742D01*
G01X440538Y109869D02*
Y105647D01*
G01X443140Y112471D02*
X440538Y109869D01*
G01X439440Y120671D02*
X436240D01*
G01X439440Y126871D02*
Y120671D01*
G01X436240Y126871D02*
X439440D01*
G01X436240Y120671D02*
Y126871D01*
G01X451456Y147310D02*
Y144110D01*
G01X445256Y147310D02*
X451456D01*
G01X445256Y144110D02*
Y147310D01*
G01X451456Y144110D02*
X445256D01*
G01X445221Y148264D02*
Y151464D01*
G01X451421Y148264D02*
X445221D01*
G01X451421Y151464D02*
Y148264D01*
G01X445221Y151464D02*
X451421D01*
G01X453671Y259389D02*
X450471D01*
G01Y265589D02*
X453671D01*
G01X450471Y259389D02*
Y265589D01*
G01X440900Y267672D02*
Y289352D01*
G01X444803Y273622D02*
Y283464D01*
G01X525197Y273622D02*
X444803D01*
G01X437354Y280615D02*
Y276815D01*
G01X437854Y280615D02*
Y276815D01*
G01X438354Y280615D02*
Y276815D01*
G01X440900Y289352D02*
X453800D01*
G01X448500Y285443D02*
X448552Y285175D01*
X448707Y284868D01*
X448965Y284676D01*
X449327Y284600D01*
X449688Y284676D01*
X449998Y284906D01*
X450153Y285251D01*
Y285635D01*
X450257Y285865D01*
X450515Y286056D01*
X450877Y286133D01*
X451238Y286018D01*
X451497Y285750D01*
X451600Y285443D01*
X451497Y285136D01*
X451238Y284868D01*
X450877Y284753D01*
X450515Y284830D01*
X450257Y285021D01*
X450153Y285251D01*
Y285635D01*
X449998Y285980D01*
X449688Y286210D01*
X449327Y286286D01*
X448965Y286210D01*
X448707Y286018D01*
X448552Y285711D01*
X448500Y285443D01*
G01X444803Y283464D02*
X525197D01*
G01X440665Y298014D02*
X443865D01*
G01X440665Y291814D02*
Y298014D01*
G01X443865Y291814D02*
X440665D01*
G01X443865Y298014D02*
Y291814D01*
G01X436064Y313234D02*
Y309434D01*
G01X440524D02*
Y313184D01*
G01X447664Y309434D02*
X440524D01*
G01X447664Y313234D02*
Y309434D01*
G01X440574Y313234D02*
X447664D01*
G01X448164Y309434D02*
X440974D01*
G01X448164Y313234D02*
Y309434D01*
G01X440974Y313234D02*
X448164D01*
G01X448664Y309434D02*
X441574D01*
G01X448664Y313234D02*
Y309434D01*
G01X441574Y313234D02*
X448664D01*
G01X443571Y368103D02*
Y383903D01*
G01X463671Y368103D02*
X443571D01*
G01Y383903D02*
X463671D01*
G01X447320Y397662D02*
X444120D01*
G01X447320Y403862D02*
Y397662D01*
G01X444120Y403862D02*
X447320D01*
G01X444120Y397662D02*
Y403862D01*
G01X453320Y406662D02*
X450120D01*
G01D02*
Y412862D01*
G01D02*
X453320D01*
G01X451420Y421362D02*
X454620D01*
G01X451420Y415162D02*
Y421362D01*
G01X454620Y415162D02*
X451420D01*
G01X446920Y421362D02*
X450120D01*
G01X446920Y415162D02*
Y421362D01*
G01X450120Y415162D02*
X446920D01*
G01X450120Y421362D02*
Y415162D01*
G01X442420Y421362D02*
X445620D01*
G01X442420Y415162D02*
Y421362D01*
G01X445620Y415162D02*
X442420D01*
G01X445620Y421362D02*
Y415162D01*
G01X441371Y437603D02*
Y453403D01*
G01X461471Y437603D02*
X441371D01*
G01Y453403D02*
X461471D01*
G01X453120Y477737D02*
X449920D01*
G01D02*
Y483937D01*
G01X440920Y474937D02*
X444120D01*
G01X440920Y468737D02*
Y474937D01*
G01X444120Y468737D02*
X440920D01*
G01X444120Y474937D02*
Y468737D01*
G01Y477737D02*
X440920D01*
G01X444120Y483937D02*
Y477737D01*
G01X440920D02*
Y483937D01*
G01X435920Y474937D02*
X439120D01*
G01X435920Y468737D02*
Y474937D01*
G01X439120Y468737D02*
X435920D01*
G01X439120Y474937D02*
Y468737D01*
G01Y477737D02*
X435920D01*
G01X439120Y483937D02*
Y477737D01*
G01X435920D02*
Y483937D01*
G01X449920Y474937D02*
X453120D01*
G01X449920Y468737D02*
Y474937D01*
G01X453120Y468737D02*
X449920D01*
G01X449120Y477737D02*
X445920D01*
G01X449120Y483937D02*
Y477737D01*
G01X445920D02*
Y483937D01*
G01X449920D02*
X453120D01*
G01X440920D02*
X444120D01*
G01X435920D02*
X439120D01*
G01X445920D02*
X449120D01*
G01X441418Y500333D02*
Y497133D01*
G01Y505833D02*
Y502633D01*
G01Y511333D02*
Y508133D01*
G01X449928Y507083D02*
Y503883D01*
G01X443728Y507083D02*
X449928D01*
G01X443728Y503883D02*
Y507083D01*
G01X449928Y503883D02*
X443728D01*
G01X449928Y511083D02*
Y507883D01*
G01X443728D02*
Y511083D01*
G01X449928Y507883D02*
X443728D01*
G01X441418Y516833D02*
Y513633D01*
G01Y522333D02*
Y519133D01*
G01Y527833D02*
Y524633D01*
G01X443728Y511083D02*
X449928D01*
G01Y515083D02*
Y511883D01*
G01X443728Y515083D02*
X449928D01*
G01X443728Y511883D02*
Y515083D01*
G01X449928Y511883D02*
X443728D01*
G01X449928Y519083D02*
Y515883D01*
G01X443728Y519083D02*
X449928D01*
G01X443728Y515883D02*
Y519083D01*
G01X449928Y515883D02*
X443728D01*
G01X449928Y523083D02*
Y519883D01*
G01X443728Y523083D02*
X449928D01*
G01X443728Y519883D02*
Y523083D01*
G01X449928Y519883D02*
X443728D01*
G01X449928Y527083D02*
Y523883D01*
G01X443728D02*
Y527083D01*
G01X449928Y523883D02*
X443728D01*
G01X441418Y544333D02*
Y541133D01*
G01X443728Y527083D02*
X449928D01*
G01Y544119D02*
Y540919D01*
G01X443728D02*
Y544119D01*
G01X449928Y540919D02*
X443728D01*
G01Y535883D02*
Y539083D01*
G01X449928Y535883D02*
X443728D01*
G01X449928Y539083D02*
Y535883D01*
G01X443728Y539083D02*
X449928D01*
G01X441418Y549369D02*
Y546169D01*
G01Y554369D02*
Y551169D01*
G01X443728Y544119D02*
X449928D01*
G01Y549119D02*
Y545919D01*
G01X443728Y549119D02*
X449928D01*
G01X443728Y545919D02*
Y549119D01*
G01X449928Y545919D02*
X443728D01*
G01X446773Y841613D02*
X451005Y833739D01*
G01D02*
X472166D01*
G01X446772Y841614D02*
X451004Y833740D01*
G01D02*
X472165D01*
G01X451005Y1148700D02*
X446773Y1140826D01*
G01X451004Y1148701D02*
X446772Y1140827D01*
G01X445930Y1160520D02*
Y1154520D01*
G01X446430Y1160520D02*
X458430D01*
G01X446430Y1154520D02*
Y1160520D01*
G01X458430Y1154520D02*
X446430D01*
G01X472166Y1148700D02*
X451005D01*
G01X472165Y1148701D02*
X451004D01*
G01X445930Y1168570D02*
Y1162570D01*
G01X446430Y1168570D02*
X458430D01*
G01X446430Y1162570D02*
Y1168570D01*
G01X458430Y1162570D02*
X446430D01*
G01X440556Y1253612D02*
Y1231958D01*
G01X436294Y1302032D02*
Y1304632D01*
G01X437087Y1302032D02*
X436294D01*
G01Y1311243D02*
Y1312941D01*
G01X439393Y1336792D02*
Y1339892D01*
X440313D01*
X440620Y1339737D01*
X440850Y1339375D01*
X440927Y1338962D01*
X440850Y1338549D01*
X440658Y1338239D01*
X440313Y1338084D01*
X439393D01*
G01X442417Y1339892D02*
Y1337670D01*
X442570Y1337205D01*
X442877Y1336895D01*
X443260Y1336792D01*
X443643Y1336895D01*
X443950Y1337205D01*
X444103Y1337670D01*
Y1339892D01*
G01X445632Y1339375D02*
X445862Y1339685D01*
X446130Y1339840D01*
X446437Y1339892D01*
X446820Y1339789D01*
X447088Y1339530D01*
X447165Y1339220D01*
X447127Y1338910D01*
X446973Y1338652D01*
X446207Y1338135D01*
X445862Y1337774D01*
X445632Y1337257D01*
X445555Y1336792D01*
X447165D01*
G01X449460D02*
X449728Y1336844D01*
X450035Y1336999D01*
X450227Y1337257D01*
X450303Y1337619D01*
X450227Y1337980D01*
X449997Y1338290D01*
X449652Y1338445D01*
X449268D01*
X449038Y1338549D01*
X448847Y1338807D01*
X448770Y1339169D01*
X448885Y1339530D01*
X449153Y1339789D01*
X449460Y1339892D01*
X449767Y1339789D01*
X450035Y1339530D01*
X450150Y1339169D01*
X450073Y1338807D01*
X449882Y1338549D01*
X449652Y1338445D01*
X449268D01*
X448923Y1338290D01*
X448693Y1337980D01*
X448617Y1337619D01*
X448693Y1337257D01*
X448885Y1336999D01*
X449192Y1336844D01*
X449460Y1336792D01*
G01X451410Y1335759D02*
X453710D01*
G01X454893Y1336792D02*
Y1339892D01*
X455813D01*
X456120Y1339737D01*
X456350Y1339375D01*
X456427Y1338962D01*
X456350Y1338549D01*
X456158Y1338239D01*
X455813Y1338084D01*
X454893D01*
G01X458760Y1336792D02*
Y1339892D01*
X458300Y1339272D01*
G01Y1336792D02*
X459220D01*
G01X460710Y1335759D02*
X463010D01*
G01X464117Y1337412D02*
X464347Y1337050D01*
X464653Y1336844D01*
X464998Y1336792D01*
X465305Y1336844D01*
X465612Y1337102D01*
X465803Y1337412D01*
X465842Y1337722D01*
X465765Y1338084D01*
X465497Y1338342D01*
X465228Y1338445D01*
X464883D01*
G01X465228D02*
X465458Y1338600D01*
X465650Y1338859D01*
X465727Y1339169D01*
X465650Y1339479D01*
X465458Y1339737D01*
X465113Y1339892D01*
X464768Y1339840D01*
X464423Y1339634D01*
G01X436294Y1325654D02*
X437302D01*
G01X436294Y1323800D02*
Y1325654D01*
G01X451361Y1334510D02*
X454561D01*
G01X451361Y1328310D02*
Y1334510D01*
G01X454561Y1328310D02*
X451361D01*
G01X436583Y1334982D02*
Y1328782D01*
G01X437953Y1332495D02*
Y1335695D01*
G01X444153Y1332495D02*
X437953D01*
G01X444153Y1335695D02*
Y1332495D01*
G01X437953Y1335695D02*
X444153D01*
G01X450473Y1328318D02*
X447273D01*
G01X450473Y1334518D02*
Y1328318D01*
G01X447273Y1334518D02*
X450473D01*
G01X447273Y1328318D02*
Y1334518D01*
G01X448247Y1341060D02*
Y1367832D01*
G01X476907Y1379662D02*
G03I-13386J0D01*
G01X436197Y1396032D02*
X436427Y1395670D01*
X436733Y1395464D01*
X437078Y1395412D01*
X437385Y1395464D01*
X437692Y1395722D01*
X437883Y1396032D01*
X437922Y1396342D01*
X437845Y1396704D01*
X437577Y1396962D01*
X437308Y1397065D01*
X436963D01*
G01X437308D02*
X437538Y1397220D01*
X437730Y1397479D01*
X437807Y1397789D01*
X437730Y1398099D01*
X437538Y1398357D01*
X437193Y1398512D01*
X436848Y1398460D01*
X436503Y1398254D01*
G01X439412Y1396704D02*
X439680Y1397065D01*
X439910Y1397272D01*
X440217Y1397375D01*
X440485Y1397272D01*
X440677Y1397065D01*
X440830Y1396755D01*
X440868Y1396394D01*
X440830Y1396084D01*
X440677Y1395774D01*
X440447Y1395515D01*
X440178Y1395412D01*
X439872Y1395515D01*
X439603Y1395825D01*
X439450Y1396290D01*
X439412Y1396807D01*
X439488Y1397479D01*
X439603Y1397840D01*
X439795Y1398202D01*
X440063Y1398460D01*
X440332Y1398512D01*
X440600Y1398409D01*
X440792Y1398150D01*
G01X441747Y1400562D02*
X441977Y1400200D01*
X442283Y1399994D01*
X442628Y1399942D01*
X442935Y1399994D01*
X443242Y1400252D01*
X443433Y1400562D01*
X443472Y1400872D01*
X443395Y1401234D01*
X443127Y1401492D01*
X442858Y1401595D01*
X442513D01*
G01X442858D02*
X443088Y1401750D01*
X443280Y1402009D01*
X443357Y1402319D01*
X443280Y1402629D01*
X443088Y1402887D01*
X442743Y1403042D01*
X442398Y1402990D01*
X442053Y1402784D01*
G01X445613Y1399942D02*
X445690Y1400614D01*
X445805Y1401182D01*
X445958Y1401699D01*
X446150Y1402267D01*
X446457Y1403042D01*
X444923D01*
G01X439285Y1403193D02*
Y1400978D01*
G01D02*
X437203D01*
G01X449489Y1392359D02*
Y1395559D01*
G01X455689Y1392359D02*
X449489D01*
G01Y1395559D02*
X455689D01*
G01X449414Y1402079D02*
X452614D01*
G01X449414Y1395879D02*
Y1402079D01*
G01X452614Y1395879D02*
X449414D01*
G01X443050Y1418302D02*
Y1421402D01*
X441632Y1419180D01*
X443548D01*
G01X445690Y1418302D02*
X445958Y1418354D01*
X446265Y1418509D01*
X446457Y1418767D01*
X446533Y1419129D01*
X446457Y1419490D01*
X446227Y1419800D01*
X445882Y1419955D01*
X445498D01*
X445268Y1420059D01*
X445077Y1420317D01*
X445000Y1420679D01*
X445115Y1421040D01*
X445383Y1421299D01*
X445690Y1421402D01*
X445997Y1421299D01*
X446265Y1421040D01*
X446380Y1420679D01*
X446303Y1420317D01*
X446112Y1420059D01*
X445882Y1419955D01*
X445498D01*
X445153Y1419800D01*
X444923Y1419490D01*
X444847Y1419129D01*
X444923Y1418767D01*
X445115Y1418509D01*
X445422Y1418354D01*
X445690Y1418302D01*
G01X444224Y1408852D02*
X440724D01*
G01X440774Y1416726D02*
X442774D01*
G01X448501Y1419025D02*
Y1422225D01*
G01X454701Y1419025D02*
X448501D01*
G01Y1407525D02*
Y1410725D01*
G01X454701Y1407525D02*
X448501D01*
G01Y1410725D02*
X454701D01*
G01X448501Y1411525D02*
Y1414725D01*
G01X454701Y1411525D02*
X448501D01*
G01Y1414725D02*
X454701D01*
G01X448501Y1415525D02*
Y1418725D01*
G01X454701Y1415525D02*
X448501D01*
G01Y1418725D02*
X454701D01*
G01X437580Y1429232D02*
Y1432332D01*
X436162Y1430110D01*
X438078D01*
G01X440220Y1429232D02*
X440488Y1429284D01*
X440795Y1429439D01*
X440987Y1429697D01*
X441063Y1430059D01*
X440987Y1430420D01*
X440757Y1430730D01*
X440412Y1430885D01*
X440028D01*
X439798Y1430989D01*
X439607Y1431247D01*
X439530Y1431609D01*
X439645Y1431970D01*
X439913Y1432229D01*
X440220Y1432332D01*
X440527Y1432229D01*
X440795Y1431970D01*
X440910Y1431609D01*
X440833Y1431247D01*
X440642Y1430989D01*
X440412Y1430885D01*
X440028D01*
X439683Y1430730D01*
X439453Y1430420D01*
X439377Y1430059D01*
X439453Y1429697D01*
X439645Y1429439D01*
X439952Y1429284D01*
X440220Y1429232D01*
G01X437075Y1424600D02*
X439285D01*
G01D02*
Y1422592D01*
G01X448501Y1426032D02*
Y1429232D01*
G01X454701Y1426032D02*
X448501D01*
G01Y1429232D02*
X454701D01*
G01X447858Y1434531D02*
X444658D01*
G01X447858Y1440731D02*
Y1434531D01*
G01X444658D02*
Y1440731D01*
G01X451378Y1434531D02*
X448178D01*
G01X451378Y1440731D02*
Y1434531D01*
G01X448178D02*
Y1440731D01*
G01X448501Y1422525D02*
Y1425725D01*
G01X454701Y1422525D02*
X448501D01*
G01Y1425725D02*
X454701D01*
G01X448501Y1422225D02*
X454701D01*
G01X448490Y1432734D02*
X454690D01*
Y1429534D01*
X448490D01*
Y1432734D01*
G01X444658Y1440731D02*
X447858D01*
G01X448178D02*
X451378D01*
G01X441189Y1550690D02*
Y1561184D01*
G01X449851Y1550690D02*
X441189D01*
G01X449851Y1554037D02*
Y1550690D01*
G01X448920Y1549037D02*
X455120D01*
G01X448920Y1545837D02*
Y1549037D01*
G01X455120Y1545837D02*
X448920D01*
G01X441189Y1561184D02*
X449851D01*
G01X447651Y1555937D02*
X449851Y1554037D01*
G01Y1557837D02*
X447651Y1555937D01*
G01X449851Y1561184D02*
Y1557837D01*
G01X439620Y1563337D02*
X436420D01*
G01X439620Y1569537D02*
Y1563337D01*
G01X436420D02*
Y1569537D01*
G01X440420Y1563337D02*
Y1569537D01*
G01X443620Y1563337D02*
X440420D01*
G01X443620Y1569537D02*
Y1563337D01*
G01X451620D02*
X448420D01*
G01X451620Y1569537D02*
Y1563337D01*
G01X448420D02*
Y1569537D01*
G01X444420Y1563337D02*
Y1569537D01*
G01X447620Y1563337D02*
X444420D01*
G01X447620Y1569537D02*
Y1563337D01*
G01X444350Y1577809D02*
Y1588689D01*
G01X436420Y1569537D02*
X439620D01*
G01X440420D02*
X443620D01*
G01X450420Y1579537D02*
X453620D01*
G01X450420Y1573337D02*
Y1579537D01*
G01X453620Y1573337D02*
X450420D01*
G01X448420Y1569537D02*
X451620D01*
G01X444420D02*
X447620D01*
G01X451071Y1600311D02*
X451019Y1600004D01*
X450813Y1599736D01*
X450503Y1599506D01*
X450141Y1599353D01*
X449728Y1599276D01*
X449314D01*
X448901Y1599353D01*
X448539Y1599506D01*
X448229Y1599736D01*
X448023Y1600004D01*
X447971Y1600311D01*
X448023Y1600618D01*
X448229Y1600886D01*
X448539Y1601116D01*
X448901Y1601269D01*
X449314Y1601346D01*
X449728D01*
X450141Y1601269D01*
X450503Y1601116D01*
X450813Y1600886D01*
X451019Y1600618D01*
X451071Y1600311D01*
G01X450244Y1600618D02*
X451071Y1601078D01*
G01X449779Y1602683D02*
X449418Y1602951D01*
X449211Y1603181D01*
X449108Y1603488D01*
X449211Y1603756D01*
X449418Y1603948D01*
X449728Y1604101D01*
X450089Y1604139D01*
X450399Y1604101D01*
X450709Y1603948D01*
X450968Y1603718D01*
X451071Y1603449D01*
X450968Y1603143D01*
X450658Y1602874D01*
X450193Y1602721D01*
X449676Y1602683D01*
X449004Y1602759D01*
X448643Y1602874D01*
X448281Y1603066D01*
X448023Y1603334D01*
X447971Y1603603D01*
X448074Y1603871D01*
X448333Y1604063D01*
G01X451071Y1606434D02*
X450399Y1606511D01*
X449831Y1606626D01*
X449314Y1606779D01*
X448746Y1606971D01*
X447971Y1607278D01*
Y1605744D01*
G01X445983Y1601754D02*
Y1598554D01*
G01X439783D02*
Y1601754D01*
G01X445983Y1598554D02*
X439783D01*
G01X438983Y1601754D02*
Y1595554D01*
G01X439783Y1601754D02*
X445983D01*
G01X448480Y1610323D02*
Y1613523D01*
G01X454680Y1610323D02*
X448480D01*
G01Y1613523D02*
X454680D01*
G01X451833Y1617749D02*
Y1619652D01*
G01X449930Y1617749D02*
X451833D01*
G01X436390Y1642677D02*
Y1648877D01*
G01X437940Y1642677D02*
X436390D01*
G01X439590Y1647192D02*
Y1644212D01*
G01X436390Y1648877D02*
X438130D01*
G01X443590D02*
Y1642677D01*
G01D02*
X441890D01*
G01X440390Y1644472D02*
Y1647032D01*
G01X441930Y1648877D02*
X443590D01*
G01X451833Y1637435D02*
X449930D01*
G01X451833Y1635532D02*
Y1637435D01*
G01X448877Y1655792D02*
Y1653570D01*
X449030Y1653105D01*
X449337Y1652795D01*
X449720Y1652692D01*
X450103Y1652795D01*
X450410Y1653105D01*
X450563Y1653570D01*
Y1655792D01*
G01X452820Y1652692D02*
Y1655792D01*
X452360Y1655172D01*
G01Y1652692D02*
X453280D01*
G01X455268Y1653054D02*
X455537Y1652795D01*
X455843Y1652692D01*
X456150Y1652795D01*
X456418Y1653105D01*
X456610Y1653570D01*
X456687Y1654035D01*
Y1654604D01*
X456610Y1655069D01*
X456418Y1655482D01*
X456188Y1655689D01*
X455920Y1655792D01*
X455613Y1655689D01*
X455383Y1655482D01*
X455230Y1655172D01*
X455153Y1654759D01*
X455230Y1654397D01*
X455422Y1654035D01*
X455652Y1653829D01*
X455920Y1653777D01*
X456227Y1653880D01*
X456457Y1654139D01*
X456687Y1654604D01*
G01X458292Y1653984D02*
X458560Y1654345D01*
X458790Y1654552D01*
X459097Y1654655D01*
X459365Y1654552D01*
X459557Y1654345D01*
X459710Y1654035D01*
X459748Y1653674D01*
X459710Y1653364D01*
X459557Y1653054D01*
X459327Y1652795D01*
X459058Y1652692D01*
X458752Y1652795D01*
X458483Y1653105D01*
X458330Y1653570D01*
X458292Y1654087D01*
X458368Y1654759D01*
X458483Y1655120D01*
X458675Y1655482D01*
X458943Y1655740D01*
X459212Y1655792D01*
X459480Y1655689D01*
X459672Y1655430D01*
G01X459650Y-534979D02*
Y-526979D01*
X458450Y-528579D01*
G01Y-534979D02*
X460850D01*
G01X467450D02*
X467650Y-533246D01*
X467950Y-531779D01*
X468350Y-530446D01*
X468850Y-528979D01*
X469650Y-526979D01*
X465650D01*
G01X475650Y-535246D02*
X475450Y-535112D01*
Y-534846D01*
X475650Y-534712D01*
X475850Y-534846D01*
Y-535112D01*
X475650Y-535246D01*
G01X481750Y-528312D02*
X482350Y-527512D01*
X483050Y-527112D01*
X483850Y-526979D01*
X484850Y-527246D01*
X485550Y-527912D01*
X485750Y-528712D01*
X485650Y-529513D01*
X485250Y-530179D01*
X483250Y-531512D01*
X482350Y-532446D01*
X481750Y-533779D01*
X481550Y-534979D01*
X485750D01*
G01X459269Y52673D02*
Y72359D01*
G01X456093Y77585D02*
Y74385D01*
G01X452742Y105647D02*
Y119295D01*
G01X455039Y114348D02*
Y117548D01*
G01X461239Y114348D02*
X455039D01*
G01X461239Y117548D02*
Y114348D01*
G01X455039Y117548D02*
X461239D01*
G01Y122548D02*
Y119348D01*
G01X455039D02*
Y122548D01*
G01X461239Y119348D02*
X455039D01*
G01Y122548D02*
X461239D01*
G01X454221Y148264D02*
Y151464D01*
G01X460421Y148264D02*
X454221D01*
G01X460421Y151464D02*
Y148264D01*
G01X454221Y151464D02*
X460421D01*
G01X454221Y153264D02*
Y156464D01*
G01X460421Y153264D02*
X454221D01*
G01X460421Y156464D02*
Y153264D01*
G01X454221Y156464D02*
X460421D01*
G01X459600Y211762D02*
X453400D01*
Y214962D01*
X459600D01*
Y211762D01*
G01Y220762D02*
X453400D01*
Y223962D01*
X459600D01*
Y220762D01*
G01X468303Y241441D02*
Y251283D01*
X498697D01*
Y241441D01*
X468303D01*
G01X453671Y265589D02*
Y259389D01*
G01X469923Y259471D02*
X466723D01*
G01Y265671D02*
X469923D01*
G01X466723Y259471D02*
Y265671D01*
G01X456664Y265557D02*
X459864D01*
G01X456664Y259357D02*
Y265557D01*
G01X459864Y259357D02*
X456664D01*
G01X459864Y265557D02*
Y259357D01*
G01X468023Y272024D02*
X467793Y272179D01*
X467525Y272282D01*
X467218D01*
X466873Y272127D01*
X466605Y271869D01*
X466413Y271559D01*
X466260Y271042D01*
X466222Y270577D01*
X466298Y270112D01*
X466413Y269802D01*
X466643Y269492D01*
X466912Y269285D01*
X467180Y269182D01*
X467448D01*
X467717Y269285D01*
X467947Y269440D01*
X468138Y269647D01*
G01X469513Y269182D02*
Y272282D01*
X470433D01*
X470740Y272127D01*
X470970Y271765D01*
X471047Y271352D01*
X470970Y270939D01*
X470778Y270629D01*
X470433Y270474D01*
X469513D01*
G01X472613Y272282D02*
Y269182D01*
X474147D01*
G01X475637D02*
Y272282D01*
X476403D01*
X476710Y272127D01*
X476940Y271920D01*
X477132Y271610D01*
X477285Y271249D01*
X477323Y270732D01*
X477285Y270215D01*
X477132Y269854D01*
X476940Y269544D01*
X476710Y269337D01*
X476403Y269182D01*
X475637D01*
G01X481990Y268149D02*
Y271249D01*
G01Y270784D02*
X482182Y271042D01*
X482373Y271197D01*
X482680Y271249D01*
X482948Y271197D01*
X483217Y270939D01*
X483332Y270577D01*
X483370Y270215D01*
X483332Y269854D01*
X483217Y269492D01*
X482987Y269285D01*
X482680Y269182D01*
X482412Y269234D01*
X482143Y269389D01*
X481990Y269595D01*
G01X485243Y269182D02*
Y271249D01*
G01Y270835D02*
X485435Y271042D01*
X485627Y271197D01*
X485895Y271249D01*
X486087Y271197D01*
X486317Y271042D01*
G01X488880Y269182D02*
X488650Y269234D01*
X488420Y269440D01*
X488267Y269802D01*
X488190Y270215D01*
X488267Y270629D01*
X488420Y270990D01*
X488650Y271197D01*
X488880Y271249D01*
X489110Y271197D01*
X489340Y270990D01*
X489493Y270629D01*
X489532Y270215D01*
X489493Y269802D01*
X489340Y269440D01*
X489110Y269234D01*
X488880Y269182D01*
G01X491443Y268407D02*
X491712Y268200D01*
X492018Y268149D01*
X492287Y268200D01*
X492517Y268459D01*
X492670Y268820D01*
Y271249D01*
G01Y270835D02*
X492517Y271042D01*
X492287Y271197D01*
X492018Y271249D01*
X491712Y271145D01*
X491520Y270939D01*
X491367Y270577D01*
X491290Y270215D01*
X491328Y269905D01*
X491482Y269544D01*
X491712Y269285D01*
X492018Y269182D01*
X492248Y269234D01*
X492517Y269440D01*
X492670Y269647D01*
G01X494543Y269182D02*
Y271249D01*
G01Y270835D02*
X494735Y271042D01*
X494927Y271197D01*
X495195Y271249D01*
X495387Y271197D01*
X495617Y271042D01*
G01X498870Y269182D02*
Y271249D01*
G01Y270887D02*
X498717Y271094D01*
X498487Y271197D01*
X498218Y271249D01*
X497950Y271145D01*
X497720Y270939D01*
X497567Y270629D01*
X497490Y270215D01*
X497567Y269802D01*
X497720Y269492D01*
X497950Y269285D01*
X498218Y269182D01*
X498487Y269234D01*
X498717Y269389D01*
X498870Y269595D01*
G01X500130Y269182D02*
Y271249D01*
G01Y270680D02*
X500245Y270939D01*
X500437Y271145D01*
X500705Y271249D01*
X500973Y271145D01*
X501165Y270939D01*
X501280Y270680D01*
Y269182D01*
G01Y270680D02*
X501395Y270939D01*
X501587Y271145D01*
X501855Y271249D01*
X502123Y271145D01*
X502315Y270939D01*
X502430Y270629D01*
Y269182D01*
G01X503230D02*
Y271249D01*
G01Y270680D02*
X503345Y270939D01*
X503537Y271145D01*
X503805Y271249D01*
X504073Y271145D01*
X504265Y270939D01*
X504380Y270680D01*
Y269182D01*
G01Y270680D02*
X504495Y270939D01*
X504687Y271145D01*
X504955Y271249D01*
X505223Y271145D01*
X505415Y270939D01*
X505530Y270629D01*
Y269182D01*
G01X507480Y271249D02*
Y269182D01*
G01Y272075D02*
X507403Y272127D01*
Y272230D01*
X507480Y272282D01*
X507557Y272230D01*
Y272127D01*
X507480Y272075D01*
G01X509928Y269182D02*
Y271249D01*
G01Y270732D02*
X510082Y270990D01*
X510312Y271197D01*
X510618Y271249D01*
X510887Y271197D01*
X511117Y270990D01*
X511232Y270629D01*
Y269182D01*
G01X513143Y268407D02*
X513412Y268200D01*
X513718Y268149D01*
X513987Y268200D01*
X514217Y268459D01*
X514370Y268820D01*
Y271249D01*
G01Y270835D02*
X514217Y271042D01*
X513987Y271197D01*
X513718Y271249D01*
X513412Y271145D01*
X513220Y270939D01*
X513067Y270577D01*
X512990Y270215D01*
X513028Y269905D01*
X513182Y269544D01*
X513412Y269285D01*
X513718Y269182D01*
X513948Y269234D01*
X514217Y269440D01*
X514370Y269647D01*
G01X453800Y289352D02*
Y316512D01*
G01X466136Y298498D02*
X469336D01*
G01X466136Y292298D02*
Y298498D01*
G01X469336Y292298D02*
X466136D01*
G01X464771Y318533D02*
Y316311D01*
X464924Y315846D01*
X465231Y315536D01*
X465614Y315433D01*
X465997Y315536D01*
X466304Y315846D01*
X466457Y316311D01*
Y318533D01*
G01X468062Y315795D02*
X468331Y315536D01*
X468637Y315433D01*
X468944Y315536D01*
X469212Y315846D01*
X469404Y316311D01*
X469481Y316776D01*
Y317345D01*
X469404Y317810D01*
X469212Y318223D01*
X468982Y318430D01*
X468714Y318533D01*
X468407Y318430D01*
X468177Y318223D01*
X468024Y317913D01*
X467947Y317500D01*
X468024Y317138D01*
X468216Y316776D01*
X468446Y316570D01*
X468714Y316518D01*
X469021Y316621D01*
X469251Y316880D01*
X469481Y317345D01*
G01X471737Y315433D02*
X471814Y316105D01*
X471929Y316673D01*
X472082Y317190D01*
X472274Y317758D01*
X472581Y318533D01*
X471047D01*
G01X464488Y310232D02*
X466736D01*
G01X464488Y310058D02*
Y310232D01*
G01Y301964D02*
Y302138D01*
G01X466736Y301964D02*
X464488D01*
G01X465807Y379100D02*
Y376878D01*
X465960Y376413D01*
X466267Y376103D01*
X466650Y376000D01*
X467033Y376103D01*
X467340Y376413D01*
X467493Y376878D01*
Y379100D01*
G01X468907Y376620D02*
X469137Y376258D01*
X469443Y376052D01*
X469788Y376000D01*
X470095Y376052D01*
X470402Y376310D01*
X470593Y376620D01*
X470632Y376930D01*
X470555Y377292D01*
X470287Y377550D01*
X470018Y377653D01*
X469673D01*
G01X470018D02*
X470248Y377808D01*
X470440Y378067D01*
X470517Y378377D01*
X470440Y378687D01*
X470248Y378945D01*
X469903Y379100D01*
X469558Y379048D01*
X469213Y378842D01*
G01X472850Y379100D02*
X472543Y378997D01*
X472313Y378738D01*
X472160Y378428D01*
X472045Y378015D01*
X472007Y377550D01*
X472045Y377085D01*
X472160Y376672D01*
X472313Y376362D01*
X472543Y376103D01*
X472850Y376000D01*
X473157Y376103D01*
X473387Y376362D01*
X473540Y376672D01*
X473655Y377085D01*
X473693Y377550D01*
X473655Y378015D01*
X473540Y378428D01*
X473387Y378738D01*
X473157Y378997D01*
X472850Y379100D01*
G01X475950Y376000D02*
Y379100D01*
X475490Y378480D01*
G01Y376000D02*
X476410D01*
G01X463671Y373753D02*
Y368103D01*
G01X461421Y376003D02*
X463671Y373753D01*
G01Y378253D02*
X461421Y376003D01*
G01X463671Y383903D02*
Y378253D01*
G01X465611Y370833D02*
X468811D01*
G01X465611Y364633D02*
Y370833D01*
G01X468811Y364633D02*
X465611D01*
G01X457320Y406662D02*
X454120D01*
G01X457320Y412862D02*
Y406662D01*
G01X454120D02*
Y412862D01*
G01X464320Y397662D02*
X461120D01*
G01X464320Y403862D02*
Y397662D01*
G01X461120Y403862D02*
X464320D01*
G01X461120Y397662D02*
Y403862D01*
G01X453320Y412862D02*
Y406662D01*
G01X454120Y403862D02*
X457320D01*
G01X454120Y397662D02*
Y403862D01*
G01X457320Y397662D02*
X454120D01*
G01X457320Y403862D02*
Y397662D01*
G01X454120Y412862D02*
X457320D01*
G01X461321Y423403D02*
Y429603D01*
G01X464521Y423403D02*
X461321D01*
G01X464521Y429603D02*
Y423403D01*
G01X454620Y421362D02*
Y415162D01*
G01X455920Y421362D02*
X459120D01*
G01X455920Y415162D02*
Y421362D01*
G01X459120Y415162D02*
X455920D01*
G01X459120Y421362D02*
Y415162D01*
G01X463447Y448072D02*
Y445850D01*
X463600Y445385D01*
X463907Y445075D01*
X464290Y444972D01*
X464673Y445075D01*
X464980Y445385D01*
X465133Y445850D01*
Y448072D01*
G01X466547Y445592D02*
X466777Y445230D01*
X467083Y445024D01*
X467428Y444972D01*
X467735Y445024D01*
X468042Y445282D01*
X468233Y445592D01*
X468272Y445902D01*
X468195Y446264D01*
X467927Y446522D01*
X467658Y446625D01*
X467313D01*
G01X467658D02*
X467888Y446780D01*
X468080Y447039D01*
X468157Y447349D01*
X468080Y447659D01*
X467888Y447917D01*
X467543Y448072D01*
X467198Y448020D01*
X466853Y447814D01*
G01X470490Y448072D02*
X470183Y447969D01*
X469953Y447710D01*
X469800Y447400D01*
X469685Y446987D01*
X469647Y446522D01*
X469685Y446057D01*
X469800Y445644D01*
X469953Y445334D01*
X470183Y445075D01*
X470490Y444972D01*
X470797Y445075D01*
X471027Y445334D01*
X471180Y445644D01*
X471295Y446057D01*
X471333Y446522D01*
X471295Y446987D01*
X471180Y447400D01*
X471027Y447710D01*
X470797Y447969D01*
X470490Y448072D01*
G01X474050Y444972D02*
Y448072D01*
X472632Y445850D01*
X474548D01*
G01X461471Y443253D02*
Y437603D01*
G01X459221Y445503D02*
X461471Y443253D01*
G01X461321Y429603D02*
X464521D01*
G01X461471Y447753D02*
X459221Y445503D01*
G01X461471Y453403D02*
Y447753D01*
G01X453120Y483937D02*
Y477737D01*
G01X454920Y474937D02*
X458120D01*
G01X454920Y468737D02*
Y474937D01*
G01X458120Y468737D02*
X454920D01*
G01X458120Y474937D02*
Y468737D01*
G01X459920Y474937D02*
X463120D01*
G01X459920Y468737D02*
Y474937D01*
G01X463120Y468737D02*
X459920D01*
G01X463120Y474937D02*
Y468737D01*
G01X458120Y477737D02*
X454920D01*
G01X458120Y483937D02*
Y477737D01*
G01X454920D02*
Y483937D01*
G01X463120Y477737D02*
X459920D01*
G01X463120Y483937D02*
Y477737D01*
G01X459920D02*
Y483937D01*
G01X453120Y474937D02*
Y468737D01*
G01X468120D02*
X464920D01*
G01X468120Y474937D02*
Y468737D01*
G01X464920Y474937D02*
X468120D01*
G01X464920Y468737D02*
Y474937D01*
G01X454920Y483937D02*
X458120D01*
G01X459920D02*
X463120D01*
G01X467725Y547214D02*
Y544992D01*
X467878Y544527D01*
X468185Y544217D01*
X468568Y544114D01*
X468951Y544217D01*
X469258Y544527D01*
X469411Y544992D01*
Y547214D01*
G01X470825Y544734D02*
X471055Y544372D01*
X471361Y544166D01*
X471706Y544114D01*
X472013Y544166D01*
X472320Y544424D01*
X472511Y544734D01*
X472550Y545044D01*
X472473Y545406D01*
X472205Y545664D01*
X471936Y545767D01*
X471591D01*
G01X471936D02*
X472166Y545922D01*
X472358Y546181D01*
X472435Y546491D01*
X472358Y546801D01*
X472166Y547059D01*
X471821Y547214D01*
X471476Y547162D01*
X471131Y546956D01*
G01X474040Y545406D02*
X474308Y545767D01*
X474538Y545974D01*
X474845Y546077D01*
X475113Y545974D01*
X475305Y545767D01*
X475458Y545457D01*
X475496Y545096D01*
X475458Y544786D01*
X475305Y544476D01*
X475075Y544217D01*
X474806Y544114D01*
X474500Y544217D01*
X474231Y544527D01*
X474078Y544992D01*
X474040Y545509D01*
X474116Y546181D01*
X474231Y546542D01*
X474423Y546904D01*
X474691Y547162D01*
X474960Y547214D01*
X475228Y547111D01*
X475420Y546852D01*
G01X455621Y1032021D02*
Y931195D01*
G01X473818D02*
X455621D01*
G01X464304Y942873D02*
X461104D01*
G01X464304Y949073D02*
Y942873D01*
G01X461104Y949073D02*
X464304D01*
G01X461104Y942873D02*
Y949073D01*
G01X465104Y949565D02*
Y955765D01*
G01X468304Y949565D02*
X465104D01*
G01X468304Y955765D02*
Y949565D01*
G01X465104Y934548D02*
Y940748D01*
X468304D01*
Y934548D01*
X465104D01*
G01X461104D02*
Y940748D01*
X464304D01*
Y934548D01*
X461104D01*
G01X457304D02*
Y940748D01*
X460504D01*
Y934548D01*
X457304D01*
G01X465104Y942873D02*
Y949073D01*
X468304D01*
Y942873D01*
X465104D01*
G01X457304D02*
Y949073D01*
X460504D01*
Y942873D01*
X457304D01*
G01X464304Y955765D02*
Y949565D01*
X461104D01*
Y955765D01*
X464304D01*
G01X460504D02*
Y949565D01*
X457304D01*
Y955765D01*
X460504D01*
G01X468304Y957656D02*
X465104D01*
G01X468304Y963856D02*
Y957656D01*
G01X465104Y963856D02*
X468304D01*
G01X465104Y957656D02*
Y963856D01*
G01X461104Y963964D02*
Y970164D01*
G01X464304Y963964D02*
X461104D01*
G01X464304Y970164D02*
Y963964D01*
G01X465104Y955765D02*
X468304D01*
G01X465104Y963964D02*
Y970164D01*
G01X468304Y963964D02*
X465104D01*
G01X468304Y970164D02*
Y963964D01*
G01X457304Y957656D02*
Y963856D01*
X460504D01*
Y957656D01*
X457304D01*
G01X460504Y970164D02*
Y963964D01*
X457304D01*
Y970164D01*
X460504D01*
G01X461104Y957656D02*
Y963856D01*
X464304D01*
Y957656D01*
X461104D01*
G01X468304Y972157D02*
X465104D01*
G01X468304Y978357D02*
Y972157D01*
G01X465104Y978357D02*
X468304D01*
G01X465104Y972157D02*
Y978357D01*
G01X461104Y970164D02*
X464304D01*
G01X465104D02*
X468304D01*
G01X465104Y978477D02*
Y984677D01*
G01X468304Y978477D02*
X465104D01*
G01X468304Y984677D02*
Y978477D01*
G01X460504Y984677D02*
Y978477D01*
X457304D01*
Y984677D01*
X460504D01*
G01X457304Y972157D02*
Y978357D01*
X460504D01*
Y972157D01*
X457304D01*
G01X464304Y984677D02*
Y978477D01*
X461104D01*
Y984677D01*
X464304D01*
G01X461104Y972157D02*
Y978357D01*
X464304D01*
Y972157D01*
X461104D01*
G01X465104Y992792D02*
Y998992D01*
G01X468304Y992792D02*
X465104D01*
G01X468304Y998992D02*
Y992792D01*
G01Y986568D02*
X465104D01*
G01X468304Y992768D02*
Y986568D01*
G01X465104Y992768D02*
X468304D01*
G01X465104Y986568D02*
Y992768D01*
G01Y984677D02*
X468304D01*
G01X461104Y986568D02*
Y992768D01*
X464304D01*
Y986568D01*
X461104D01*
G01X457304D02*
Y992768D01*
X460504D01*
Y986568D01*
X457304D01*
G01X464304Y998992D02*
Y992792D01*
X461104D01*
Y998992D01*
X464304D01*
G01X460504D02*
Y992792D01*
X457304D01*
Y998992D01*
X460504D01*
G01X465104D02*
X468304D01*
G01X465104Y1013550D02*
X468304D01*
G01X465104Y1007350D02*
Y1013550D01*
G01X468304Y1007350D02*
X465104D01*
G01X468304Y1013550D02*
Y1007350D01*
G01Y1001050D02*
X465104D01*
G01X468304Y1007250D02*
Y1001050D01*
G01X465104Y1007250D02*
X468304D01*
G01X465104Y1001050D02*
Y1007250D01*
G01X457304Y1001050D02*
Y1007250D01*
X460504D01*
Y1001050D01*
X457304D01*
G01X461104D02*
Y1007250D01*
X464304D01*
Y1001050D01*
X461104D01*
G01X460504Y1013550D02*
Y1007350D01*
X457304D01*
Y1013550D01*
X460504D01*
G01X464304D02*
Y1007350D01*
X461104D01*
Y1013550D01*
X464304D01*
G01X468304Y1015510D02*
X465104D01*
G01X468304Y1021710D02*
Y1015510D01*
G01X465104Y1021710D02*
X468304D01*
G01X465104Y1015510D02*
Y1021710D01*
G01X460504Y1028160D02*
Y1021960D01*
X457304D01*
Y1028160D01*
X460504D01*
G01X468304D02*
Y1021960D01*
X465104D01*
Y1028160D01*
X468304D01*
G01X464304D02*
Y1021960D01*
X461104D01*
Y1028160D01*
X464304D01*
G01X457304Y1015510D02*
Y1021710D01*
X460504D01*
Y1015510D01*
X457304D01*
G01X461104D02*
Y1021710D01*
X464304D01*
Y1015510D01*
X461104D01*
G01X455621Y1032021D02*
X473818D01*
G01X458430Y1160520D02*
Y1154520D01*
G01X470930D02*
X458930D01*
G01Y1160520D02*
X470930D01*
G01X458930Y1154520D02*
Y1160520D01*
G01X458430Y1168570D02*
Y1162570D01*
G01X470930D02*
X458930D01*
G01Y1168570D02*
X470930D01*
G01X458930Y1162570D02*
Y1168570D01*
G01X464956Y1253612D02*
Y1231958D01*
G01X475783Y1242785D02*
G03I-10827J0D01*
G01X463669Y1255690D02*
Y1298998D01*
G01X469010Y1255690D02*
X463669D01*
G01X461020D02*
Y1298998D01*
G01X455679Y1255690D02*
X461020D01*
G01X455980Y1302032D02*
X455187D01*
G01X455980Y1304632D02*
Y1302032D01*
G01X463669Y1298998D02*
X469010D01*
G01X461020D02*
X455679D01*
G01X455980Y1325654D02*
Y1323463D01*
G01X462591Y1316192D02*
X465791D01*
G01X462591Y1309992D02*
Y1316192D01*
G01X465791Y1309992D02*
X462591D01*
G01X465791Y1316192D02*
Y1309992D01*
G01Y1320492D02*
X462591D01*
G01X465791Y1326692D02*
Y1320492D01*
G01X462591D02*
Y1326692D01*
G01X458589Y1317291D02*
X461789D01*
G01X458589Y1311091D02*
Y1317291D01*
G01X461789Y1311091D02*
X458589D01*
G01X461789Y1317291D02*
Y1311091D01*
G01X455247Y1325654D02*
X455980D01*
G01X466044Y1335000D02*
X469244D01*
G01X466044Y1328800D02*
Y1335000D01*
G01X469244Y1328800D02*
X466044D01*
G01X458980Y1328933D02*
Y1332133D01*
G01X465180Y1328933D02*
X458980D01*
G01X465180Y1332133D02*
Y1328933D01*
G01X458980Y1332133D02*
X465180D01*
G01X462591Y1326692D02*
X465791D01*
G01X454561Y1334510D02*
Y1328310D01*
G01X491007Y1353962D02*
G03I-13386J0D01*
G01X463521Y1366276D02*
Y1393048D01*
G01X464000Y1395745D02*
X460900D01*
Y1396665D01*
X461055Y1396972D01*
X461417Y1397202D01*
X461830Y1397279D01*
X462243Y1397202D01*
X462553Y1397010D01*
X462708Y1396665D01*
Y1395745D01*
G01X463380Y1398845D02*
X463690Y1399037D01*
X463897Y1399267D01*
X464000Y1399535D01*
X463897Y1399842D01*
X463690Y1400072D01*
X463380Y1400302D01*
X462967Y1400379D01*
X460900D01*
G01X464000Y1403172D02*
X460900D01*
X463122Y1401754D01*
Y1403670D01*
G01X463638Y1405160D02*
X463897Y1405429D01*
X464000Y1405735D01*
X463897Y1406042D01*
X463587Y1406310D01*
X463122Y1406502D01*
X462657Y1406579D01*
X462088D01*
X461623Y1406502D01*
X461210Y1406310D01*
X461003Y1406080D01*
X460900Y1405812D01*
X461003Y1405505D01*
X461210Y1405275D01*
X461520Y1405122D01*
X461933Y1405045D01*
X462295Y1405122D01*
X462657Y1405314D01*
X462863Y1405544D01*
X462915Y1405812D01*
X462812Y1406119D01*
X462553Y1406349D01*
X462088Y1406579D01*
G01X455689Y1395559D02*
Y1392359D01*
G01X466747Y1402035D02*
X472947D01*
G01X466747Y1398835D02*
Y1402035D01*
G01X472947Y1398835D02*
X466747D01*
G01X470220Y1402862D02*
X467020D01*
G01D02*
Y1409062D01*
G01X466716Y1398206D02*
X472916D01*
G01X466716Y1395006D02*
Y1398206D01*
G01X472916Y1395006D02*
X466716D01*
G01X452614Y1402079D02*
Y1395879D01*
G01X473292Y1419496D02*
X460811D01*
G01D02*
Y1434850D01*
G01X454701Y1422225D02*
Y1419025D01*
G01Y1410725D02*
Y1407525D01*
G01Y1414725D02*
Y1411525D01*
G01Y1418725D02*
Y1415525D01*
G01X467020Y1409062D02*
X470220D01*
G01X458910Y1437355D02*
Y1440455D01*
X459830D01*
X460137Y1440300D01*
X460367Y1439938D01*
X460444Y1439525D01*
X460367Y1439112D01*
X460175Y1438802D01*
X459830Y1438647D01*
X458910D01*
G01X461934Y1440455D02*
Y1438233D01*
X462087Y1437768D01*
X462394Y1437458D01*
X462777Y1437355D01*
X463160Y1437458D01*
X463467Y1437768D01*
X463620Y1438233D01*
Y1440455D01*
G01X465877Y1437355D02*
Y1440455D01*
X465417Y1439835D01*
G01Y1437355D02*
X466337D01*
G01X468900D02*
X468977Y1438027D01*
X469092Y1438595D01*
X469245Y1439112D01*
X469437Y1439680D01*
X469744Y1440455D01*
X468210D01*
G01X472537Y1437355D02*
Y1440455D01*
X471119Y1438233D01*
X473035D01*
G01X460811Y1434850D02*
X473489D01*
G01X454701Y1429232D02*
Y1426032D01*
G01Y1425725D02*
Y1422525D01*
G01X464130Y1550652D02*
X463823Y1550704D01*
X463555Y1550910D01*
X463325Y1551220D01*
X463172Y1551582D01*
X463095Y1551995D01*
Y1552409D01*
X463172Y1552822D01*
X463325Y1553184D01*
X463555Y1553494D01*
X463823Y1553700D01*
X464130Y1553752D01*
X464437Y1553700D01*
X464705Y1553494D01*
X464935Y1553184D01*
X465088Y1552822D01*
X465165Y1552409D01*
Y1551995D01*
X465088Y1551582D01*
X464935Y1551220D01*
X464705Y1550910D01*
X464437Y1550704D01*
X464130Y1550652D01*
G01X464437Y1551479D02*
X464897Y1550652D01*
G01X467153D02*
X467230Y1551324D01*
X467345Y1551892D01*
X467498Y1552409D01*
X467690Y1552977D01*
X467997Y1553752D01*
X466463D01*
G01X470790Y1550652D02*
Y1553752D01*
X469372Y1551530D01*
X471288D01*
G01X455120Y1549037D02*
Y1545837D01*
G01X461120Y1547837D02*
X457920D01*
G01X461120Y1554037D02*
Y1547837D01*
G01X457920D02*
Y1554037D01*
G01X466500Y1562002D02*
X466193Y1562054D01*
X465925Y1562260D01*
X465695Y1562570D01*
X465542Y1562932D01*
X465465Y1563345D01*
Y1563759D01*
X465542Y1564172D01*
X465695Y1564534D01*
X465925Y1564844D01*
X466193Y1565050D01*
X466500Y1565102D01*
X466807Y1565050D01*
X467075Y1564844D01*
X467305Y1564534D01*
X467458Y1564172D01*
X467535Y1563759D01*
Y1563345D01*
X467458Y1562932D01*
X467305Y1562570D01*
X467075Y1562260D01*
X466807Y1562054D01*
X466500Y1562002D01*
G01X466807Y1562829D02*
X467267Y1562002D01*
G01X469523D02*
X469600Y1562674D01*
X469715Y1563242D01*
X469868Y1563759D01*
X470060Y1564327D01*
X470367Y1565102D01*
X468833D01*
G01X471857Y1562467D02*
X472087Y1562209D01*
X472355Y1562054D01*
X472700Y1562002D01*
X473045Y1562105D01*
X473313Y1562312D01*
X473505Y1562674D01*
X473543Y1563087D01*
X473467Y1563500D01*
X473275Y1563759D01*
X473007Y1563965D01*
X472738Y1564017D01*
X472470Y1563965D01*
X472125Y1563759D01*
X472240Y1565102D01*
X473275D01*
G01X455189Y1560690D02*
Y1571184D01*
G01X463851Y1560690D02*
X455189D01*
G01X463851Y1564037D02*
Y1560690D01*
G01X461651Y1565937D02*
X463851Y1564037D01*
G01Y1567837D02*
X461651Y1565937D01*
G01X457920Y1554037D02*
X461120D01*
G01X455189Y1571184D02*
X463851D01*
G01D02*
Y1567837D01*
G01X457620Y1573337D02*
X454420D01*
G01X457620Y1579537D02*
Y1573337D01*
G01X454420Y1579537D02*
X457620D01*
G01X454420Y1573337D02*
Y1579537D01*
G01X453620D02*
Y1573337D01*
G01X458420Y1579537D02*
X461620D01*
G01X458420Y1573337D02*
Y1579537D01*
G01X461620Y1573337D02*
X458420D01*
G01X461620Y1579537D02*
Y1573337D01*
G01X465620D02*
X462420D01*
G01X465620Y1579537D02*
Y1573337D01*
G01X462420Y1579537D02*
X465620D01*
G01X462420Y1573337D02*
Y1579537D01*
G01X452889Y1597748D02*
Y1608242D01*
G01X461551Y1597748D02*
X452889D01*
G01X461551Y1601095D02*
Y1597748D01*
G01X464720Y1594629D02*
Y1600829D01*
G01X467920Y1594629D02*
X464720D01*
G01X467920Y1600829D02*
Y1594629D01*
G01X458820Y1584895D02*
X455620D01*
G01X458820Y1591095D02*
Y1584895D01*
G01X455620Y1591095D02*
X458820D01*
G01X455620Y1584895D02*
Y1591095D01*
G01X452889Y1608242D02*
X461551D01*
G01X459351Y1602995D02*
X461551Y1601095D01*
G01Y1604895D02*
X459351Y1602995D01*
G01X461551Y1608242D02*
Y1604895D01*
G01X464813Y1613082D02*
Y1616282D01*
G01X471013Y1613082D02*
X464813D01*
G01Y1616282D02*
X471013D01*
G01X454680Y1613523D02*
Y1610323D01*
G01X464813Y1612282D02*
X471013D01*
G01X464813Y1609082D02*
Y1612282D01*
G01X471013Y1609082D02*
X464813D01*
G01X464720Y1600829D02*
X467920D01*
G01X464813Y1605282D02*
X471013D01*
G01X464813Y1602082D02*
Y1605282D01*
G01X471013Y1602082D02*
X464813D01*
G01X464770Y1617026D02*
Y1620226D01*
G01X470970Y1617026D02*
X464770D01*
G01Y1620226D02*
X470970D01*
G01X464770Y1624335D02*
X470970D01*
G01X464770Y1621135D02*
Y1624335D01*
G01X470970Y1621135D02*
X464770D01*
G01X464860Y1628332D02*
X471060D01*
G01X464860Y1625132D02*
Y1628332D01*
G01X471060Y1625132D02*
X464860D01*
G01X460958Y1647613D02*
X463620D01*
G01X458320Y1644782D02*
X460958Y1647613D01*
G01X455682D02*
X458320Y1644782D01*
G01X453020Y1647613D02*
X455682D01*
G01X453020Y1638951D02*
Y1647613D01*
G01X463620Y1638951D02*
X453020D01*
G01X463620Y1647613D02*
Y1638951D01*
G01X466530Y1650132D02*
X463330D01*
G01X466530Y1656332D02*
Y1650132D01*
G01X463330Y1656332D02*
X466530D01*
G01X463330Y1650132D02*
Y1656332D01*
G01X454921Y1656969D02*
Y1782166D01*
G01X460690Y1705683D02*
X460882Y1705373D01*
X461112Y1705166D01*
X461380Y1705063D01*
X461687Y1705166D01*
X461917Y1705373D01*
X462147Y1705683D01*
X462224Y1706096D01*
Y1708163D01*
G01X464557Y1705063D02*
Y1708163D01*
X464097Y1707543D01*
G01Y1705063D02*
X465017D01*
G01X466929Y1707646D02*
X467159Y1707956D01*
X467427Y1708111D01*
X467734Y1708163D01*
X468117Y1708060D01*
X468385Y1707801D01*
X468462Y1707491D01*
X468424Y1707181D01*
X468270Y1706923D01*
X467504Y1706406D01*
X467159Y1706045D01*
X466929Y1705528D01*
X466852Y1705063D01*
X468462D01*
G01X470029Y1707646D02*
X470259Y1707956D01*
X470527Y1708111D01*
X470834Y1708163D01*
X471217Y1708060D01*
X471485Y1707801D01*
X471562Y1707491D01*
X471524Y1707181D01*
X471370Y1706923D01*
X470604Y1706406D01*
X470259Y1706045D01*
X470029Y1705528D01*
X469952Y1705063D01*
X471562D01*
G01X479650Y-508379D02*
X480150Y-509179D01*
X480750Y-509712D01*
X481450Y-509979D01*
X482250Y-509712D01*
X482850Y-509179D01*
X483450Y-508379D01*
X483650Y-507312D01*
Y-501979D01*
G01X484343Y54295D02*
Y57495D01*
G01X490543Y54295D02*
X484343D01*
G01X470583Y54335D02*
Y57535D01*
G01X476783Y54335D02*
X470583D01*
G01X476783Y57535D02*
Y54335D01*
G01X484073Y68165D02*
X490273D01*
G01X484073Y64965D02*
Y68165D01*
G01X490273Y64965D02*
X484073D01*
G01X484183Y62805D02*
X490383D01*
G01X484183Y59605D02*
Y62805D01*
G01X490383Y59605D02*
X484183D01*
G01X470653Y64975D02*
Y68175D01*
G01X476853Y64975D02*
X470653D01*
G01X476853Y68175D02*
Y64975D01*
G01X470653Y68175D02*
X476853D01*
G01X470627Y59529D02*
Y62729D01*
G01X476827Y59529D02*
X470627D01*
G01X476827Y62729D02*
Y59529D01*
G01X470627Y62729D02*
X476827D01*
G01X484343Y57495D02*
X490543D01*
G01X470583Y57535D02*
X476783D01*
G01X469283Y143898D02*
Y141676D01*
X469436Y141211D01*
X469743Y140901D01*
X470126Y140798D01*
X470509Y140901D01*
X470816Y141211D01*
X470969Y141676D01*
Y143898D01*
G01X472498Y143381D02*
X472728Y143691D01*
X472996Y143846D01*
X473303Y143898D01*
X473686Y143795D01*
X473954Y143536D01*
X474031Y143226D01*
X473993Y142916D01*
X473839Y142658D01*
X473073Y142141D01*
X472728Y141780D01*
X472498Y141263D01*
X472421Y140798D01*
X474031D01*
G01X476786D02*
Y143898D01*
X475368Y141676D01*
X477284D01*
G01X479426Y140798D02*
X479694Y140850D01*
X480001Y141005D01*
X480193Y141263D01*
X480269Y141625D01*
X480193Y141986D01*
X479963Y142296D01*
X479618Y142451D01*
X479234D01*
X479004Y142555D01*
X478813Y142813D01*
X478736Y143175D01*
X478851Y143536D01*
X479119Y143795D01*
X479426Y143898D01*
X479733Y143795D01*
X480001Y143536D01*
X480116Y143175D01*
X480039Y142813D01*
X479848Y142555D01*
X479618Y142451D01*
X479234D01*
X478889Y142296D01*
X478659Y141986D01*
X478583Y141625D01*
X478659Y141263D01*
X478851Y141005D01*
X479158Y140850D01*
X479426Y140798D01*
G01X468916Y145297D02*
Y153959D01*
G01X480716Y145297D02*
X468916D01*
G01X480716Y153959D02*
Y145297D01*
G01X468916Y153959D02*
X480716D01*
G01X479721Y157264D02*
Y160464D01*
G01X485921Y157264D02*
X479721D01*
G01Y160464D02*
X485921D01*
G01X490400Y230412D02*
Y210312D01*
X474600D01*
Y230412D01*
X480250D01*
X482500Y228162D01*
X484750Y230412D01*
X490400D01*
G01X485100Y239462D02*
Y233262D01*
X481900D01*
Y239462D01*
X485100D01*
G01X471900Y233262D02*
Y239462D01*
X475100D01*
Y233262D01*
X471900D01*
G01X476852Y259410D02*
X473652D01*
G01X476852Y265610D02*
Y259410D01*
G01X473652Y265610D02*
X476852D01*
G01X473652Y259410D02*
Y265610D01*
G01X469923Y265671D02*
Y259471D01*
G01X469336Y298498D02*
Y292298D01*
G01X487100Y292262D02*
X483900D01*
G01D02*
Y298462D01*
G01D02*
X487100D01*
G01X483100Y292262D02*
X479900D01*
G01X483100Y298462D02*
Y292262D01*
G01X479900Y298462D02*
X483100D01*
G01X479900Y292262D02*
Y298462D01*
G01X470984Y310232D02*
Y310058D01*
G01X468736Y310232D02*
X470984D01*
G01Y302088D02*
Y301964D01*
G01D02*
X468736D01*
G01X473120Y361762D02*
Y367962D01*
G01X476320Y361762D02*
X473120D01*
G01X476320Y367962D02*
Y361762D01*
G01X480320D02*
X477120D01*
G01X480320Y367962D02*
Y361762D01*
G01X477120D02*
Y367962D01*
G01X484320Y361762D02*
X481120D01*
G01X484320Y367962D02*
Y361762D01*
G01X481120D02*
Y367962D01*
G01X487444Y373444D02*
X477996D01*
Y384280D01*
X487444D01*
Y380862D01*
X485720Y378862D01*
X487444Y376862D01*
Y373444D01*
G01X468811Y370833D02*
Y364633D01*
G01X473120Y367962D02*
X476320D01*
G01X477120D02*
X480320D01*
G01X481120D02*
X484320D01*
G01X478700Y394000D02*
X478487Y394042D01*
X478300Y394208D01*
X478140Y394458D01*
X478033Y394750D01*
X477980Y395083D01*
Y395417D01*
X478033Y395750D01*
X478140Y396042D01*
X478300Y396292D01*
X478487Y396458D01*
X478700Y396500D01*
X478913Y396458D01*
X479100Y396292D01*
X479260Y396042D01*
X479367Y395750D01*
X479420Y395417D01*
Y395083D01*
X479367Y394750D01*
X479260Y394458D01*
X479100Y394208D01*
X478913Y394042D01*
X478700Y394000D01*
G01X478913Y394667D02*
X479233Y394000D01*
G01X480900D02*
Y396500D01*
X480580Y396000D01*
G01Y394000D02*
X481220D01*
G01X482513Y394500D02*
X482673Y394208D01*
X482887Y394042D01*
X483127Y394000D01*
X483340Y394042D01*
X483553Y394250D01*
X483687Y394500D01*
X483713Y394750D01*
X483660Y395042D01*
X483473Y395250D01*
X483287Y395333D01*
X483047D01*
G01X483287D02*
X483447Y395458D01*
X483580Y395667D01*
X483633Y395917D01*
X483580Y396167D01*
X483447Y396375D01*
X483207Y396500D01*
X482967Y396458D01*
X482727Y396292D01*
G01X485300Y394000D02*
X485487Y394042D01*
X485700Y394167D01*
X485833Y394375D01*
X485887Y394667D01*
X485833Y394958D01*
X485673Y395208D01*
X485433Y395333D01*
X485167D01*
X485007Y395417D01*
X484873Y395625D01*
X484820Y395917D01*
X484900Y396208D01*
X485087Y396417D01*
X485300Y396500D01*
X485513Y396417D01*
X485700Y396208D01*
X485780Y395917D01*
X485727Y395625D01*
X485593Y395417D01*
X485433Y395333D01*
X485167D01*
X484927Y395208D01*
X484767Y394958D01*
X484713Y394667D01*
X484767Y394375D01*
X484900Y394167D01*
X485113Y394042D01*
X485300Y394000D01*
G01X478620Y389762D02*
Y392962D01*
G01X484820Y389762D02*
X478620D01*
G01Y392962D02*
X484820D01*
G01X483420Y421362D02*
X486620D01*
G01X483420Y415162D02*
Y421362D01*
G01X486620Y415162D02*
X483420D01*
G01X478920Y421362D02*
X482120D01*
G01X478920Y415162D02*
Y421362D01*
G01X482120Y415162D02*
X478920D01*
G01X482120Y421362D02*
Y415162D01*
G01X478020Y437462D02*
Y453262D01*
G01X498120Y437462D02*
X478020D01*
G01Y453262D02*
X498120D01*
G01X477569Y474796D02*
X480769D01*
G01X477569Y468596D02*
Y474796D01*
G01X480769Y468596D02*
X477569D01*
G01X480769Y474796D02*
Y468596D01*
G01Y477596D02*
X477569D01*
G01X480769Y483796D02*
Y477596D01*
G01X477569D02*
Y483796D01*
G01X472569Y474796D02*
X475769D01*
G01X472569Y468596D02*
Y474796D01*
G01X475769Y468596D02*
X472569D01*
G01X475769Y474796D02*
Y468596D01*
G01Y477596D02*
X472569D01*
G01X475769Y483796D02*
Y477596D01*
G01X472569D02*
Y483796D01*
G01X485769Y477596D02*
X482569D01*
G01D02*
Y483796D01*
G01X477569D02*
X480769D01*
G01X472569D02*
X475769D01*
G01X482569D02*
X485769D01*
G01X476018Y537947D02*
X470967Y542998D01*
X468718D01*
Y511896D01*
X483318D01*
Y542998D01*
X481069D01*
X476018Y537947D01*
G01X472166Y833739D02*
X489883Y829802D01*
G01X472165Y833740D02*
X489882Y829803D01*
G01X473818Y931195D02*
Y1032021D01*
G01X468904Y949565D02*
Y955765D01*
G01X472104Y949565D02*
X468904D01*
G01X472104Y955765D02*
Y949565D01*
G01X468904Y934548D02*
Y940748D01*
X472104D01*
Y934548D01*
X468904D01*
G01Y942873D02*
Y949073D01*
X472104D01*
Y942873D01*
X468904D01*
G01X472104Y957656D02*
X468904D01*
G01X472104Y963856D02*
Y957656D01*
G01X468904Y963856D02*
X472104D01*
G01X468904Y957656D02*
Y963856D01*
G01Y955765D02*
X472104D01*
G01Y970164D02*
Y963964D01*
X468904D01*
Y970164D01*
X472104D01*
G01X468904Y978477D02*
Y984677D01*
G01X472104Y978477D02*
X468904D01*
G01X472104Y984677D02*
Y978477D01*
G01X468904Y972157D02*
Y978357D01*
X472104D01*
Y972157D01*
X468904D01*
G01Y984677D02*
X472104D01*
G01X468904Y992792D02*
Y998992D01*
G01X472104Y992792D02*
X468904D01*
G01X472104Y998992D02*
Y992792D01*
G01Y986568D02*
X468904D01*
G01X472104Y992768D02*
Y986568D01*
G01X468904Y992768D02*
X472104D01*
G01X468904Y986568D02*
Y992768D01*
G01Y1013550D02*
X472104D01*
G01X468904Y1007350D02*
Y1013550D01*
G01X472104Y1007350D02*
X468904D01*
G01X472104Y1013550D02*
Y1007350D01*
G01X468904Y998992D02*
X472104D01*
G01Y1001050D02*
X468904D01*
G01X472104Y1007250D02*
Y1001050D01*
G01X468904Y1007250D02*
X472104D01*
G01X468904Y1001050D02*
Y1007250D01*
G01X472104Y1015510D02*
X468904D01*
G01X472104Y1021710D02*
Y1015510D01*
G01X468904Y1021710D02*
X472104D01*
G01X468904Y1015510D02*
Y1021710D01*
G01X472104Y1028160D02*
Y1021960D01*
X468904D01*
Y1028160D01*
X472104D01*
G01X470930Y1160520D02*
Y1154520D01*
G01X489883Y1152637D02*
X472166Y1148700D01*
G01X489882Y1152638D02*
X472165Y1148701D01*
G01X470930Y1168570D02*
Y1162570D01*
G01X500183Y1242785D02*
G03I-10827J0D01*
G01X468422Y1302032D02*
Y1304632D01*
G01X469215Y1302032D02*
X468422D01*
G01Y1311243D02*
Y1312941D01*
G01Y1325654D02*
X469430D01*
G01X468422Y1323800D02*
Y1325654D01*
G01X483696Y1334510D02*
X486896D01*
G01X483696Y1328310D02*
Y1334510D01*
G01X486896Y1328310D02*
X483696D01*
G01X469244Y1335000D02*
Y1328800D01*
G01X470081Y1332495D02*
Y1335695D01*
G01X476281Y1332495D02*
X470081D01*
G01X476281Y1335695D02*
Y1332495D01*
G01X470081Y1335695D02*
X476281D01*
G01X482854Y1328310D02*
X479654D01*
G01X482854Y1334510D02*
Y1328310D01*
G01X479654Y1334510D02*
X482854D01*
G01X479654Y1328310D02*
Y1334510D01*
G01X477621Y1340576D02*
Y1367348D01*
G01X478968Y1402870D02*
X475768D01*
G01X478968Y1409070D02*
Y1402870D01*
G01X475768D02*
Y1409070D01*
G01X472947Y1402035D02*
Y1398835D01*
G01X474301Y1402870D02*
X471101D01*
G01X474301Y1409070D02*
Y1402870D01*
G01X471101D02*
Y1409070D01*
G01X476366Y1398785D02*
Y1401985D01*
G01X482566Y1398785D02*
X476366D01*
G01X482566Y1401985D02*
Y1398785D01*
G01X476366Y1401985D02*
X482566D01*
G01X483068Y1402870D02*
X479868D01*
G01X483068Y1409070D02*
Y1402870D01*
G01X479868D02*
Y1409070D01*
G01X470220Y1409062D02*
Y1402862D01*
G01X472916Y1398206D02*
Y1395006D01*
G01X473489Y1434850D02*
Y1419496D01*
G01X474971Y1409544D02*
Y1412744D01*
G01X481171Y1409544D02*
X474971D01*
G01X481171Y1412744D02*
Y1409544D01*
G01X474971Y1412744D02*
X481171D01*
G01X487312Y1420377D02*
X484112D01*
G01D02*
Y1426577D01*
G01X477881Y1414393D02*
X474681D01*
G01X477881Y1420593D02*
Y1414393D01*
G01X474681Y1420593D02*
X477881D01*
G01X474681Y1414393D02*
Y1420593D01*
G01X475768Y1409070D02*
X478968D01*
G01X481852Y1414393D02*
X478652D01*
G01X481852Y1420593D02*
Y1414393D01*
G01X478652Y1420593D02*
X481852D01*
G01X478652Y1414393D02*
Y1420593D01*
G01X471101Y1409070D02*
X474301D01*
G01X479868D02*
X483068D01*
G01X487826Y1429288D02*
X481737D01*
G01Y1429258D02*
Y1458028D01*
G01X484112Y1426577D02*
X487312D01*
G01X476860Y1447179D02*
X480060D01*
G01X476860Y1440979D02*
Y1447179D01*
G01X480060Y1440979D02*
X476860D01*
G01X480060Y1447179D02*
Y1440979D01*
G01X481737Y1458028D02*
X487826D01*
G01X471013Y1616282D02*
Y1613082D01*
G01Y1612282D02*
Y1609082D01*
G01Y1605282D02*
Y1602082D01*
G01X483550Y1629438D02*
Y1632638D01*
G01X489750Y1629438D02*
X483550D01*
G01Y1632638D02*
X489750D01*
G01X475960Y1632603D02*
Y1629403D01*
G01X469760Y1632603D02*
X475960D01*
G01X469760Y1629403D02*
Y1632603D01*
G01X475960Y1629403D02*
X469760D01*
G01X470970Y1620226D02*
Y1617026D01*
G01Y1624335D02*
Y1621135D01*
G01X471060Y1628332D02*
Y1625132D01*
G01X478347Y1646023D02*
Y1781456D01*
G01X568504Y1646023D02*
X478347D01*
G01X475900Y1636547D02*
Y1633347D01*
G01X469700Y1636547D02*
X475900D01*
G01X469700Y1633347D02*
Y1636547D01*
G01X475900Y1633347D02*
X469700D01*
G01X470830Y1641642D02*
Y1644842D01*
G01X477030Y1641642D02*
X470830D01*
G01X477030Y1644842D02*
Y1641642D01*
G01X470830Y1644842D02*
X477030D01*
G01Y1648842D02*
Y1645642D01*
G01X470830Y1648842D02*
X477030D01*
G01X470830Y1645642D02*
Y1648842D01*
G01X477030Y1645642D02*
X470830D01*
G01X480803Y1652352D02*
X480995Y1652042D01*
X481225Y1651835D01*
X481493Y1651732D01*
X481800Y1651835D01*
X482030Y1652042D01*
X482260Y1652352D01*
X482337Y1652765D01*
Y1654832D01*
G01X484670Y1651732D02*
Y1654832D01*
X484210Y1654212D01*
G01Y1651732D02*
X485130D01*
G01X487770D02*
Y1654832D01*
X487310Y1654212D01*
G01Y1651732D02*
X488230D01*
G01X490870Y1654832D02*
X490563Y1654729D01*
X490333Y1654470D01*
X490180Y1654160D01*
X490065Y1653747D01*
X490027Y1653282D01*
X490065Y1652817D01*
X490180Y1652404D01*
X490333Y1652094D01*
X490563Y1651835D01*
X490870Y1651732D01*
X491177Y1651835D01*
X491407Y1652094D01*
X491560Y1652404D01*
X491675Y1652817D01*
X491713Y1653282D01*
X491675Y1653747D01*
X491560Y1654160D01*
X491407Y1654470D01*
X491177Y1654729D01*
X490870Y1654832D01*
G01X477030Y1664842D02*
Y1661642D01*
G01X470830Y1664842D02*
X477030D01*
G01X470830Y1661642D02*
Y1664842D01*
G01X477030Y1661642D02*
X470830D01*
G01Y1657642D02*
Y1660842D01*
G01X477030Y1657642D02*
X470830D01*
G01X477030Y1660842D02*
Y1657642D01*
G01X470830Y1660842D02*
X477030D01*
G01X470830Y1649642D02*
Y1652842D01*
G01X477030Y1649642D02*
X470830D01*
G01X477030Y1652842D02*
Y1649642D01*
G01X470830Y1652842D02*
X477030D01*
G01X470830Y1665642D02*
Y1668842D01*
G01X477030Y1665642D02*
X470830D01*
G01X477030Y1668842D02*
Y1665642D01*
G01X470830Y1668842D02*
X477030D01*
G01X470760Y1671862D02*
Y1675062D01*
G01X476960Y1671862D02*
X470760D01*
G01X476960Y1675062D02*
Y1671862D01*
G01X470760Y1675062D02*
X476960D01*
G01Y1679062D02*
Y1675862D01*
G01X470760Y1679062D02*
X476960D01*
G01X470760Y1675862D02*
Y1679062D01*
G01X476960Y1675862D02*
X470760D01*
G01X476960Y1683062D02*
Y1679862D01*
G01X470760D02*
Y1683062D01*
G01X476960Y1679862D02*
X470760D01*
G01Y1683062D02*
X476960D01*
G01X470760Y1683862D02*
Y1687062D01*
G01X476960Y1683862D02*
X470760D01*
G01X476960Y1687062D02*
Y1683862D01*
G01X470760Y1687062D02*
X476960D01*
G01X478347Y1781456D02*
X568504D01*
G01X509544Y64567D02*
X498354D01*
Y20867D01*
X764654D01*
Y64567D01*
G01X518620Y71930D02*
X496228D01*
Y18268D01*
X766780D01*
Y71930D01*
G01X490543Y57495D02*
Y54295D01*
G01X490273Y68165D02*
Y64965D01*
G01X490383Y62805D02*
Y59605D01*
G01X498180Y84292D02*
Y90292D01*
G01X501180Y84292D02*
X498180D01*
G01X497980Y91982D02*
Y95182D01*
G01X504180Y91982D02*
X497980D01*
G01Y95182D02*
X504180D01*
G01X498180Y90292D02*
X501180D01*
G01X485921Y160464D02*
Y157264D01*
G01X487807Y235962D02*
Y233740D01*
X487960Y233275D01*
X488267Y232965D01*
X488650Y232862D01*
X489033Y232965D01*
X489340Y233275D01*
X489493Y233740D01*
Y235962D01*
G01X490907Y233482D02*
X491137Y233120D01*
X491443Y232914D01*
X491788Y232862D01*
X492095Y232914D01*
X492402Y233172D01*
X492593Y233482D01*
X492632Y233792D01*
X492555Y234154D01*
X492287Y234412D01*
X492018Y234515D01*
X491673D01*
G01X492018D02*
X492248Y234670D01*
X492440Y234929D01*
X492517Y235239D01*
X492440Y235549D01*
X492248Y235807D01*
X491903Y235962D01*
X491558Y235910D01*
X491213Y235704D01*
G01X494122Y235445D02*
X494352Y235755D01*
X494620Y235910D01*
X494927Y235962D01*
X495310Y235859D01*
X495578Y235600D01*
X495655Y235290D01*
X495617Y234980D01*
X495463Y234722D01*
X494697Y234205D01*
X494352Y233844D01*
X494122Y233327D01*
X494045Y232862D01*
X495655D01*
G01X497873D02*
X497950Y233534D01*
X498065Y234102D01*
X498218Y234619D01*
X498410Y235187D01*
X498717Y235962D01*
X497183D01*
G01X499400Y229962D02*
X505600D01*
Y226762D01*
X499400D01*
Y229962D01*
G01X494480Y238519D02*
X494842Y238749D01*
X495048Y239055D01*
X495100Y239400D01*
X495048Y239707D01*
X494790Y240014D01*
X494480Y240205D01*
X494170Y240244D01*
X493808Y240167D01*
X493550Y239899D01*
X493447Y239630D01*
Y239285D01*
G01Y239630D02*
X493292Y239860D01*
X493033Y240052D01*
X492723Y240129D01*
X492413Y240052D01*
X492155Y239860D01*
X492000Y239515D01*
X492052Y239170D01*
X492258Y238825D01*
G01X500696Y260114D02*
X497496D01*
G01X500696Y266314D02*
Y260114D01*
G01X497496Y266314D02*
X500696D01*
G01X497496Y260114D02*
Y266314D01*
G01X494536Y260157D02*
X491336D01*
G01X494536Y266357D02*
Y260157D01*
G01X491336Y266357D02*
X494536D01*
G01X491336Y260157D02*
Y266357D01*
G01X491603Y285092D02*
X491795Y284782D01*
X492025Y284575D01*
X492293Y284472D01*
X492600Y284575D01*
X492830Y284782D01*
X493060Y285092D01*
X493137Y285505D01*
Y287572D01*
G01X495930Y284472D02*
Y287572D01*
X494512Y285350D01*
X496428D01*
G01X497727Y285092D02*
X497957Y284730D01*
X498263Y284524D01*
X498608Y284472D01*
X498915Y284524D01*
X499222Y284782D01*
X499413Y285092D01*
X499452Y285402D01*
X499375Y285764D01*
X499107Y286022D01*
X498838Y286125D01*
X498493D01*
G01X498838D02*
X499068Y286280D01*
X499260Y286539D01*
X499337Y286849D01*
X499260Y287159D01*
X499068Y287417D01*
X498723Y287572D01*
X498378Y287520D01*
X498033Y287314D01*
G01X499536Y297798D02*
X502736D01*
G01X499536Y291598D02*
Y297798D01*
G01X502736Y291598D02*
X499536D01*
G01X487100Y298462D02*
Y292262D01*
G01X497888Y309532D02*
X500136D01*
G01X497888Y309358D02*
Y309532D01*
G01Y301264D02*
Y301438D01*
G01X500136Y301264D02*
X497888D01*
G01X487736Y303798D02*
Y306998D01*
G01X493936Y303798D02*
X487736D01*
G01X493936Y306998D02*
Y303798D01*
G01X487736Y306998D02*
X493936D01*
G01Y310998D02*
Y307798D01*
G01X487736Y310998D02*
X493936D01*
G01X487736Y307798D02*
Y310998D01*
G01X493936Y307798D02*
X487736D01*
G01X487710Y315182D02*
X493910D01*
Y311982D01*
X487710D01*
Y315182D01*
G01X489120Y361762D02*
Y367962D01*
G01X492320Y361762D02*
X489120D01*
G01X492320Y367962D02*
Y361762D01*
G01X497120D02*
Y367962D01*
G01X500320Y361762D02*
X497120D01*
G01X500320Y367962D02*
Y361762D01*
G01X485120D02*
Y367962D01*
G01X488320Y361762D02*
X485120D01*
G01X488320Y367962D02*
Y361762D01*
G01X496320D02*
X493120D01*
G01X496320Y367962D02*
Y361762D01*
G01X493120D02*
Y367962D01*
G01X500844Y373551D02*
X491396D01*
Y384387D01*
X500844D01*
Y380969D01*
X499120Y378969D01*
X500844Y376969D01*
Y373551D01*
G01X489120Y367962D02*
X492320D01*
G01X497120D02*
X500320D01*
G01X485120D02*
X488320D01*
G01X493120D02*
X496320D01*
G01X489700Y394000D02*
X489487Y394042D01*
X489300Y394208D01*
X489140Y394458D01*
X489033Y394750D01*
X488980Y395083D01*
Y395417D01*
X489033Y395750D01*
X489140Y396042D01*
X489300Y396292D01*
X489487Y396458D01*
X489700Y396500D01*
X489913Y396458D01*
X490100Y396292D01*
X490260Y396042D01*
X490367Y395750D01*
X490420Y395417D01*
Y395083D01*
X490367Y394750D01*
X490260Y394458D01*
X490100Y394208D01*
X489913Y394042D01*
X489700Y394000D01*
G01X489913Y394667D02*
X490233Y394000D01*
G01X491900D02*
Y396500D01*
X491580Y396000D01*
G01Y394000D02*
X492220D01*
G01X493513Y394500D02*
X493673Y394208D01*
X493887Y394042D01*
X494127Y394000D01*
X494340Y394042D01*
X494553Y394250D01*
X494687Y394500D01*
X494713Y394750D01*
X494660Y395042D01*
X494473Y395250D01*
X494287Y395333D01*
X494047D01*
G01X494287D02*
X494447Y395458D01*
X494580Y395667D01*
X494633Y395917D01*
X494580Y396167D01*
X494447Y396375D01*
X494207Y396500D01*
X493967Y396458D01*
X493727Y396292D01*
G01X495847Y394292D02*
X496033Y394083D01*
X496247Y394000D01*
X496460Y394083D01*
X496647Y394333D01*
X496780Y394708D01*
X496833Y395083D01*
Y395542D01*
X496780Y395917D01*
X496647Y396250D01*
X496487Y396417D01*
X496300Y396500D01*
X496087Y396417D01*
X495927Y396250D01*
X495820Y396000D01*
X495767Y395667D01*
X495820Y395375D01*
X495953Y395083D01*
X496113Y394917D01*
X496300Y394875D01*
X496513Y394958D01*
X496673Y395167D01*
X496833Y395542D01*
G01X491620Y389762D02*
Y392962D01*
G01X497820Y389762D02*
X491620D01*
G01X497820Y392962D02*
Y389762D01*
G01X491620Y392962D02*
X497820D01*
G01X484820D02*
Y389762D01*
G01X497970Y423262D02*
Y429462D01*
G01X501170Y423262D02*
X497970D01*
G01X486620Y421362D02*
Y415162D01*
G01X487920Y421362D02*
X491120D01*
G01X487920Y415162D02*
Y421362D01*
G01X491120Y415162D02*
X487920D01*
G01X491120Y421362D02*
Y415162D01*
G01X492420Y421362D02*
X495620D01*
G01X492420Y415162D02*
Y421362D01*
G01X495620Y415162D02*
X492420D01*
G01X495620Y421362D02*
Y415162D01*
G01X498120Y443112D02*
Y437462D01*
G01X495870Y445362D02*
X498120Y443112D01*
G01Y447612D02*
X495870Y445362D01*
G01X497970Y429462D02*
X501170D01*
G01X501047Y455302D02*
Y453080D01*
X501200Y452615D01*
X501507Y452305D01*
X501890Y452202D01*
X502273Y452305D01*
X502580Y452615D01*
X502733Y453080D01*
Y455302D01*
G01X504147Y452822D02*
X504377Y452460D01*
X504683Y452254D01*
X505028Y452202D01*
X505335Y452254D01*
X505642Y452512D01*
X505833Y452822D01*
X505872Y453132D01*
X505795Y453494D01*
X505527Y453752D01*
X505258Y453855D01*
X504913D01*
G01X505258D02*
X505488Y454010D01*
X505680Y454269D01*
X505757Y454579D01*
X505680Y454889D01*
X505488Y455147D01*
X505143Y455302D01*
X504798Y455250D01*
X504453Y455044D01*
G01X508090Y455302D02*
X507783Y455199D01*
X507553Y454940D01*
X507400Y454630D01*
X507285Y454217D01*
X507247Y453752D01*
X507285Y453287D01*
X507400Y452874D01*
X507553Y452564D01*
X507783Y452305D01*
X508090Y452202D01*
X508397Y452305D01*
X508627Y452564D01*
X508780Y452874D01*
X508895Y453287D01*
X508933Y453752D01*
X508895Y454217D01*
X508780Y454630D01*
X508627Y454940D01*
X508397Y455199D01*
X508090Y455302D01*
G01X510347Y452667D02*
X510577Y452409D01*
X510845Y452254D01*
X511190Y452202D01*
X511535Y452305D01*
X511803Y452512D01*
X511995Y452874D01*
X512033Y453287D01*
X511957Y453700D01*
X511765Y453959D01*
X511497Y454165D01*
X511228Y454217D01*
X510960Y454165D01*
X510615Y453959D01*
X510730Y455302D01*
X511765D01*
G01X498120Y453262D02*
Y447612D01*
G01X489769Y477596D02*
X486569D01*
G01X489769Y483796D02*
Y477596D01*
G01X486569D02*
Y483796D01*
G01X496569Y474796D02*
X499769D01*
G01X496569Y468596D02*
Y474796D01*
G01X499769Y468596D02*
X496569D01*
G01X499769Y474796D02*
Y468596D01*
G01Y477596D02*
X496569D01*
G01X499769Y483796D02*
Y477596D01*
G01X496569D02*
Y483796D01*
G01X491569Y474796D02*
X494769D01*
G01X491569Y468596D02*
Y474796D01*
G01X494769Y468596D02*
X491569D01*
G01X494769Y474796D02*
Y468596D01*
G01Y477596D02*
X491569D01*
G01X494769Y483796D02*
Y477596D01*
G01X491569D02*
Y483796D01*
G01X486569Y474796D02*
X489769D01*
G01X486569Y468596D02*
Y474796D01*
G01X489769Y468596D02*
X486569D01*
G01X489769Y474796D02*
Y468596D01*
G01X485769Y483796D02*
Y477596D01*
G01X486569Y483796D02*
X489769D01*
G01X496569D02*
X499769D01*
G01X491569D02*
X494769D01*
G01X489518Y546347D02*
Y549547D01*
G01X495718Y546347D02*
X489518D01*
G01X495718Y549547D02*
Y546347D01*
G01X489518Y549547D02*
X495718D01*
G01X493366Y602146D02*
Y611988D01*
X523760D01*
Y602146D01*
X493366D01*
G01X499722Y625145D02*
X499952Y625455D01*
X500220Y625610D01*
X500527Y625662D01*
X500910Y625559D01*
X501178Y625300D01*
X501255Y624990D01*
X501217Y624680D01*
X501063Y624422D01*
X500297Y623905D01*
X499952Y623544D01*
X499722Y623027D01*
X499645Y622562D01*
X501255D01*
G01X503052Y623595D02*
X504048D01*
G01X505807Y623182D02*
X506037Y622820D01*
X506343Y622614D01*
X506688Y622562D01*
X506995Y622614D01*
X507302Y622872D01*
X507493Y623182D01*
X507532Y623492D01*
X507455Y623854D01*
X507187Y624112D01*
X506918Y624215D01*
X506573D01*
G01X506918D02*
X507148Y624370D01*
X507340Y624629D01*
X507417Y624939D01*
X507340Y625249D01*
X507148Y625507D01*
X506803Y625662D01*
X506458Y625610D01*
X506113Y625404D01*
G01X512007Y622562D02*
Y625662D01*
X512773D01*
X513080Y625507D01*
X513310Y625300D01*
X513502Y624990D01*
X513655Y624629D01*
X513693Y624112D01*
X513655Y623595D01*
X513502Y623234D01*
X513310Y622924D01*
X513080Y622717D01*
X512773Y622562D01*
X512007D01*
G01X515490Y625662D02*
X516410D01*
G01X515950D02*
Y622562D01*
G01X515490D02*
X516410D01*
G01X518245Y622975D02*
X518552Y622717D01*
X518897Y622562D01*
X519203D01*
X519510Y622717D01*
X519740Y622975D01*
X519855Y623337D01*
X519778Y623699D01*
X519587Y624009D01*
X519242Y624215D01*
X518782Y624319D01*
X518513Y624525D01*
X518398Y624887D01*
X518475Y625249D01*
X518667Y625507D01*
X518935Y625662D01*
X519203D01*
X519472Y625559D01*
X519702Y625300D01*
G01X521192Y622562D02*
X522150Y625662D01*
X523108Y622562D01*
G01X522763Y623647D02*
X521537D01*
G01X525557Y624215D02*
X525710Y624370D01*
X525825Y624629D01*
X525902Y624990D01*
X525825Y625300D01*
X525672Y625507D01*
X525403Y625662D01*
X524368D01*
Y622562D01*
X525633D01*
X525902Y622769D01*
X526055Y623079D01*
X526132Y623440D01*
X526055Y623802D01*
X525825Y624112D01*
X525557Y624215D01*
X524368D01*
G01X527583Y625662D02*
Y622562D01*
X529117D01*
G01X532217D02*
X530683D01*
Y625662D01*
X532217D01*
G01X531603Y624164D02*
X530683D01*
G01X497060Y614012D02*
Y617212D01*
G01D02*
X503260D01*
G01Y614012D02*
X497060D01*
G01X500450Y628562D02*
Y631662D01*
X499990Y631042D01*
G01Y628562D02*
X500910D01*
G01X503052Y629595D02*
X504048D01*
G01X505922Y631145D02*
X506152Y631455D01*
X506420Y631610D01*
X506727Y631662D01*
X507110Y631559D01*
X507378Y631300D01*
X507455Y630990D01*
X507417Y630680D01*
X507263Y630422D01*
X506497Y629905D01*
X506152Y629544D01*
X505922Y629027D01*
X505845Y628562D01*
X507455D01*
G01X513617D02*
X512083D01*
Y631662D01*
X513617D01*
G01X513003Y630164D02*
X512083D01*
G01X515068Y628562D02*
Y631662D01*
X516832Y628562D01*
Y631662D01*
G01X518092Y628562D02*
X519050Y631662D01*
X520008Y628562D01*
G01X519663Y629647D02*
X518437D01*
G01X522457Y630215D02*
X522610Y630370D01*
X522725Y630629D01*
X522802Y630990D01*
X522725Y631300D01*
X522572Y631507D01*
X522303Y631662D01*
X521268D01*
Y628562D01*
X522533D01*
X522802Y628769D01*
X522955Y629079D01*
X523032Y629440D01*
X522955Y629802D01*
X522725Y630112D01*
X522457Y630215D01*
X521268D01*
G01X524483Y631662D02*
Y628562D01*
X526017D01*
G01X529117D02*
X527583D01*
Y631662D01*
X529117D01*
G01X528503Y630164D02*
X527583D01*
G01X499722Y634562D02*
Y637662D01*
X501178D01*
G01X500642Y636164D02*
X499722D01*
G01X503550Y634562D02*
X503243Y634614D01*
X502975Y634820D01*
X502745Y635130D01*
X502592Y635492D01*
X502515Y635905D01*
Y636319D01*
X502592Y636732D01*
X502745Y637094D01*
X502975Y637404D01*
X503243Y637610D01*
X503550Y637662D01*
X503857Y637610D01*
X504125Y637404D01*
X504355Y637094D01*
X504508Y636732D01*
X504585Y636319D01*
Y635905D01*
X504508Y635492D01*
X504355Y635130D01*
X504125Y634820D01*
X503857Y634614D01*
X503550Y634562D01*
G01X505883D02*
Y637662D01*
X506842D01*
X507148Y637507D01*
X507340Y637300D01*
X507417Y636887D01*
X507340Y636474D01*
X507110Y636215D01*
X506842Y636060D01*
X505883D01*
G01X506842D02*
X507417Y634562D01*
G01X510593Y637404D02*
X510363Y637559D01*
X510095Y637662D01*
X509788D01*
X509443Y637507D01*
X509175Y637249D01*
X508983Y636939D01*
X508830Y636422D01*
X508792Y635957D01*
X508868Y635492D01*
X508983Y635182D01*
X509213Y634872D01*
X509482Y634665D01*
X509750Y634562D01*
X510018D01*
X510287Y634665D01*
X510517Y634820D01*
X510708Y635027D01*
G01X513617Y634562D02*
X512083D01*
Y637662D01*
X513617D01*
G01X513003Y636164D02*
X512083D01*
G01X518283Y634562D02*
Y637662D01*
X519203D01*
X519510Y637507D01*
X519740Y637145D01*
X519817Y636732D01*
X519740Y636319D01*
X519548Y636009D01*
X519203Y635854D01*
X518283D01*
G01X521000Y637662D02*
X521537Y634562D01*
X522150Y637662D01*
X522763Y634562D01*
X523300Y637662D01*
G01X524483Y634562D02*
Y637662D01*
X525442D01*
X525748Y637507D01*
X525940Y637300D01*
X526017Y636887D01*
X525940Y636474D01*
X525710Y636215D01*
X525442Y636060D01*
X524483D01*
G01X525442D02*
X526017Y634562D01*
G01X528350D02*
X528043Y634614D01*
X527775Y634820D01*
X527545Y635130D01*
X527392Y635492D01*
X527315Y635905D01*
Y636319D01*
X527392Y636732D01*
X527545Y637094D01*
X527775Y637404D01*
X528043Y637610D01*
X528350Y637662D01*
X528657Y637610D01*
X528925Y637404D01*
X529155Y637094D01*
X529308Y636732D01*
X529385Y636319D01*
Y635905D01*
X529308Y635492D01*
X529155Y635130D01*
X528925Y634820D01*
X528657Y634614D01*
X528350Y634562D01*
G01X530568D02*
Y637662D01*
X532332Y634562D01*
Y637662D01*
G01X500083Y642282D02*
X500275Y641972D01*
X500505Y641765D01*
X500773Y641662D01*
X501080Y641765D01*
X501310Y641972D01*
X501540Y642282D01*
X501617Y642695D01*
Y644762D01*
G01X503183Y641662D02*
Y644762D01*
X504103D01*
X504410Y644607D01*
X504640Y644245D01*
X504717Y643832D01*
X504640Y643419D01*
X504448Y643109D01*
X504103Y642954D01*
X503183D01*
G01X507050Y641662D02*
Y644762D01*
X506590Y644142D01*
G01Y641662D02*
X507510D01*
G01X509307Y642127D02*
X509537Y641869D01*
X509805Y641714D01*
X510150Y641662D01*
X510495Y641765D01*
X510763Y641972D01*
X510955Y642334D01*
X510993Y642747D01*
X510917Y643160D01*
X510725Y643419D01*
X510457Y643625D01*
X510188Y643677D01*
X509920Y643625D01*
X509575Y643419D01*
X509690Y644762D01*
X510725D01*
G01X489883Y829802D02*
X560749D01*
G01X489882Y829803D02*
X560748D01*
G01X560749Y1152637D02*
X489883D01*
G01X560748Y1152638D02*
X489882D01*
G01X489356Y1253612D02*
Y1231958D01*
G01X493197Y1255690D02*
Y1298998D01*
G01X487856Y1255690D02*
X493197D01*
G01X495856Y1268871D02*
Y1312179D01*
G01X501197Y1268871D02*
X495856D01*
G01X488108Y1302032D02*
X487315D01*
G01X488108Y1304632D02*
Y1302032D01*
G01X493197Y1298998D02*
X487856D01*
G01X500550Y1315458D02*
Y1318058D01*
G01X501343Y1315458D02*
X500550D01*
G01X488108Y1325654D02*
Y1323463D01*
G01X495856Y1312179D02*
X501197D01*
G01X494719Y1323418D02*
Y1329618D01*
G01X497919Y1323418D02*
X494719D01*
G01X497919Y1329618D02*
Y1323418D01*
G01X491140Y1317992D02*
Y1321192D01*
G01X497340Y1317992D02*
X491140D01*
G01X497340Y1321192D02*
Y1317992D01*
G01X491140Y1321192D02*
X497340D01*
G01X490717Y1317291D02*
X493917D01*
G01X490717Y1311091D02*
Y1317291D01*
G01X493917Y1311091D02*
X490717D01*
G01X493917Y1317291D02*
Y1311091D01*
G01X500550Y1339080D02*
X501558D01*
G01X500550Y1337226D02*
Y1339080D01*
G01Y1324669D02*
Y1326367D01*
G01X487375Y1325654D02*
X488108D01*
G01X497919Y1333918D02*
X494719D01*
G01X497919Y1340118D02*
Y1333918D01*
G01X494719D02*
Y1340118D01*
G01Y1329618D02*
X497919D01*
G01X486896Y1334510D02*
Y1328310D01*
G01X497913Y1353232D02*
Y1356332D01*
X498833D01*
X499140Y1356177D01*
X499370Y1355815D01*
X499447Y1355402D01*
X499370Y1354989D01*
X499178Y1354679D01*
X498833Y1354524D01*
X497913D01*
G01X500937Y1356332D02*
Y1354110D01*
X501090Y1353645D01*
X501397Y1353335D01*
X501780Y1353232D01*
X502163Y1353335D01*
X502470Y1353645D01*
X502623Y1354110D01*
Y1356332D01*
G01X504152Y1355815D02*
X504382Y1356125D01*
X504650Y1356280D01*
X504957Y1356332D01*
X505340Y1356229D01*
X505608Y1355970D01*
X505685Y1355660D01*
X505647Y1355350D01*
X505493Y1355092D01*
X504727Y1354575D01*
X504382Y1354214D01*
X504152Y1353697D01*
X504075Y1353232D01*
X505685D01*
G01X507252Y1354524D02*
X507520Y1354885D01*
X507750Y1355092D01*
X508057Y1355195D01*
X508325Y1355092D01*
X508517Y1354885D01*
X508670Y1354575D01*
X508708Y1354214D01*
X508670Y1353904D01*
X508517Y1353594D01*
X508287Y1353335D01*
X508018Y1353232D01*
X507712Y1353335D01*
X507443Y1353645D01*
X507290Y1354110D01*
X507252Y1354627D01*
X507328Y1355299D01*
X507443Y1355660D01*
X507635Y1356022D01*
X507903Y1356280D01*
X508172Y1356332D01*
X508440Y1356229D01*
X508632Y1355970D01*
G01X509930Y1352199D02*
X512230D01*
G01X513413Y1353232D02*
Y1356332D01*
X514333D01*
X514640Y1356177D01*
X514870Y1355815D01*
X514947Y1355402D01*
X514870Y1354989D01*
X514678Y1354679D01*
X514333Y1354524D01*
X513413D01*
G01X517280Y1353232D02*
Y1356332D01*
X516820Y1355712D01*
G01Y1353232D02*
X517740D01*
G01X519230Y1352199D02*
X521530D01*
G01X522637Y1353697D02*
X522867Y1353439D01*
X523135Y1353284D01*
X523480Y1353232D01*
X523825Y1353335D01*
X524093Y1353542D01*
X524285Y1353904D01*
X524323Y1354317D01*
X524247Y1354730D01*
X524055Y1354989D01*
X523787Y1355195D01*
X523518Y1355247D01*
X523250Y1355195D01*
X522905Y1354989D01*
X523020Y1356332D01*
X524055D01*
G01X497858Y1348439D02*
X501058D01*
G01X497858Y1342239D02*
Y1348439D01*
G01X501058Y1342239D02*
X497858D01*
G01X494719Y1340118D02*
X497919D01*
G01X494083Y1363482D02*
Y1366582D01*
X495003D01*
X495310Y1366427D01*
X495540Y1366065D01*
X495617Y1365652D01*
X495540Y1365239D01*
X495348Y1364929D01*
X495003Y1364774D01*
X494083D01*
G01X497107Y1366582D02*
Y1364360D01*
X497260Y1363895D01*
X497567Y1363585D01*
X497950Y1363482D01*
X498333Y1363585D01*
X498640Y1363895D01*
X498793Y1364360D01*
Y1366582D01*
G01X500322Y1366065D02*
X500552Y1366375D01*
X500820Y1366530D01*
X501127Y1366582D01*
X501510Y1366479D01*
X501778Y1366220D01*
X501855Y1365910D01*
X501817Y1365600D01*
X501663Y1365342D01*
X500897Y1364825D01*
X500552Y1364464D01*
X500322Y1363947D01*
X500245Y1363482D01*
X501855D01*
G01X504073D02*
X504150Y1364154D01*
X504265Y1364722D01*
X504418Y1365239D01*
X504610Y1365807D01*
X504917Y1366582D01*
X503383D01*
G01X506100Y1362449D02*
X508400D01*
G01X509583Y1363482D02*
Y1366582D01*
X510503D01*
X510810Y1366427D01*
X511040Y1366065D01*
X511117Y1365652D01*
X511040Y1365239D01*
X510848Y1364929D01*
X510503Y1364774D01*
X509583D01*
G01X513450Y1363482D02*
Y1366582D01*
X512990Y1365962D01*
G01Y1363482D02*
X513910D01*
G01X515400Y1362449D02*
X517700D01*
G01X520110Y1363482D02*
Y1366582D01*
X518692Y1364360D01*
X520608D01*
G01X491582Y1384027D02*
X503582D01*
G01X491582Y1378027D02*
Y1384027D01*
G01X503582Y1378027D02*
X491582D01*
G01X491623Y1386027D02*
Y1392027D01*
G01X503623Y1386027D02*
X491623D01*
G01Y1400027D02*
X503623D01*
G01X491623Y1394027D02*
Y1400027D01*
G01X503623Y1394027D02*
X491623D01*
G01Y1392027D02*
X503623D01*
G01X494941Y1403191D02*
X501043D01*
Y1403662D01*
G01X488839Y1403462D02*
Y1403191D01*
G01D02*
X492641D01*
G01X487312Y1426577D02*
Y1420377D01*
G01X501043Y1419062D02*
Y1419333D01*
X497241D01*
G01X492641D02*
X488839D01*
Y1419062D01*
G01X494956Y1425633D02*
Y1422433D01*
G01X488756Y1425633D02*
X494956D01*
G01X488756Y1422433D02*
Y1425633D01*
G01X494956Y1422433D02*
X488756D01*
G01X489750Y1632638D02*
Y1629438D01*
G01X494133Y1636642D02*
Y1644142D01*
X496373D01*
X497120Y1643767D01*
X497680Y1642892D01*
X497867Y1641892D01*
X497680Y1640892D01*
X497213Y1640142D01*
X496373Y1639767D01*
X494133D01*
G01X501633Y1636642D02*
Y1644142D01*
X503967D01*
X504713Y1643767D01*
X505180Y1643267D01*
X505367Y1642267D01*
X505180Y1641267D01*
X504620Y1640642D01*
X503967Y1640267D01*
X501633D01*
G01X503967D02*
X505367Y1636642D01*
G01X512867D02*
X509133D01*
Y1644142D01*
X512867D01*
G01X511373Y1640517D02*
X509133D01*
G01X516540Y1637642D02*
X517287Y1637017D01*
X518127Y1636642D01*
X518873D01*
X519620Y1637017D01*
X520180Y1637642D01*
X520460Y1638517D01*
X520273Y1639392D01*
X519807Y1640142D01*
X518967Y1640642D01*
X517847Y1640892D01*
X517193Y1641392D01*
X516913Y1642267D01*
X517100Y1643142D01*
X517567Y1643767D01*
X518220Y1644142D01*
X518873D01*
X519527Y1643892D01*
X520087Y1643267D01*
G01X524040Y1637642D02*
X524787Y1637017D01*
X525627Y1636642D01*
X526373D01*
X527120Y1637017D01*
X527680Y1637642D01*
X527960Y1638517D01*
X527773Y1639392D01*
X527307Y1640142D01*
X526467Y1640642D01*
X525347Y1640892D01*
X524693Y1641392D01*
X524413Y1642267D01*
X524600Y1643142D01*
X525067Y1643767D01*
X525720Y1644142D01*
X526373D01*
X527027Y1643892D01*
X527587Y1643267D01*
G01X532287Y1639142D02*
X534713D01*
G01X539227Y1636642D02*
Y1644142D01*
X542773D01*
G01X541467Y1640517D02*
X539227D01*
G01X547380Y1644142D02*
X549620D01*
G01X548500D02*
Y1636642D01*
G01X547380D02*
X549620D01*
G01X556000Y1644142D02*
Y1636642D01*
G01X553853Y1644142D02*
X558147D01*
G01X496282Y1653472D02*
Y1656572D01*
X495822Y1655952D01*
G01Y1653472D02*
X496742D01*
G01X490158Y1657834D02*
X556693D01*
G01X490158Y1769645D02*
Y1657834D01*
G01X485524Y1682573D02*
Y1679473D01*
X487058D01*
G01X485294Y1674749D02*
Y1677849D01*
X486291Y1675266D01*
X487288Y1677849D01*
Y1674749D01*
G01X485409Y1670025D02*
Y1673125D01*
X487173Y1670025D01*
Y1673125D01*
G01X485524Y1689542D02*
X485716Y1689232D01*
X485946Y1689025D01*
X486214Y1688922D01*
X486521Y1689025D01*
X486751Y1689232D01*
X486981Y1689542D01*
X487058Y1689955D01*
Y1692022D01*
G01X485448Y1684198D02*
Y1687298D01*
G01X486904D02*
X485448Y1685386D01*
G01X487134Y1684198D02*
X486099Y1686265D01*
G01X485831Y1696747D02*
X486751D01*
G01X486291D02*
Y1693647D01*
G01X485831D02*
X486751D01*
G01X485486Y1698371D02*
Y1701471D01*
G01X487096D02*
Y1698371D01*
G01Y1699921D02*
X485486D01*
G01X487058Y1712544D02*
X485524D01*
Y1715644D01*
X487058D01*
G01X486444Y1714146D02*
X485524D01*
G01X485563Y1707820D02*
Y1710920D01*
X487019D01*
G01X486483Y1709422D02*
X485563D01*
G01X486521Y1704646D02*
X487288D01*
Y1703716D01*
X487058Y1703406D01*
X486789Y1703199D01*
X486406Y1703096D01*
X486023Y1703199D01*
X485754Y1703406D01*
X485524Y1703716D01*
X485371Y1704078D01*
X485294Y1704491D01*
Y1704853D01*
X485371Y1705163D01*
X485524Y1705524D01*
X485754Y1705834D01*
X485984Y1706041D01*
X486291Y1706196D01*
X486559D01*
X486866Y1706093D01*
X487096Y1705886D01*
G01X485448Y1717269D02*
Y1720369D01*
X486214D01*
X486521Y1720214D01*
X486751Y1720007D01*
X486943Y1719697D01*
X487096Y1719336D01*
X487134Y1718819D01*
X487096Y1718302D01*
X486943Y1717941D01*
X486751Y1717631D01*
X486521Y1717424D01*
X486214Y1717269D01*
X485448D01*
G01X486598Y1728371D02*
X486751Y1728526D01*
X486866Y1728785D01*
X486943Y1729146D01*
X486866Y1729456D01*
X486713Y1729663D01*
X486444Y1729818D01*
X485409D01*
Y1726718D01*
X486674D01*
X486943Y1726925D01*
X487096Y1727235D01*
X487173Y1727596D01*
X487096Y1727958D01*
X486866Y1728268D01*
X486598Y1728371D01*
X485409D01*
G01X487134Y1724835D02*
X486904Y1724990D01*
X486636Y1725093D01*
X486329D01*
X485984Y1724938D01*
X485716Y1724680D01*
X485524Y1724370D01*
X485371Y1723853D01*
X485333Y1723388D01*
X485409Y1722923D01*
X485524Y1722613D01*
X485754Y1722303D01*
X486023Y1722096D01*
X486291Y1721993D01*
X486559D01*
X486828Y1722096D01*
X487058Y1722251D01*
X487249Y1722458D01*
G01X497179Y1736412D02*
X502179D01*
G01X497179Y1739812D02*
Y1736412D01*
G01X499179Y1737812D02*
X497179Y1739812D01*
G01X495179Y1737812D02*
X499179D01*
G01X497179Y1739812D02*
X495179Y1737812D01*
G01X490158Y1740118D02*
X556693D01*
G01Y1769645D02*
X490158D01*
G01X518620Y81762D02*
X515420D01*
G01D02*
Y87962D01*
G01X513820Y81762D02*
X510620D01*
G01X513820Y87962D02*
Y81762D01*
G01X510620D02*
Y87962D01*
G01X502350Y84822D02*
Y88022D01*
G01X508550Y84822D02*
X502350D01*
G01X508550Y88022D02*
Y84822D01*
G01X501180Y90292D02*
Y84292D01*
G01X516850Y94542D02*
X504850D01*
G01X516850Y100542D02*
Y94542D01*
G01X504850Y100542D02*
X516850D01*
G01X504850Y94542D02*
Y100542D01*
G01X504180Y95182D02*
Y91982D01*
G01X515420Y87962D02*
X518620D01*
G01X510620D02*
X513820D01*
G01X502350Y88022D02*
X508550D01*
G01X509230Y110772D02*
X512430D01*
G01X509230Y104572D02*
Y110772D01*
G01X512430Y104572D02*
X509230D01*
G01X512430Y110772D02*
Y104572D01*
G01X515725Y166843D02*
Y170043D01*
G01X521925Y166843D02*
X515725D01*
G01Y170043D02*
X521925D01*
G01X505400Y211462D02*
X511600D01*
Y208262D01*
X505400D01*
Y211462D01*
G01X511600Y221762D02*
X505400D01*
Y224962D01*
X511600D01*
Y221762D01*
G01X501383Y245482D02*
X501575Y245172D01*
X501805Y244965D01*
X502073Y244862D01*
X502380Y244965D01*
X502610Y245172D01*
X502840Y245482D01*
X502917Y245895D01*
Y247962D01*
G01X504483Y244862D02*
Y247962D01*
X505403D01*
X505710Y247807D01*
X505940Y247445D01*
X506017Y247032D01*
X505940Y246619D01*
X505748Y246309D01*
X505403Y246154D01*
X504483D01*
G01X508350Y244862D02*
Y247962D01*
X507890Y247342D01*
G01Y244862D02*
X508810D01*
G01X510722Y246154D02*
X510990Y246515D01*
X511220Y246722D01*
X511527Y246825D01*
X511795Y246722D01*
X511987Y246515D01*
X512140Y246205D01*
X512178Y245844D01*
X512140Y245534D01*
X511987Y245224D01*
X511757Y244965D01*
X511488Y244862D01*
X511182Y244965D01*
X510913Y245275D01*
X510760Y245740D01*
X510722Y246257D01*
X510798Y246929D01*
X510913Y247290D01*
X511105Y247652D01*
X511373Y247910D01*
X511642Y247962D01*
X511910Y247859D01*
X512102Y247600D01*
G01X500900Y239462D02*
X507100D01*
Y236262D01*
X500900D01*
Y239462D01*
G01X507100Y240262D02*
X500900D01*
Y243462D01*
X507100D01*
Y240262D01*
G01X517404Y260363D02*
X514204D01*
G01D02*
Y266563D01*
G01X511096Y260439D02*
X507896D01*
G01X511096Y266639D02*
Y260439D01*
G01X507896D02*
Y266639D01*
G01X514204Y266563D02*
X517404D01*
G01X507896Y266639D02*
X511096D01*
G01X502736Y297798D02*
Y291598D01*
G01X503900Y287262D02*
Y290462D01*
G01X510100Y287262D02*
X503900D01*
G01X510100Y290462D02*
Y287262D01*
G01X503900Y290462D02*
X510100D01*
G01X506150Y297683D02*
X509350D01*
G01X506150Y291483D02*
Y297683D01*
G01X509350D02*
Y291483D01*
G01D02*
X506150D01*
G01X512640Y287075D02*
Y284649D01*
G01X522530Y288455D02*
X514330D01*
G01X522530Y288955D02*
X514330D01*
G01Y287955D02*
Y308355D01*
G01X522530Y287955D02*
X514330D01*
G01X520430Y297655D02*
X516330D01*
G01X504384Y309532D02*
Y309358D01*
G01X502136Y309532D02*
X504384D01*
G01Y301388D02*
Y301264D01*
G01D02*
X502136D01*
G01X509857Y313804D02*
X503657D01*
G01X509857Y317004D02*
Y313804D01*
G01X503657D02*
Y317004D01*
G01X518230Y312482D02*
Y310242D01*
G01X519855Y311455D02*
X516605D01*
G01X514330Y308355D02*
X522530D01*
G01X516330Y300655D02*
X518530Y297955D01*
G01X520430Y300655D02*
X516330D01*
G01X502457Y321742D02*
Y319520D01*
X502610Y319055D01*
X502917Y318745D01*
X503300Y318642D01*
X503683Y318745D01*
X503990Y319055D01*
X504143Y319520D01*
Y321742D01*
G01X505748Y319004D02*
X506017Y318745D01*
X506323Y318642D01*
X506630Y318745D01*
X506898Y319055D01*
X507090Y319520D01*
X507167Y319985D01*
Y320554D01*
X507090Y321019D01*
X506898Y321432D01*
X506668Y321639D01*
X506400Y321742D01*
X506093Y321639D01*
X505863Y321432D01*
X505710Y321122D01*
X505633Y320709D01*
X505710Y320347D01*
X505902Y319985D01*
X506132Y319779D01*
X506400Y319727D01*
X506707Y319830D01*
X506937Y320089D01*
X507167Y320554D01*
G01X508772Y319934D02*
X509040Y320295D01*
X509270Y320502D01*
X509577Y320605D01*
X509845Y320502D01*
X510037Y320295D01*
X510190Y319985D01*
X510228Y319624D01*
X510190Y319314D01*
X510037Y319004D01*
X509807Y318745D01*
X509538Y318642D01*
X509232Y318745D01*
X508963Y319055D01*
X508810Y319520D01*
X508772Y320037D01*
X508848Y320709D01*
X508963Y321070D01*
X509155Y321432D01*
X509423Y321690D01*
X509692Y321742D01*
X509960Y321639D01*
X510152Y321380D01*
G01X503657Y317004D02*
X509857D01*
G01X517120Y361762D02*
Y367962D01*
G01X520320Y361762D02*
X517120D01*
G01X516320D02*
X513120D01*
G01X516320Y367962D02*
Y361762D01*
G01X513120D02*
Y367962D01*
G01X505120Y361762D02*
Y367962D01*
G01X508320Y361762D02*
X505120D01*
G01X508320Y367962D02*
Y361762D01*
G01X512320D02*
X509120D01*
G01X512320Y367962D02*
Y361762D01*
G01X509120D02*
Y367962D01*
G01X504320Y361762D02*
X501120D01*
G01X504320Y367962D02*
Y361762D01*
G01X501120D02*
Y367962D01*
G01X516944Y373444D02*
X507496D01*
Y384280D01*
X516944D01*
Y380862D01*
X515220Y378862D01*
X516944Y376862D01*
Y373444D01*
G01X517120Y367962D02*
X520320D01*
G01X513120D02*
X516320D01*
G01X505640Y376802D02*
X502440D01*
G01X505640Y383002D02*
Y376802D01*
G01X502440D02*
Y383002D01*
G01X505120Y367962D02*
X508320D01*
G01X509120D02*
X512320D01*
G01X501120D02*
X504320D01*
G01X506200Y387500D02*
X505987Y387542D01*
X505800Y387708D01*
X505640Y387958D01*
X505533Y388250D01*
X505480Y388583D01*
Y388917D01*
X505533Y389250D01*
X505640Y389542D01*
X505800Y389792D01*
X505987Y389958D01*
X506200Y390000D01*
X506413Y389958D01*
X506600Y389792D01*
X506760Y389542D01*
X506867Y389250D01*
X506920Y388917D01*
Y388583D01*
X506867Y388250D01*
X506760Y387958D01*
X506600Y387708D01*
X506413Y387542D01*
X506200Y387500D01*
G01X506413Y388167D02*
X506733Y387500D01*
G01X508400D02*
Y390000D01*
X508080Y389500D01*
G01Y387500D02*
X508720D01*
G01X510920D02*
Y390000D01*
X509933Y388208D01*
X511267D01*
G01X512213Y388000D02*
X512373Y387708D01*
X512587Y387542D01*
X512827Y387500D01*
X513040Y387542D01*
X513253Y387750D01*
X513387Y388000D01*
X513413Y388250D01*
X513360Y388542D01*
X513173Y388750D01*
X512987Y388833D01*
X512747D01*
G01X512987D02*
X513147Y388958D01*
X513280Y389167D01*
X513333Y389417D01*
X513280Y389667D01*
X513147Y389875D01*
X512907Y390000D01*
X512667Y389958D01*
X512427Y389792D01*
G01X516120Y391262D02*
Y397462D01*
G01X519320Y391262D02*
X516120D01*
G01X515320D02*
X512120D01*
G01X515320Y397462D02*
Y391262D01*
G01X512120D02*
Y397462D01*
G01X502440Y383002D02*
X505640D01*
G01X511320Y391262D02*
X508120D01*
G01X511320Y397462D02*
Y391262D01*
G01X508120D02*
Y397462D01*
G01X504120Y391262D02*
Y397462D01*
G01X507320Y391262D02*
X504120D01*
G01X507320Y397462D02*
Y391262D01*
G01X519500Y404350D02*
X519448Y404043D01*
X519242Y403775D01*
X518932Y403545D01*
X518570Y403392D01*
X518157Y403315D01*
X517743D01*
X517330Y403392D01*
X516968Y403545D01*
X516658Y403775D01*
X516452Y404043D01*
X516400Y404350D01*
X516452Y404657D01*
X516658Y404925D01*
X516968Y405155D01*
X517330Y405308D01*
X517743Y405385D01*
X518157D01*
X518570Y405308D01*
X518932Y405155D01*
X519242Y404925D01*
X519448Y404657D01*
X519500Y404350D01*
G01X518673Y404657D02*
X519500Y405117D01*
G01Y407450D02*
X516400D01*
X517020Y406990D01*
G01X519500D02*
Y407910D01*
G01Y411010D02*
X516400D01*
X518622Y409592D01*
Y411508D01*
G01X519500Y413650D02*
X516400D01*
X517020Y413190D01*
G01X519500D02*
Y414110D01*
G01X514944Y402944D02*
X505496D01*
Y413780D01*
X514944D01*
Y410362D01*
X513220Y408362D01*
X514944Y406362D01*
Y402944D01*
G01X516120Y397462D02*
X519320D01*
G01X512120D02*
X515320D01*
G01X508120D02*
X511320D01*
G01X504120D02*
X507320D01*
G01X501170Y429462D02*
Y423262D01*
G01X506620Y419262D02*
Y422462D01*
G01X512820Y419262D02*
X506620D01*
G01X512820Y422462D02*
Y419262D01*
G01X506620Y422462D02*
X512820D01*
G01X512997Y435899D02*
Y433677D01*
X513150Y433212D01*
X513457Y432902D01*
X513840Y432799D01*
X514223Y432902D01*
X514530Y433212D01*
X514683Y433677D01*
Y435899D01*
G01X516212Y435382D02*
X516442Y435692D01*
X516710Y435847D01*
X517017Y435899D01*
X517400Y435796D01*
X517668Y435537D01*
X517745Y435227D01*
X517707Y434917D01*
X517553Y434659D01*
X516787Y434142D01*
X516442Y433781D01*
X516212Y433264D01*
X516135Y432799D01*
X517745D01*
G01X520040D02*
Y435899D01*
X519580Y435279D01*
G01Y432799D02*
X520500D01*
G01X522297Y433264D02*
X522527Y433006D01*
X522795Y432851D01*
X523140Y432799D01*
X523485Y432902D01*
X523753Y433109D01*
X523945Y433471D01*
X523983Y433884D01*
X523907Y434297D01*
X523715Y434556D01*
X523447Y434762D01*
X523178Y434814D01*
X522910Y434762D01*
X522565Y434556D01*
X522680Y435899D01*
X523715D01*
G01X510633Y437920D02*
Y450401D01*
G01X525987Y437723D02*
X510633D01*
G01Y450401D02*
X525987D01*
G01X511082Y458633D02*
X523286D01*
G01X511082Y472281D02*
Y458633D01*
G01X523286Y472281D02*
X511082D01*
G01X504769Y468596D02*
X501569D01*
G01X504769Y474796D02*
Y468596D01*
G01X501569Y474796D02*
X504769D01*
G01X501569Y468596D02*
Y474796D01*
G01X515300Y493512D02*
Y496712D01*
G01X521500Y493512D02*
X515300D01*
G01Y490712D02*
X521500D01*
G01X515300Y487512D02*
Y490712D01*
G01X521500Y487512D02*
X515300D01*
G01X515420Y485552D02*
X518620D01*
G01X515420Y479352D02*
Y485552D01*
G01X518620Y479352D02*
X515420D01*
G01X514486Y509869D02*
Y513069D01*
G01X520686Y509869D02*
X514486D01*
G01Y502069D02*
X520686D01*
G01X514486Y498869D02*
Y502069D01*
G01X520686Y498869D02*
X514486D01*
G01Y507569D02*
X520686D01*
G01X514486Y504369D02*
Y507569D01*
G01X520686Y504369D02*
X514486D01*
G01X502418Y510219D02*
Y513419D01*
G01X508618Y510219D02*
X502418D01*
G01X508618Y513419D02*
Y510219D01*
G01X502418Y506219D02*
Y509419D01*
G01X508618Y506219D02*
X502418D01*
G01X508618Y509419D02*
Y506219D01*
G01X502418Y509419D02*
X508618D01*
G01X515300Y496712D02*
X521500D01*
G01X514486Y513069D02*
X520686D01*
G01X502418Y513419D02*
X508618D01*
G01X514486Y518569D02*
X520686D01*
G01X514486Y515369D02*
Y518569D01*
G01X520686Y515369D02*
X514486D01*
G01X502418Y518219D02*
Y521419D01*
G01X508618Y518219D02*
X502418D01*
G01X508618Y521419D02*
Y518219D01*
G01X502418Y521419D02*
X508618D01*
G01X502418Y514219D02*
Y517419D01*
G01X508618Y514219D02*
X502418D01*
G01X508618Y517419D02*
Y514219D01*
G01X502418Y517419D02*
X508618D01*
G01X514486Y526369D02*
Y529569D01*
G01X520686Y526369D02*
X514486D01*
G01Y524069D02*
X520686D01*
G01X514486Y520869D02*
Y524069D01*
G01X520686Y520869D02*
X514486D01*
G01X502418Y526219D02*
Y529419D01*
G01X508618Y526219D02*
X502418D01*
G01X508618Y529419D02*
Y526219D01*
G01X502418Y522219D02*
Y525419D01*
G01X508618Y522219D02*
X502418D01*
G01X508618Y525419D02*
Y522219D01*
G01X502418Y525419D02*
X508618D01*
G01X514486Y529569D02*
X520686D01*
G01X502418Y529419D02*
X508618D01*
G01X514486Y541419D02*
X520686D01*
G01X514486Y538219D02*
Y541419D01*
G01X520686Y538219D02*
X514486D01*
G01X502418D02*
Y541419D01*
G01X508618Y538219D02*
X502418D01*
G01X508618Y541419D02*
Y538219D01*
G01X502418Y541419D02*
X508618D01*
G01X519543Y599224D02*
X519905Y599454D01*
X520111Y599760D01*
X520163Y600105D01*
X520111Y600412D01*
X519853Y600719D01*
X519543Y600910D01*
X519233Y600949D01*
X518871Y600872D01*
X518613Y600604D01*
X518510Y600335D01*
Y599990D01*
G01Y600335D02*
X518355Y600565D01*
X518096Y600757D01*
X517786Y600834D01*
X517476Y600757D01*
X517218Y600565D01*
X517063Y600220D01*
X517115Y599875D01*
X517321Y599530D01*
G01X503260Y617212D02*
Y614012D01*
G01X513900Y614142D02*
Y617342D01*
G01D02*
X520100D01*
G01Y614142D02*
X513900D01*
G01X535226Y1171318D02*
G03I-9950J0D01*
G01X509283Y1254262D02*
Y1257362D01*
X510203D01*
X510510Y1257207D01*
X510740Y1256845D01*
X510817Y1256432D01*
X510740Y1256019D01*
X510548Y1255709D01*
X510203Y1255554D01*
X509283D01*
G01X512383Y1257362D02*
Y1254262D01*
X513917D01*
G01X515522Y1256845D02*
X515752Y1257155D01*
X516020Y1257310D01*
X516327Y1257362D01*
X516710Y1257259D01*
X516978Y1257000D01*
X517055Y1256690D01*
X517017Y1256380D01*
X516863Y1256122D01*
X516097Y1255605D01*
X515752Y1255244D01*
X515522Y1254727D01*
X515445Y1254262D01*
X517055D01*
G01X519350D02*
X519618Y1254314D01*
X519925Y1254469D01*
X520117Y1254727D01*
X520193Y1255089D01*
X520117Y1255450D01*
X519887Y1255760D01*
X519542Y1255915D01*
X519158D01*
X518928Y1256019D01*
X518737Y1256277D01*
X518660Y1256639D01*
X518775Y1257000D01*
X519043Y1257259D01*
X519350Y1257362D01*
X519657Y1257259D01*
X519925Y1257000D01*
X520040Y1256639D01*
X519963Y1256277D01*
X519772Y1256019D01*
X519542Y1255915D01*
X519158D01*
X518813Y1255760D01*
X518583Y1255450D01*
X518507Y1255089D01*
X518583Y1254727D01*
X518775Y1254469D01*
X519082Y1254314D01*
X519350Y1254262D01*
G01X509453Y1249222D02*
Y1252322D01*
X510373D01*
X510680Y1252167D01*
X510910Y1251805D01*
X510987Y1251392D01*
X510910Y1250979D01*
X510718Y1250669D01*
X510373Y1250514D01*
X509453D01*
G01X512553Y1252322D02*
Y1249222D01*
X514087D01*
G01X515692Y1251805D02*
X515922Y1252115D01*
X516190Y1252270D01*
X516497Y1252322D01*
X516880Y1252219D01*
X517148Y1251960D01*
X517225Y1251650D01*
X517187Y1251340D01*
X517033Y1251082D01*
X516267Y1250565D01*
X515922Y1250204D01*
X515692Y1249687D01*
X515615Y1249222D01*
X517225D01*
G01X518868Y1249584D02*
X519137Y1249325D01*
X519443Y1249222D01*
X519750Y1249325D01*
X520018Y1249635D01*
X520210Y1250100D01*
X520287Y1250565D01*
Y1251134D01*
X520210Y1251599D01*
X520018Y1252012D01*
X519788Y1252219D01*
X519520Y1252322D01*
X519213Y1252219D01*
X518983Y1252012D01*
X518830Y1251702D01*
X518753Y1251289D01*
X518830Y1250927D01*
X519022Y1250565D01*
X519252Y1250359D01*
X519520Y1250307D01*
X519827Y1250410D01*
X520057Y1250669D01*
X520287Y1251134D01*
G01X515824Y1348493D02*
X519024D01*
G01X515824Y1342293D02*
Y1348493D01*
G01X519024Y1342293D02*
X515824D01*
G01X501058Y1348439D02*
Y1342239D01*
G01X502209Y1345921D02*
Y1349121D01*
G01X508409Y1345921D02*
X502209D01*
G01X508409Y1349121D02*
Y1345921D01*
G01X502209Y1349121D02*
X508409D01*
G01X514982Y1342293D02*
X511782D01*
G01X514982Y1348493D02*
Y1342293D01*
G01X511782Y1348493D02*
X514982D01*
G01X511782Y1342293D02*
Y1348493D01*
G01X503582Y1384027D02*
Y1378027D01*
G01X503623Y1392027D02*
Y1386027D01*
G01Y1400027D02*
Y1394027D01*
G01X504496Y1419917D02*
X507696D01*
G01X504496Y1413717D02*
Y1419917D01*
G01X507696Y1413717D02*
X504496D01*
G01X507696Y1419917D02*
Y1413717D01*
G01X510771Y1424094D02*
Y1420894D01*
G01X504571D02*
Y1424094D01*
G01X510771Y1420894D02*
X504571D01*
G01X510123Y1413047D02*
Y1416147D01*
X511043D01*
X511350Y1415992D01*
X511580Y1415630D01*
X511657Y1415217D01*
X511580Y1414804D01*
X511388Y1414494D01*
X511043Y1414339D01*
X510123D01*
G01X513147Y1416147D02*
Y1413925D01*
X513300Y1413460D01*
X513607Y1413150D01*
X513990Y1413047D01*
X514373Y1413150D01*
X514680Y1413460D01*
X514833Y1413925D01*
Y1416147D01*
G01X517090Y1413047D02*
X517358Y1413099D01*
X517665Y1413254D01*
X517857Y1413512D01*
X517933Y1413874D01*
X517857Y1414235D01*
X517627Y1414545D01*
X517282Y1414700D01*
X516898D01*
X516668Y1414804D01*
X516477Y1415062D01*
X516400Y1415424D01*
X516515Y1415785D01*
X516783Y1416044D01*
X517090Y1416147D01*
X517397Y1416044D01*
X517665Y1415785D01*
X517780Y1415424D01*
X517703Y1415062D01*
X517512Y1414804D01*
X517282Y1414700D01*
X516898D01*
X516553Y1414545D01*
X516323Y1414235D01*
X516247Y1413874D01*
X516323Y1413512D01*
X516515Y1413254D01*
X516822Y1413099D01*
X517090Y1413047D01*
G01X520190Y1416147D02*
X519883Y1416044D01*
X519653Y1415785D01*
X519500Y1415475D01*
X519385Y1415062D01*
X519347Y1414597D01*
X519385Y1414132D01*
X519500Y1413719D01*
X519653Y1413409D01*
X519883Y1413150D01*
X520190Y1413047D01*
X520497Y1413150D01*
X520727Y1413409D01*
X520880Y1413719D01*
X520995Y1414132D01*
X521033Y1414597D01*
X520995Y1415062D01*
X520880Y1415475D01*
X520727Y1415785D01*
X520497Y1416044D01*
X520190Y1416147D01*
G01X512953Y1426922D02*
Y1430022D01*
X513873D01*
X514180Y1429867D01*
X514410Y1429505D01*
X514487Y1429092D01*
X514410Y1428679D01*
X514218Y1428369D01*
X513873Y1428214D01*
X512953D01*
G01X516053Y1430022D02*
Y1426922D01*
X517587D01*
G01X519920D02*
Y1430022D01*
X519460Y1429402D01*
G01Y1426922D02*
X520380D01*
G01X523020D02*
Y1430022D01*
X522560Y1429402D01*
G01Y1426922D02*
X523480D01*
G01X525468Y1427284D02*
X525737Y1427025D01*
X526043Y1426922D01*
X526350Y1427025D01*
X526618Y1427335D01*
X526810Y1427800D01*
X526887Y1428265D01*
Y1428834D01*
X526810Y1429299D01*
X526618Y1429712D01*
X526388Y1429919D01*
X526120Y1430022D01*
X525813Y1429919D01*
X525583Y1429712D01*
X525430Y1429402D01*
X525353Y1428989D01*
X525430Y1428627D01*
X525622Y1428265D01*
X525852Y1428059D01*
X526120Y1428007D01*
X526427Y1428110D01*
X526657Y1428369D01*
X526887Y1428834D01*
G01X508115Y1429288D02*
X502126D01*
G01X508115Y1458028D02*
Y1429288D01*
G01X504571Y1424094D02*
X510771D01*
G01X539864Y1444874D02*
G03I-13386J0D01*
G01X513092D02*
X539864D01*
G01X502026Y1458028D02*
X508115D01*
G01X503428Y1656055D02*
X503658Y1656365D01*
X503926Y1656520D01*
X504233Y1656572D01*
X504616Y1656469D01*
X504884Y1656210D01*
X504961Y1655900D01*
X504923Y1655590D01*
X504769Y1655332D01*
X504003Y1654815D01*
X503658Y1654454D01*
X503428Y1653937D01*
X503351Y1653472D01*
X504961D01*
G01X511187Y1654092D02*
X511417Y1653730D01*
X511723Y1653524D01*
X512068Y1653472D01*
X512375Y1653524D01*
X512682Y1653782D01*
X512873Y1654092D01*
X512912Y1654402D01*
X512835Y1654764D01*
X512567Y1655022D01*
X512298Y1655125D01*
X511953D01*
G01X512298D02*
X512528Y1655280D01*
X512720Y1655539D01*
X512797Y1655849D01*
X512720Y1656159D01*
X512528Y1656417D01*
X512183Y1656572D01*
X511838Y1656520D01*
X511493Y1656314D01*
G01X505262Y1736629D02*
X504196D01*
Y1739129D01*
X505262D01*
G01X504836Y1737921D02*
X504196D01*
G01X506342Y1736629D02*
Y1739129D01*
X506876D01*
X507089Y1739004D01*
X507249Y1738837D01*
X507382Y1738587D01*
X507489Y1738296D01*
X507516Y1737879D01*
X507489Y1737462D01*
X507382Y1737171D01*
X507249Y1736921D01*
X507089Y1736754D01*
X506876Y1736629D01*
X506342D01*
G01X509289Y1737879D02*
X509822D01*
Y1737129D01*
X509662Y1736879D01*
X509476Y1736712D01*
X509209Y1736629D01*
X508942Y1736712D01*
X508756Y1736879D01*
X508596Y1737129D01*
X508489Y1737421D01*
X508436Y1737754D01*
Y1738046D01*
X508489Y1738296D01*
X508596Y1738587D01*
X508756Y1738837D01*
X508916Y1739004D01*
X509129Y1739129D01*
X509316D01*
X509529Y1739046D01*
X509689Y1738879D01*
G01X511862Y1736629D02*
X510796D01*
Y1739129D01*
X511862D01*
G01X511436Y1737921D02*
X510796D01*
G01X515729Y1736629D02*
X515516Y1736671D01*
X515329Y1736837D01*
X515169Y1737087D01*
X515062Y1737379D01*
X515009Y1737712D01*
Y1738046D01*
X515062Y1738379D01*
X515169Y1738671D01*
X515329Y1738921D01*
X515516Y1739087D01*
X515729Y1739129D01*
X515942Y1739087D01*
X516129Y1738921D01*
X516289Y1738671D01*
X516396Y1738379D01*
X516449Y1738046D01*
Y1737712D01*
X516396Y1737379D01*
X516289Y1737087D01*
X516129Y1736837D01*
X515942Y1736671D01*
X515729Y1736629D01*
G01X517422D02*
Y1739129D01*
X518436D01*
G01X518062Y1737921D02*
X517422D01*
G01X521742Y1736629D02*
Y1739129D01*
X522276D01*
X522489Y1739004D01*
X522649Y1738837D01*
X522782Y1738587D01*
X522889Y1738296D01*
X522916Y1737879D01*
X522889Y1737462D01*
X522782Y1737171D01*
X522649Y1736921D01*
X522489Y1736754D01*
X522276Y1736629D01*
X521742D01*
G01X523862D02*
X524529Y1739129D01*
X525196Y1736629D01*
G01X524956Y1737504D02*
X524102D01*
G01X526142Y1739129D02*
Y1737337D01*
X526249Y1736962D01*
X526462Y1736712D01*
X526729Y1736629D01*
X526996Y1736712D01*
X527209Y1736962D01*
X527316Y1737337D01*
Y1739129D01*
G01X529089Y1737879D02*
X529622D01*
Y1737129D01*
X529462Y1736879D01*
X529276Y1736712D01*
X529009Y1736629D01*
X528742Y1736712D01*
X528556Y1736879D01*
X528396Y1737129D01*
X528289Y1737421D01*
X528236Y1737754D01*
Y1738046D01*
X528289Y1738296D01*
X528396Y1738587D01*
X528556Y1738837D01*
X528716Y1739004D01*
X528929Y1739129D01*
X529116D01*
X529329Y1739046D01*
X529489Y1738879D01*
G01X530569Y1736629D02*
Y1739129D01*
G01X531689D02*
Y1736629D01*
G01Y1737879D02*
X530569D01*
G01X533329Y1739129D02*
Y1736629D01*
G01X532716Y1739129D02*
X533942D01*
G01X536062Y1736629D02*
X534996D01*
Y1739129D01*
X536062D01*
G01X535636Y1737921D02*
X534996D01*
G01X537196Y1736629D02*
Y1739129D01*
X537862D01*
X538076Y1739004D01*
X538209Y1738837D01*
X538262Y1738504D01*
X538209Y1738171D01*
X538049Y1737962D01*
X537862Y1737837D01*
X537196D01*
G01X537862D02*
X538262Y1736629D01*
G01X542716Y1738921D02*
X542556Y1739046D01*
X542369Y1739129D01*
X542156D01*
X541916Y1739004D01*
X541729Y1738796D01*
X541596Y1738546D01*
X541489Y1738129D01*
X541462Y1737754D01*
X541516Y1737379D01*
X541596Y1737129D01*
X541756Y1736879D01*
X541942Y1736712D01*
X542129Y1736629D01*
X542316D01*
X542502Y1736712D01*
X542662Y1736837D01*
X542796Y1737004D01*
G01X543662Y1736629D02*
X544329Y1739129D01*
X544996Y1736629D01*
G01X544756Y1737504D02*
X543902D01*
G01X545996Y1736629D02*
Y1739129D01*
X546662D01*
X546876Y1739004D01*
X547009Y1738837D01*
X547062Y1738504D01*
X547009Y1738171D01*
X546849Y1737962D01*
X546662Y1737837D01*
X545996D01*
G01X546662D02*
X547062Y1736629D01*
G01X548142D02*
Y1739129D01*
X548676D01*
X548889Y1739004D01*
X549049Y1738837D01*
X549182Y1738587D01*
X549289Y1738296D01*
X549316Y1737879D01*
X549289Y1737462D01*
X549182Y1737171D01*
X549049Y1736921D01*
X548889Y1736754D01*
X548676Y1736629D01*
X548142D01*
G01X502179Y1736412D02*
X503079Y1737312D01*
G01X518620Y87962D02*
Y81762D01*
G01X533360Y71930D02*
X524000D01*
G01X523507Y123462D02*
Y121240D01*
X523660Y120775D01*
X523967Y120465D01*
X524350Y120362D01*
X524733Y120465D01*
X525040Y120775D01*
X525193Y121240D01*
Y123462D01*
G01X526722Y122945D02*
X526952Y123255D01*
X527220Y123410D01*
X527527Y123462D01*
X527910Y123359D01*
X528178Y123100D01*
X528255Y122790D01*
X528217Y122480D01*
X528063Y122222D01*
X527297Y121705D01*
X526952Y121344D01*
X526722Y120827D01*
X526645Y120362D01*
X528255D01*
G01X531010D02*
Y123462D01*
X529592Y121240D01*
X531508D01*
G01X532807Y120827D02*
X533037Y120569D01*
X533305Y120414D01*
X533650Y120362D01*
X533995Y120465D01*
X534263Y120672D01*
X534455Y121034D01*
X534493Y121447D01*
X534417Y121860D01*
X534225Y122119D01*
X533957Y122325D01*
X533688Y122377D01*
X533420Y122325D01*
X533075Y122119D01*
X533190Y123462D01*
X534225D01*
G01X528660Y127402D02*
Y136202D01*
G01X534460D02*
X528660D01*
G01X542260Y127402D02*
X528660D01*
G01X518747Y144322D02*
Y142100D01*
X518900Y141635D01*
X519207Y141325D01*
X519590Y141222D01*
X519973Y141325D01*
X520280Y141635D01*
X520433Y142100D01*
Y144322D01*
G01X521962Y143805D02*
X522192Y144115D01*
X522460Y144270D01*
X522767Y144322D01*
X523150Y144219D01*
X523418Y143960D01*
X523495Y143650D01*
X523457Y143340D01*
X523303Y143082D01*
X522537Y142565D01*
X522192Y142204D01*
X521962Y141687D01*
X521885Y141222D01*
X523495D01*
G01X526250D02*
Y144322D01*
X524832Y142100D01*
X526748D01*
G01X528162Y142514D02*
X528430Y142875D01*
X528660Y143082D01*
X528967Y143185D01*
X529235Y143082D01*
X529427Y142875D01*
X529580Y142565D01*
X529618Y142204D01*
X529580Y141894D01*
X529427Y141584D01*
X529197Y141325D01*
X528928Y141222D01*
X528622Y141325D01*
X528353Y141635D01*
X528200Y142100D01*
X528162Y142617D01*
X528238Y143289D01*
X528353Y143650D01*
X528545Y144012D01*
X528813Y144270D01*
X529082Y144322D01*
X529350Y144219D01*
X529542Y143960D01*
G01X528660Y145402D02*
Y154202D01*
G01X542260Y145402D02*
X528660D01*
G01X528115Y160326D02*
Y169126D01*
G01X541715Y160326D02*
X528115D01*
G01X534460Y154202D02*
X528660D01*
G01X521925Y170043D02*
Y166843D01*
G01X528182Y173736D02*
Y171514D01*
X528335Y171049D01*
X528642Y170739D01*
X529025Y170636D01*
X529408Y170739D01*
X529715Y171049D01*
X529868Y171514D01*
Y173736D01*
G01X531397Y173219D02*
X531627Y173529D01*
X531895Y173684D01*
X532202Y173736D01*
X532585Y173633D01*
X532853Y173374D01*
X532930Y173064D01*
X532892Y172754D01*
X532738Y172496D01*
X531972Y171979D01*
X531627Y171618D01*
X531397Y171101D01*
X531320Y170636D01*
X532930D01*
G01X534382Y171101D02*
X534612Y170843D01*
X534880Y170688D01*
X535225Y170636D01*
X535570Y170739D01*
X535838Y170946D01*
X536030Y171308D01*
X536068Y171721D01*
X535992Y172134D01*
X535800Y172393D01*
X535532Y172599D01*
X535263Y172651D01*
X534995Y172599D01*
X534650Y172393D01*
X534765Y173736D01*
X535800D01*
G01X537673Y170998D02*
X537942Y170739D01*
X538248Y170636D01*
X538555Y170739D01*
X538823Y171049D01*
X539015Y171514D01*
X539092Y171979D01*
Y172548D01*
X539015Y173013D01*
X538823Y173426D01*
X538593Y173633D01*
X538325Y173736D01*
X538018Y173633D01*
X537788Y173426D01*
X537635Y173116D01*
X537558Y172703D01*
X537635Y172341D01*
X537827Y171979D01*
X538057Y171773D01*
X538325Y171721D01*
X538632Y171824D01*
X538862Y172083D01*
X539092Y172548D01*
G01X533915Y169126D02*
X528115D01*
G01X530473Y177031D02*
Y185693D01*
G01X540967Y177031D02*
X530473D01*
G01X531270Y186929D02*
X530963Y186981D01*
X530695Y187187D01*
X530465Y187497D01*
X530312Y187859D01*
X530235Y188272D01*
Y188686D01*
X530312Y189099D01*
X530465Y189461D01*
X530695Y189771D01*
X530963Y189977D01*
X531270Y190029D01*
X531577Y189977D01*
X531845Y189771D01*
X532075Y189461D01*
X532228Y189099D01*
X532305Y188686D01*
Y188272D01*
X532228Y187859D01*
X532075Y187497D01*
X531845Y187187D01*
X531577Y186981D01*
X531270Y186929D01*
G01X531577Y187756D02*
X532037Y186929D01*
G01X533718Y187291D02*
X533987Y187032D01*
X534293Y186929D01*
X534600Y187032D01*
X534868Y187342D01*
X535060Y187807D01*
X535137Y188272D01*
Y188841D01*
X535060Y189306D01*
X534868Y189719D01*
X534638Y189926D01*
X534370Y190029D01*
X534063Y189926D01*
X533833Y189719D01*
X533680Y189409D01*
X533603Y188996D01*
X533680Y188634D01*
X533872Y188272D01*
X534102Y188066D01*
X534370Y188014D01*
X534677Y188117D01*
X534907Y188376D01*
X535137Y188841D01*
G01X536627Y187394D02*
X536857Y187136D01*
X537125Y186981D01*
X537470Y186929D01*
X537815Y187032D01*
X538083Y187239D01*
X538275Y187601D01*
X538313Y188014D01*
X538237Y188427D01*
X538045Y188686D01*
X537777Y188892D01*
X537508Y188944D01*
X537240Y188892D01*
X536895Y188686D01*
X537010Y190029D01*
X538045D01*
G01X530473Y185693D02*
X533820D01*
G01X517404Y266563D02*
Y260363D01*
G01X525197Y283464D02*
Y273622D01*
G01X528220Y286362D02*
Y298362D01*
G01X534220Y286362D02*
X528220D01*
G01Y298362D02*
X534220D01*
G01X527320Y289262D02*
X524120D01*
G01X527320Y295462D02*
Y289262D01*
G01X524120Y295462D02*
X527320D01*
G01X524120Y289262D02*
Y295462D01*
G01X522530Y308355D02*
Y287955D01*
G01X518530Y297955D02*
X520330Y300555D01*
G01X528277Y316132D02*
Y319232D01*
X529043D01*
X529350Y319077D01*
X529580Y318870D01*
X529772Y318560D01*
X529925Y318199D01*
X529963Y317682D01*
X529925Y317165D01*
X529772Y316804D01*
X529580Y316494D01*
X529350Y316287D01*
X529043Y316132D01*
X528277D01*
G01X532220D02*
Y319232D01*
X531760Y318612D01*
G01Y316132D02*
X532680D01*
G01X535780D02*
Y319232D01*
X534362Y317010D01*
X536278D01*
G01X538420Y316132D02*
Y319232D01*
X537960Y318612D01*
G01Y316132D02*
X538880D01*
G01X520320Y367962D02*
Y361762D01*
G01X530120D02*
Y367962D01*
G01X533320Y361762D02*
X530120D01*
G01X533320Y367962D02*
Y361762D01*
G01X522120D02*
Y367962D01*
G01X525320Y361762D02*
X522120D01*
G01X525320Y367962D02*
Y361762D01*
G01X529320D02*
X526120D01*
G01X529320Y367962D02*
Y361762D01*
G01X526120D02*
Y367962D01*
G01X533944Y373944D02*
X524496D01*
Y384780D01*
X533944D01*
Y381362D01*
X532220Y379362D01*
X533944Y377362D01*
Y373944D01*
G01X530120Y367962D02*
X533320D01*
G01X522430Y379282D02*
X519230D01*
G01X522430Y385482D02*
Y379282D01*
G01X519230D02*
Y385482D01*
G01X522120Y367962D02*
X525320D01*
G01X526120D02*
X529320D01*
G01X519320Y397462D02*
Y391262D01*
G01X531320D02*
X528120D01*
G01X531320Y397462D02*
Y391262D01*
G01X528120D02*
Y397462D01*
G01X532120Y391262D02*
Y397462D01*
G01X535320Y391262D02*
X532120D01*
G01X519230Y385482D02*
X522430D01*
G01X527320Y391262D02*
X524120D01*
G01X527320Y397462D02*
Y391262D01*
G01X524120D02*
Y397462D01*
G01X520120Y391262D02*
Y397462D01*
G01X523320Y391262D02*
X520120D01*
G01X523320Y397462D02*
Y391262D01*
G01X530944Y402944D02*
X521496D01*
Y413780D01*
X530944D01*
Y410362D01*
X529220Y408362D01*
X530944Y406362D01*
Y402944D01*
G01X528120Y397462D02*
X531320D01*
G01X532120D02*
X535320D01*
G01X524120D02*
X527320D01*
G01X520120D02*
X523320D01*
G01X521620Y419262D02*
Y422462D01*
G01X527820Y419262D02*
X521620D01*
G01X527820Y422462D02*
Y419262D01*
G01X521620Y422462D02*
X527820D01*
G01X525987Y450401D02*
Y437723D01*
G01X526337Y462242D02*
Y460020D01*
X526490Y459555D01*
X526797Y459245D01*
X527180Y459142D01*
X527563Y459245D01*
X527870Y459555D01*
X528023Y460020D01*
Y462242D01*
G01X529437Y459607D02*
X529667Y459349D01*
X529935Y459194D01*
X530280Y459142D01*
X530625Y459245D01*
X530893Y459452D01*
X531085Y459814D01*
X531123Y460227D01*
X531047Y460640D01*
X530855Y460899D01*
X530587Y461105D01*
X530318Y461157D01*
X530050Y461105D01*
X529705Y460899D01*
X529820Y462242D01*
X530855D01*
G01X533380D02*
X533073Y462139D01*
X532843Y461880D01*
X532690Y461570D01*
X532575Y461157D01*
X532537Y460692D01*
X532575Y460227D01*
X532690Y459814D01*
X532843Y459504D01*
X533073Y459245D01*
X533380Y459142D01*
X533687Y459245D01*
X533917Y459504D01*
X534070Y459814D01*
X534185Y460227D01*
X534223Y460692D01*
X534185Y461157D01*
X534070Y461570D01*
X533917Y461880D01*
X533687Y462139D01*
X533380Y462242D01*
G01X523286Y458633D02*
Y462855D01*
G01X523410Y456662D02*
Y453462D01*
G01X517210Y456662D02*
X523410D01*
G01X517210Y453462D02*
Y456662D01*
G01X523410Y453462D02*
X517210D01*
G01X523286Y462855D02*
X520684Y465457D01*
G01X523286Y468059D02*
Y472281D01*
G01X520684Y465457D02*
X523286Y468059D01*
G01X521280Y480092D02*
X527480D01*
Y476892D01*
X521280D01*
Y480092D01*
G01X525300Y493512D02*
Y496712D01*
G01X531500Y493512D02*
X525300D01*
G01X531500Y496712D02*
Y493512D01*
G01X521500Y496712D02*
Y493512D01*
G01Y490712D02*
Y487512D01*
G01X525300D02*
Y490712D01*
G01X531500Y487512D02*
X525300D01*
G01X531500Y490712D02*
Y487512D01*
G01X525300Y490712D02*
X531500D01*
G01X518620Y485552D02*
Y479352D01*
G01X531490Y501822D02*
Y498622D01*
G01X525290Y501822D02*
X531490D01*
G01X525290Y498622D02*
Y501822D01*
G01X531490Y498622D02*
X525290D01*
G01X520686Y513069D02*
Y509869D01*
G01Y502069D02*
Y498869D01*
G01Y507569D02*
Y504369D01*
G01X525300Y496712D02*
X531500D01*
G01X520686Y518569D02*
Y515369D01*
G01Y529569D02*
Y526369D01*
G01Y524069D02*
Y520869D01*
G01Y541419D02*
Y538219D01*
G01X520100Y617342D02*
Y614142D01*
G01X526955Y794318D02*
Y797418D01*
G01X528565D02*
Y794318D01*
G01Y795868D02*
X526955D01*
G01X530860Y794318D02*
Y797418D01*
X530400Y796798D01*
G01Y794318D02*
X531320D01*
G01X533960D02*
X534228Y794370D01*
X534535Y794525D01*
X534727Y794783D01*
X534803Y795145D01*
X534727Y795506D01*
X534497Y795816D01*
X534152Y795971D01*
X533768D01*
X533538Y796075D01*
X533347Y796333D01*
X533270Y796695D01*
X533385Y797056D01*
X533653Y797315D01*
X533960Y797418D01*
X534267Y797315D01*
X534535Y797056D01*
X534650Y796695D01*
X534573Y796333D01*
X534382Y796075D01*
X534152Y795971D01*
X533768D01*
X533423Y795816D01*
X533193Y795506D01*
X533117Y795145D01*
X533193Y794783D01*
X533385Y794525D01*
X533692Y794370D01*
X533960Y794318D01*
G01X541190Y811121D02*
G03I-9950J0D01*
G01X526415Y1194402D02*
Y1197502D01*
G01X528025D02*
Y1194402D01*
G01Y1195952D02*
X526415D01*
G01X530320Y1194402D02*
Y1197502D01*
X529860Y1196882D01*
G01Y1194402D02*
X530780D01*
G01X532692Y1195694D02*
X532960Y1196055D01*
X533190Y1196262D01*
X533497Y1196365D01*
X533765Y1196262D01*
X533957Y1196055D01*
X534110Y1195745D01*
X534148Y1195384D01*
X534110Y1195074D01*
X533957Y1194764D01*
X533727Y1194505D01*
X533458Y1194402D01*
X533152Y1194505D01*
X532883Y1194815D01*
X532730Y1195280D01*
X532692Y1195797D01*
X532768Y1196469D01*
X532883Y1196830D01*
X533075Y1197192D01*
X533343Y1197450D01*
X533612Y1197502D01*
X533880Y1197399D01*
X534072Y1197140D01*
G01X528049Y1272969D02*
Y1276069D01*
X528969D01*
X529276Y1275914D01*
X529506Y1275552D01*
X529583Y1275139D01*
X529506Y1274726D01*
X529314Y1274416D01*
X528969Y1274261D01*
X528049D01*
G01X531149Y1276069D02*
Y1272969D01*
X532683D01*
G01X534288Y1275552D02*
X534518Y1275862D01*
X534786Y1276017D01*
X535093Y1276069D01*
X535476Y1275966D01*
X535744Y1275707D01*
X535821Y1275397D01*
X535783Y1275087D01*
X535629Y1274829D01*
X534863Y1274312D01*
X534518Y1273951D01*
X534288Y1273434D01*
X534211Y1272969D01*
X535821D01*
G01X538039D02*
X538116Y1273641D01*
X538231Y1274209D01*
X538384Y1274726D01*
X538576Y1275294D01*
X538883Y1276069D01*
X537349D01*
G01X525384Y1268871D02*
Y1312179D01*
G01X520043Y1268871D02*
X525384D01*
G01X528221Y1291541D02*
Y1334849D01*
G01X533562Y1291541D02*
X528221D01*
G01X520236Y1315458D02*
X519443D01*
G01X520236Y1318058D02*
Y1315458D01*
G01X525384Y1312179D02*
X520043D01*
G01X532678Y1338256D02*
Y1340856D01*
G01X533471Y1338256D02*
X532678D01*
G01X520236Y1339080D02*
Y1336889D01*
G01X519503Y1339080D02*
X520236D01*
G01X528221Y1334849D02*
X533562D01*
G01X523738Y1337237D02*
Y1340437D01*
G01X529938Y1337237D02*
X523738D01*
G01X529938Y1340437D02*
Y1337237D01*
G01X522845Y1330717D02*
X526045D01*
G01X522845Y1324517D02*
Y1330717D01*
G01X526045Y1324517D02*
X522845D01*
G01X526045Y1330717D02*
Y1324517D01*
G01X532678Y1347467D02*
Y1349165D01*
G01X526847Y1352416D02*
X530047D01*
G01X526847Y1346216D02*
Y1352416D01*
G01X530047Y1346216D02*
X526847D01*
G01X530047Y1352416D02*
Y1346216D01*
G01X523738Y1340437D02*
X529938D01*
G01X519024Y1348493D02*
Y1342293D01*
G01X532678Y1361878D02*
X533686D01*
G01X532678Y1360024D02*
Y1361878D01*
G01X530010Y1371249D02*
X533210D01*
G01X530010Y1365049D02*
Y1371249D01*
G01X533210Y1365049D02*
X530010D01*
G01X533210Y1371249D02*
Y1365049D01*
G01X530047Y1356716D02*
X526847D01*
G01X530047Y1362916D02*
Y1356716D01*
G01X526847Y1362916D02*
X530047D01*
G01X526847Y1356716D02*
Y1362916D01*
G01X527432Y1413910D02*
Y1417010D01*
G01X529042D02*
Y1413910D01*
G01Y1415460D02*
X527432D01*
G01X531797Y1413910D02*
Y1417010D01*
X530379Y1414788D01*
X532295D01*
G01X533785Y1414272D02*
X534054Y1414013D01*
X534360Y1413910D01*
X534667Y1414013D01*
X534935Y1414323D01*
X535127Y1414788D01*
X535204Y1415253D01*
Y1415822D01*
X535127Y1416287D01*
X534935Y1416700D01*
X534705Y1416907D01*
X534437Y1417010D01*
X534130Y1416907D01*
X533900Y1416700D01*
X533747Y1416390D01*
X533670Y1415977D01*
X533747Y1415615D01*
X533939Y1415253D01*
X534169Y1415047D01*
X534437Y1414995D01*
X534744Y1415098D01*
X534974Y1415357D01*
X535204Y1415822D01*
G01X520364Y1653472D02*
Y1656572D01*
X518946Y1654350D01*
X520862D01*
G01X526935Y1653937D02*
X527165Y1653679D01*
X527433Y1653524D01*
X527778Y1653472D01*
X528123Y1653575D01*
X528391Y1653782D01*
X528583Y1654144D01*
X528621Y1654557D01*
X528545Y1654970D01*
X528353Y1655229D01*
X528085Y1655435D01*
X527816Y1655487D01*
X527548Y1655435D01*
X527203Y1655229D01*
X527318Y1656572D01*
X528353D01*
G01X534693Y82849D02*
X535000Y82591D01*
X535345Y82436D01*
X535651D01*
X535958Y82591D01*
X536188Y82849D01*
X536303Y83211D01*
X536226Y83573D01*
X536035Y83883D01*
X535690Y84089D01*
X535230Y84193D01*
X534961Y84399D01*
X534846Y84761D01*
X534923Y85123D01*
X535115Y85381D01*
X535383Y85536D01*
X535651D01*
X535920Y85433D01*
X536150Y85174D01*
G01X539441Y85278D02*
X539211Y85433D01*
X538943Y85536D01*
X538636D01*
X538291Y85381D01*
X538023Y85123D01*
X537831Y84813D01*
X537678Y84296D01*
X537640Y83831D01*
X537716Y83366D01*
X537831Y83056D01*
X538061Y82746D01*
X538330Y82539D01*
X538598Y82436D01*
X538866D01*
X539135Y82539D01*
X539365Y82694D01*
X539556Y82901D01*
G01X540701Y82436D02*
Y85536D01*
X541698Y82953D01*
X542695Y85536D01*
Y82436D01*
G01X548511Y84244D02*
X548243Y84451D01*
X548013Y84503D01*
X547706Y84399D01*
X547476Y84193D01*
X547323Y83831D01*
X547285Y83469D01*
X547323Y83108D01*
X547476Y82798D01*
X547706Y82539D01*
X548013Y82436D01*
X548281Y82539D01*
X548511Y82746D01*
G01X550998Y82436D02*
X550768Y82488D01*
X550538Y82694D01*
X550385Y83056D01*
X550308Y83469D01*
X550385Y83883D01*
X550538Y84244D01*
X550768Y84451D01*
X550998Y84503D01*
X551228Y84451D01*
X551458Y84244D01*
X551611Y83883D01*
X551650Y83469D01*
X551611Y83056D01*
X551458Y82694D01*
X551228Y82488D01*
X550998Y82436D01*
G01X553446D02*
Y84503D01*
G01Y83986D02*
X553600Y84244D01*
X553830Y84451D01*
X554136Y84503D01*
X554405Y84451D01*
X554635Y84244D01*
X554750Y83883D01*
Y82436D01*
G01X556546D02*
Y84503D01*
G01Y83986D02*
X556700Y84244D01*
X556930Y84451D01*
X557236Y84503D01*
X557505Y84451D01*
X557735Y84244D01*
X557850Y83883D01*
Y82436D01*
G01X547760Y71930D02*
X546290D01*
G01X539080D02*
X536890D01*
G01X534720Y101752D02*
Y104952D01*
G01X540920Y101752D02*
X534720D01*
G01X540920Y104952D02*
Y101752D01*
G01X540940Y100772D02*
Y97572D01*
G01X534740Y100772D02*
X540940D01*
G01X534740Y97572D02*
Y100772D01*
G01X540940Y97572D02*
X534740D01*
G01X535384Y89483D02*
X535576Y89173D01*
X535806Y88966D01*
X536074Y88863D01*
X536381Y88966D01*
X536611Y89173D01*
X536841Y89483D01*
X536918Y89896D01*
Y91963D01*
G01X539711Y88863D02*
Y91963D01*
X538293Y89741D01*
X540209D01*
G01X542351Y88863D02*
Y91963D01*
X541891Y91343D01*
G01Y88863D02*
X542811D01*
G01X534790Y106462D02*
Y109662D01*
G01X540990Y106462D02*
X534790D01*
G01X540990Y109662D02*
Y106462D01*
G01X534790Y109662D02*
X540990D01*
G01X541000Y114112D02*
Y110912D01*
G01X534800Y114112D02*
X541000D01*
G01X534800Y110912D02*
Y114112D01*
G01X541000Y110912D02*
X534800D01*
G01X534720Y104952D02*
X540920D01*
G01X535460Y134702D02*
X534460Y136202D01*
G01X536460D02*
X535460Y134702D01*
G01X542260Y136202D02*
Y127402D01*
G01Y136202D02*
X536460D01*
G01X542260Y154202D02*
Y145402D01*
G01X545870Y148202D02*
Y151402D01*
G01X552070Y148202D02*
X545870D01*
G01Y151402D02*
X552070D01*
G01X534915Y167626D02*
X533915Y169126D01*
G01X535915D02*
X534915Y167626D01*
G01X541715Y169126D02*
Y160326D01*
G01X535460Y152702D02*
X534460Y154202D01*
G01X536460D02*
X535460Y152702D01*
G01X542260Y154202D02*
X536460D01*
G01X548120Y162962D02*
X554320D01*
G01X548120Y159762D02*
Y162962D01*
G01X554320Y159762D02*
X548120D01*
G01X541715Y169126D02*
X535915D01*
G01X540967Y185693D02*
Y177031D01*
G01X535720Y183493D02*
X537620Y185693D01*
G01X533820D02*
X535720Y183493D01*
G01X548120Y183262D02*
Y186462D01*
G01X554320Y183262D02*
X548120D01*
G01Y173462D02*
X554320D01*
G01X548120Y170262D02*
Y173462D01*
G01X554320Y170262D02*
X548120D01*
G01X537620Y185693D02*
X540967D01*
G01X548120Y186462D02*
X554320D01*
G01X539664Y242962D02*
X539357Y243014D01*
X539089Y243220D01*
X538859Y243530D01*
X538706Y243892D01*
X538629Y244305D01*
Y244719D01*
X538706Y245132D01*
X538859Y245494D01*
X539089Y245804D01*
X539357Y246010D01*
X539664Y246062D01*
X539971Y246010D01*
X540239Y245804D01*
X540469Y245494D01*
X540622Y245132D01*
X540699Y244719D01*
Y244305D01*
X540622Y243892D01*
X540469Y243530D01*
X540239Y243220D01*
X539971Y243014D01*
X539664Y242962D01*
G01X539971Y243789D02*
X540431Y242962D01*
G01X543224D02*
Y246062D01*
X541806Y243840D01*
X543722D01*
G01X545136Y244254D02*
X545404Y244615D01*
X545634Y244822D01*
X545941Y244925D01*
X546209Y244822D01*
X546401Y244615D01*
X546554Y244305D01*
X546592Y243944D01*
X546554Y243634D01*
X546401Y243324D01*
X546171Y243065D01*
X545902Y242962D01*
X545596Y243065D01*
X545327Y243375D01*
X545174Y243840D01*
X545136Y244357D01*
X545212Y245029D01*
X545327Y245390D01*
X545519Y245752D01*
X545787Y246010D01*
X546056Y246062D01*
X546324Y245959D01*
X546516Y245700D01*
G01X546376Y260608D02*
Y248796D01*
G01D02*
X533752D01*
G01D02*
Y260608D01*
G01D02*
X546376D01*
G01X541164Y271072D02*
Y267872D01*
G01X534964Y271072D02*
X541164D01*
G01X534964Y267872D02*
Y271072D01*
G01X541164Y267872D02*
X534964D01*
G01X534220Y298362D02*
Y286362D01*
G01X549200Y313388D02*
X551862D01*
G01X549200Y304726D02*
Y313388D01*
G01X559800Y304726D02*
X549200D01*
G01X537320Y361762D02*
X534120D01*
G01X537320Y367962D02*
Y361762D01*
G01X534120D02*
Y367962D01*
G01X545730Y361642D02*
Y367842D01*
G01X548930Y361642D02*
X545730D01*
G01X548930Y367842D02*
Y361642D01*
G01X547651Y377173D02*
Y392973D01*
G01X567751Y377173D02*
X547651D01*
G01X540000Y374850D02*
X539948Y374543D01*
X539742Y374275D01*
X539432Y374045D01*
X539070Y373892D01*
X538657Y373815D01*
X538243D01*
X537830Y373892D01*
X537468Y374045D01*
X537158Y374275D01*
X536952Y374543D01*
X536900Y374850D01*
X536952Y375157D01*
X537158Y375425D01*
X537468Y375655D01*
X537830Y375808D01*
X538243Y375885D01*
X538657D01*
X539070Y375808D01*
X539432Y375655D01*
X539742Y375425D01*
X539948Y375157D01*
X540000Y374850D01*
G01X539173Y375157D02*
X540000Y375617D01*
G01Y377950D02*
X536900D01*
X537520Y377490D01*
G01X540000D02*
Y378410D01*
G01Y381510D02*
X536900D01*
X539122Y380092D01*
Y382008D01*
G01X537417Y383422D02*
X537107Y383652D01*
X536952Y383920D01*
X536900Y384227D01*
X537003Y384610D01*
X537262Y384878D01*
X537572Y384955D01*
X537882Y384917D01*
X538140Y384763D01*
X538657Y383997D01*
X539018Y383652D01*
X539535Y383422D01*
X540000Y383345D01*
Y384955D01*
G01X534120Y367962D02*
X537320D01*
G01X545730Y367842D02*
X548930D01*
G01X547651Y392973D02*
X567751D01*
G01X535320Y397462D02*
Y391262D01*
G01X538500Y403850D02*
X538448Y403543D01*
X538242Y403275D01*
X537932Y403045D01*
X537570Y402892D01*
X537157Y402815D01*
X536743D01*
X536330Y402892D01*
X535968Y403045D01*
X535658Y403275D01*
X535452Y403543D01*
X535400Y403850D01*
X535452Y404157D01*
X535658Y404425D01*
X535968Y404655D01*
X536330Y404808D01*
X536743Y404885D01*
X537157D01*
X537570Y404808D01*
X537932Y404655D01*
X538242Y404425D01*
X538448Y404157D01*
X538500Y403850D01*
G01X537673Y404157D02*
X538500Y404617D01*
G01Y406950D02*
X535400D01*
X536020Y406490D01*
G01X538500D02*
Y407410D01*
G01Y410510D02*
X535400D01*
X537622Y409092D01*
Y411008D01*
G01X535400Y413150D02*
X535503Y412843D01*
X535762Y412613D01*
X536072Y412460D01*
X536485Y412345D01*
X536950Y412307D01*
X537415Y412345D01*
X537828Y412460D01*
X538138Y412613D01*
X538397Y412843D01*
X538500Y413150D01*
X538397Y413457D01*
X538138Y413687D01*
X537828Y413840D01*
X537415Y413955D01*
X536950Y413993D01*
X536485Y413955D01*
X536072Y413840D01*
X535762Y413687D01*
X535503Y413457D01*
X535400Y413150D01*
G01X546700Y406807D02*
Y413007D01*
G01X549900Y406807D02*
X546700D01*
G01Y413007D02*
X549900D01*
G01X553394Y449896D02*
X550792Y452498D01*
X546570D01*
Y440294D01*
X560218D01*
Y452498D01*
X555996D01*
X553394Y449896D01*
G01X533850Y443976D02*
X540050D01*
Y440776D01*
X533850D01*
Y443976D01*
G01Y447996D02*
X540050D01*
Y444796D01*
X533850D01*
Y447996D01*
G01Y451930D02*
X540050D01*
Y448730D01*
X533850D01*
Y451930D01*
G01X540050Y452670D02*
X533850D01*
Y455870D01*
X540050D01*
Y452670D01*
G01X554070Y487212D02*
X548519Y492763D01*
X545812D01*
Y461661D01*
X562328D01*
Y492763D01*
X559621D01*
X554070Y487212D01*
G01X545477Y497279D02*
Y495057D01*
X545630Y494592D01*
X545937Y494282D01*
X546320Y494179D01*
X546703Y494282D01*
X547010Y494592D01*
X547163Y495057D01*
Y497279D01*
G01X548577Y494644D02*
X548807Y494386D01*
X549075Y494231D01*
X549420Y494179D01*
X549765Y494282D01*
X550033Y494489D01*
X550225Y494851D01*
X550263Y495264D01*
X550187Y495677D01*
X549995Y495936D01*
X549727Y496142D01*
X549458Y496194D01*
X549190Y496142D01*
X548845Y495936D01*
X548960Y497279D01*
X549995D01*
G01X552520Y494179D02*
Y497279D01*
X552060Y496659D01*
G01Y494179D02*
X552980D01*
G01X551929Y835668D02*
X548190D01*
G01D02*
Y838464D01*
G01X548189Y835668D02*
Y838464D01*
G01X551929Y835668D02*
X548189D01*
G01X540316Y835708D02*
Y838464D01*
G01X540315Y835708D02*
Y838464D01*
G01X540316Y835708D02*
Y832558D01*
G01Y833556D02*
Y829802D01*
G01D02*
Y832558D01*
G01X540315Y835708D02*
Y832558D01*
G01Y833556D02*
Y829803D01*
G01D02*
Y832558D01*
G01X548190Y838464D02*
X540316D01*
G01X548189D02*
X540315D01*
G01X548740Y996338D02*
X556812Y1003031D01*
G01X548740Y996338D02*
X556811Y1003031D01*
G01X548740Y986102D02*
Y996338D01*
G01Y986103D02*
Y996338D01*
G01X556812Y979409D02*
X548740Y986102D01*
G01X556811Y979410D02*
X548740Y986103D01*
G01X552678Y1116456D02*
G03Y1110157I0J-3149D01*
G01X552677Y1116456D02*
G03Y1110157I0J-3149D01*
G01X548190Y1143976D02*
Y1146771D01*
G01X548189Y1143977D02*
Y1146771D01*
G01X540316Y1152637D02*
Y1143976D01*
G01D02*
X548190D01*
G01X540315Y1152638D02*
Y1143977D01*
G01D02*
X548189D01*
G01X551929Y1146771D02*
X548190D01*
G01X551929D02*
X548189D01*
G01X541954Y1284169D02*
Y1287269D01*
X542874D01*
X543181Y1287114D01*
X543411Y1286752D01*
X543488Y1286339D01*
X543411Y1285926D01*
X543219Y1285616D01*
X542874Y1285461D01*
X541954D01*
G01X545054Y1287269D02*
Y1284169D01*
X546588D01*
G01X548193Y1286752D02*
X548423Y1287062D01*
X548691Y1287217D01*
X548998Y1287269D01*
X549381Y1287166D01*
X549649Y1286907D01*
X549726Y1286597D01*
X549688Y1286287D01*
X549534Y1286029D01*
X548768Y1285512D01*
X548423Y1285151D01*
X548193Y1284634D01*
X548116Y1284169D01*
X549726D01*
G01X552481D02*
Y1287269D01*
X551063Y1285047D01*
X552979D01*
G01X547952Y1371291D02*
X551152D01*
G01X547952Y1365091D02*
Y1371291D01*
G01X551152Y1365091D02*
X547952D01*
G01X534337Y1368719D02*
Y1371919D01*
G01X540537Y1368719D02*
X534337D01*
G01X540537Y1371919D02*
Y1368719D01*
G01X534337Y1371919D02*
X540537D01*
G01X547110Y1365091D02*
X543910D01*
G01X547110Y1371291D02*
Y1365091D01*
G01X543910Y1371291D02*
X547110D01*
G01X543910Y1365091D02*
Y1371291D01*
G01X545024Y1374177D02*
Y1377277D01*
X545944D01*
X546251Y1377122D01*
X546481Y1376760D01*
X546558Y1376347D01*
X546481Y1375934D01*
X546289Y1375624D01*
X545944Y1375469D01*
X545024D01*
G01X548048Y1377277D02*
Y1375055D01*
X548201Y1374590D01*
X548508Y1374280D01*
X548891Y1374177D01*
X549274Y1374280D01*
X549581Y1374590D01*
X549734Y1375055D01*
Y1377277D01*
G01X551263Y1376760D02*
X551493Y1377070D01*
X551761Y1377225D01*
X552068Y1377277D01*
X552451Y1377174D01*
X552719Y1376915D01*
X552796Y1376605D01*
X552758Y1376295D01*
X552604Y1376037D01*
X551838Y1375520D01*
X551493Y1375159D01*
X551263Y1374642D01*
X551186Y1374177D01*
X552796D01*
G01X554248Y1374797D02*
X554478Y1374435D01*
X554784Y1374229D01*
X555129Y1374177D01*
X555436Y1374229D01*
X555743Y1374487D01*
X555934Y1374797D01*
X555973Y1375107D01*
X555896Y1375469D01*
X555628Y1375727D01*
X555359Y1375830D01*
X555014D01*
G01X555359D02*
X555589Y1375985D01*
X555781Y1376244D01*
X555858Y1376554D01*
X555781Y1376864D01*
X555589Y1377122D01*
X555244Y1377277D01*
X554899Y1377225D01*
X554554Y1377019D01*
G01X557041Y1373144D02*
X559341D01*
G01X560524Y1374177D02*
Y1377277D01*
X561444D01*
X561751Y1377122D01*
X561981Y1376760D01*
X562058Y1376347D01*
X561981Y1375934D01*
X561789Y1375624D01*
X561444Y1375469D01*
X560524D01*
G01X564391Y1374177D02*
Y1377277D01*
X563931Y1376657D01*
G01Y1374177D02*
X564851D01*
G01X566341Y1373144D02*
X568641D01*
G01X570591Y1374177D02*
X570859Y1374229D01*
X571166Y1374384D01*
X571358Y1374642D01*
X571434Y1375004D01*
X571358Y1375365D01*
X571128Y1375675D01*
X570783Y1375830D01*
X570399D01*
X570169Y1375934D01*
X569978Y1376192D01*
X569901Y1376554D01*
X570016Y1376915D01*
X570284Y1377174D01*
X570591Y1377277D01*
X570898Y1377174D01*
X571166Y1376915D01*
X571281Y1376554D01*
X571204Y1376192D01*
X571013Y1375934D01*
X570783Y1375830D01*
X570399D01*
X570054Y1375675D01*
X569824Y1375365D01*
X569748Y1375004D01*
X569824Y1374642D01*
X570016Y1374384D01*
X570323Y1374229D01*
X570591Y1374177D01*
G01X574433Y1436286D02*
X544039D01*
G01D02*
Y1446128D01*
G01D02*
X574433D01*
G01X548841Y1462063D02*
X549099Y1462370D01*
X549254Y1462715D01*
Y1463021D01*
X549099Y1463328D01*
X548841Y1463558D01*
X548479Y1463673D01*
X548117Y1463596D01*
X547807Y1463405D01*
X547601Y1463060D01*
X547497Y1462600D01*
X547291Y1462331D01*
X546929Y1462216D01*
X546567Y1462293D01*
X546309Y1462485D01*
X546154Y1462753D01*
Y1463021D01*
X546257Y1463290D01*
X546516Y1463520D01*
G01X546412Y1466811D02*
X546257Y1466581D01*
X546154Y1466313D01*
Y1466006D01*
X546309Y1465661D01*
X546567Y1465393D01*
X546877Y1465201D01*
X547394Y1465048D01*
X547859Y1465010D01*
X548324Y1465086D01*
X548634Y1465201D01*
X548944Y1465431D01*
X549151Y1465700D01*
X549254Y1465968D01*
Y1466236D01*
X549151Y1466505D01*
X548996Y1466735D01*
X548789Y1466926D01*
G01X546154Y1468301D02*
X549254D01*
Y1469835D01*
G01X534917Y1624269D02*
X535837Y1623486D01*
X536872Y1623016D01*
X537792D01*
X538712Y1623486D01*
X539402Y1624269D01*
X539747Y1625366D01*
X539517Y1626463D01*
X538942Y1627403D01*
X537907Y1628029D01*
X536527Y1628343D01*
X535722Y1628969D01*
X535377Y1630066D01*
X535607Y1631163D01*
X536182Y1631946D01*
X536987Y1632416D01*
X537792D01*
X538597Y1632103D01*
X539287Y1631319D01*
G01X543082Y1632416D02*
X544692Y1623016D01*
X546532Y1632416D01*
X548372Y1623016D01*
X549982Y1632416D01*
G01X556652Y1628029D02*
X557112Y1628499D01*
X557457Y1629282D01*
X557687Y1630379D01*
X557457Y1631319D01*
X556997Y1631946D01*
X556192Y1632416D01*
X553087D01*
Y1623016D01*
X556882D01*
X557687Y1623643D01*
X558147Y1624583D01*
X558377Y1625679D01*
X558147Y1626776D01*
X557457Y1627716D01*
X556652Y1628029D01*
X553087D01*
G01X561482Y1619883D02*
X568382D01*
G01X571947Y1623016D02*
Y1632416D01*
X576317D01*
G01X574707Y1627873D02*
X571947D01*
G01X545276Y1646023D02*
Y1781456D01*
G01X635433Y1646023D02*
X545276D01*
G01X538753Y1653332D02*
X538830Y1654004D01*
X538945Y1654572D01*
X539098Y1655089D01*
X539290Y1655657D01*
X539597Y1656432D01*
X538063D01*
G01X534924Y1654764D02*
X535192Y1655125D01*
X535422Y1655332D01*
X535729Y1655435D01*
X535997Y1655332D01*
X536189Y1655125D01*
X536342Y1654815D01*
X536380Y1654454D01*
X536342Y1654144D01*
X536189Y1653834D01*
X535959Y1653575D01*
X535690Y1653472D01*
X535384Y1653575D01*
X535115Y1653885D01*
X534962Y1654350D01*
X534924Y1654867D01*
X535000Y1655539D01*
X535115Y1655900D01*
X535307Y1656262D01*
X535575Y1656520D01*
X535844Y1656572D01*
X536112Y1656469D01*
X536304Y1656210D01*
G01X541930Y1653502D02*
X542198Y1653554D01*
X542505Y1653709D01*
X542697Y1653967D01*
X542773Y1654329D01*
X542697Y1654690D01*
X542467Y1655000D01*
X542122Y1655155D01*
X541738D01*
X541508Y1655259D01*
X541317Y1655517D01*
X541240Y1655879D01*
X541355Y1656240D01*
X541623Y1656499D01*
X541930Y1656602D01*
X542237Y1656499D01*
X542505Y1656240D01*
X542620Y1655879D01*
X542543Y1655517D01*
X542352Y1655259D01*
X542122Y1655155D01*
X541738D01*
X541393Y1655000D01*
X541163Y1654690D01*
X541087Y1654329D01*
X541163Y1653967D01*
X541355Y1653709D01*
X541662Y1653554D01*
X541930Y1653502D01*
G01X545276Y1781456D02*
X635433D01*
G01X553870Y71930D02*
X551220D01*
G01X731100D02*
X559810D01*
G01X569100Y101262D02*
X562900D01*
Y104462D01*
X569100D01*
Y101262D01*
G01Y97262D02*
X562900D01*
Y100462D01*
X569100D01*
Y97262D01*
G01X550870Y130156D02*
Y133356D01*
G01X557070Y130156D02*
X550870D01*
G01X557070Y133356D02*
Y130156D01*
G01X550870Y133356D02*
X557070D01*
G01Y129388D02*
Y126188D01*
G01X550870Y129388D02*
X557070D01*
G01X550870Y126188D02*
Y129388D01*
G01X557070Y126188D02*
X550870D01*
G01X557070Y139374D02*
Y136174D01*
G01X550870D02*
Y139374D01*
G01X557070Y136174D02*
X550870D01*
G01X563717Y153532D02*
Y151310D01*
X563870Y150845D01*
X564177Y150535D01*
X564560Y150432D01*
X564943Y150535D01*
X565250Y150845D01*
X565403Y151310D01*
Y153532D01*
G01X566932Y153015D02*
X567162Y153325D01*
X567430Y153480D01*
X567737Y153532D01*
X568120Y153429D01*
X568388Y153170D01*
X568465Y152860D01*
X568427Y152550D01*
X568273Y152292D01*
X567507Y151775D01*
X567162Y151414D01*
X566932Y150897D01*
X566855Y150432D01*
X568465D01*
G01X571220D02*
Y153532D01*
X569802Y151310D01*
X571718D01*
G01X573017Y151052D02*
X573247Y150690D01*
X573553Y150484D01*
X573898Y150432D01*
X574205Y150484D01*
X574512Y150742D01*
X574703Y151052D01*
X574742Y151362D01*
X574665Y151724D01*
X574397Y151982D01*
X574128Y152085D01*
X573783D01*
G01X574128D02*
X574358Y152240D01*
X574550Y152499D01*
X574627Y152809D01*
X574550Y153119D01*
X574358Y153377D01*
X574013Y153532D01*
X573668Y153480D01*
X573323Y153274D01*
G01X552070Y151402D02*
Y148202D01*
G01X557070Y155478D02*
Y152278D01*
G01X550870D02*
Y155478D01*
G01X557070Y152278D02*
X550870D01*
G01Y139374D02*
X557070D01*
G01X554320Y163262D02*
X551120D01*
G01X554320Y169462D02*
Y163262D01*
G01X551120D02*
Y169462D01*
G01X550870Y155478D02*
X557070D01*
G01X557620Y165512D02*
Y168712D01*
G01X563820Y165512D02*
X557620D01*
G01X563820Y168712D02*
Y165512D01*
G01X557620Y168712D02*
X563820D01*
G01X557620Y159762D02*
Y162962D01*
G01X563820Y159762D02*
X557620D01*
G01X563820Y162962D02*
Y159762D01*
G01X557620Y162962D02*
X563820D01*
G01X554320D02*
Y159762D01*
G01X551120Y169462D02*
X554320D01*
G01X558120Y183262D02*
Y186462D01*
G01X564320Y183262D02*
X558120D01*
G01X564320Y186462D02*
Y183262D01*
G01X554320Y186462D02*
Y183262D01*
G01Y173462D02*
Y170262D01*
G01X558120Y186462D02*
X564320D01*
G01X565901Y248499D02*
Y246277D01*
X566054Y245812D01*
X566361Y245502D01*
X566744Y245399D01*
X567127Y245502D01*
X567434Y245812D01*
X567587Y246277D01*
Y248499D01*
G01X569844Y245399D02*
Y248499D01*
X569384Y247879D01*
G01Y245399D02*
X570304D01*
G01X573404D02*
Y248499D01*
X571986Y246277D01*
X573902D01*
G01X575201Y245864D02*
X575431Y245606D01*
X575699Y245451D01*
X576044Y245399D01*
X576389Y245502D01*
X576657Y245709D01*
X576849Y246071D01*
X576887Y246484D01*
X576811Y246897D01*
X576619Y247156D01*
X576351Y247362D01*
X576082Y247414D01*
X575814Y247362D01*
X575469Y247156D01*
X575584Y248499D01*
X576619D01*
G01X565872Y250401D02*
Y259063D01*
G01X576896Y250401D02*
X565872D01*
G01X576896Y259063D02*
X565872D01*
G01X552964Y251602D02*
Y254802D01*
G01X559164Y251602D02*
X552964D01*
G01X559164Y254802D02*
Y251602D01*
G01X552964Y254802D02*
X559164D01*
G01X552964Y255602D02*
Y258802D01*
G01X559164Y255602D02*
X552964D01*
G01X559164Y258802D02*
Y255602D01*
G01X552964Y258802D02*
X559164D01*
G01X550237Y318582D02*
Y316360D01*
X550390Y315895D01*
X550697Y315585D01*
X551080Y315482D01*
X551463Y315585D01*
X551770Y315895D01*
X551923Y316360D01*
Y318582D01*
G01X554180Y315482D02*
Y318582D01*
X553720Y317962D01*
G01Y315482D02*
X554640D01*
G01X556437Y315947D02*
X556667Y315689D01*
X556935Y315534D01*
X557280Y315482D01*
X557625Y315585D01*
X557893Y315792D01*
X558085Y316154D01*
X558123Y316567D01*
X558047Y316980D01*
X557855Y317239D01*
X557587Y317445D01*
X557318Y317497D01*
X557050Y317445D01*
X556705Y317239D01*
X556820Y318582D01*
X557855D01*
G01X560380D02*
X560073Y318479D01*
X559843Y318220D01*
X559690Y317910D01*
X559575Y317497D01*
X559537Y317032D01*
X559575Y316567D01*
X559690Y316154D01*
X559843Y315844D01*
X560073Y315585D01*
X560380Y315482D01*
X560687Y315585D01*
X560917Y315844D01*
X561070Y316154D01*
X561185Y316567D01*
X561223Y317032D01*
X561185Y317497D01*
X561070Y317910D01*
X560917Y318220D01*
X560687Y318479D01*
X560380Y318582D01*
G01X557138Y313388D02*
X559800D01*
G01X554500Y310557D02*
X557138Y313388D01*
G01X551862D02*
X554500Y310557D01*
G01X559800Y313388D02*
Y304726D01*
G01X565089Y303647D02*
Y306847D01*
G01X571289Y303647D02*
X565089D01*
G01Y306847D02*
X571289D01*
G01X564989Y312447D02*
X571189D01*
G01X564989Y309247D02*
Y312447D01*
G01X571189Y309247D02*
X564989D01*
G01X563098Y361602D02*
Y367802D01*
G01X566298Y361602D02*
X563098D01*
G01Y367802D02*
X566298D01*
G01X565501Y385073D02*
X567751Y382823D01*
G01Y387323D02*
X565501Y385073D01*
G01X549900Y413007D02*
Y406807D01*
G01X552700D02*
Y413007D01*
G01X555900Y406807D02*
X552700D01*
G01X555900Y413007D02*
Y406807D01*
G01X562700D02*
Y413007D01*
G01X565900Y406807D02*
X562700D01*
G01X565900Y413007D02*
Y406807D01*
G01X557700D02*
Y413007D01*
G01X560900Y406807D02*
X557700D01*
G01X560900Y413007D02*
Y406807D01*
G01X563725Y425992D02*
X569925D01*
G01X563725Y422792D02*
Y425992D01*
G01X569925Y422792D02*
X563725D01*
G01X552700Y413007D02*
X555900D01*
G01X562700D02*
X565900D01*
G01X557700D02*
X560900D01*
G01Y415657D02*
X557700D01*
G01X560900Y421857D02*
Y415657D01*
G01X557700Y421857D02*
X560900D01*
G01X557700Y415657D02*
Y421857D01*
G01X555501Y439263D02*
Y437041D01*
X555654Y436576D01*
X555961Y436266D01*
X556344Y436163D01*
X556727Y436266D01*
X557034Y436576D01*
X557187Y437041D01*
Y439263D01*
G01X558601Y436783D02*
X558831Y436421D01*
X559137Y436215D01*
X559482Y436163D01*
X559789Y436215D01*
X560096Y436473D01*
X560287Y436783D01*
X560326Y437093D01*
X560249Y437455D01*
X559981Y437713D01*
X559712Y437816D01*
X559367D01*
G01X559712D02*
X559942Y437971D01*
X560134Y438230D01*
X560211Y438540D01*
X560134Y438850D01*
X559942Y439108D01*
X559597Y439263D01*
X559252Y439211D01*
X558907Y439005D01*
G01X561701Y436783D02*
X561931Y436421D01*
X562237Y436215D01*
X562582Y436163D01*
X562889Y436215D01*
X563196Y436473D01*
X563387Y436783D01*
X563426Y437093D01*
X563349Y437455D01*
X563081Y437713D01*
X562812Y437816D01*
X562467D01*
G01X562812D02*
X563042Y437971D01*
X563234Y438230D01*
X563311Y438540D01*
X563234Y438850D01*
X563042Y439108D01*
X562697Y439263D01*
X562352Y439211D01*
X562007Y439005D01*
G01X564801Y436628D02*
X565031Y436370D01*
X565299Y436215D01*
X565644Y436163D01*
X565989Y436266D01*
X566257Y436473D01*
X566449Y436835D01*
X566487Y437248D01*
X566411Y437661D01*
X566219Y437920D01*
X565951Y438126D01*
X565682Y438178D01*
X565414Y438126D01*
X565069Y437920D01*
X565184Y439263D01*
X566219D01*
G01X563440Y444256D02*
X569640D01*
Y441056D01*
X563440D01*
Y444256D01*
G01X569617Y445106D02*
X563417D01*
Y448306D01*
X569617D01*
Y445106D01*
G01X563417Y453310D02*
X569617D01*
Y450110D01*
X563417D01*
Y453310D01*
G01X551929Y835668D02*
G03X554883Y838621I1J2953D01*
G01X551929Y835668D02*
G03X554882Y838621I0J2953D01*
G01X560749Y829802D02*
Y850235D01*
G01X560748Y829803D02*
Y850236D01*
G01X552087Y838464D02*
Y1143976D01*
G01X562718Y853424D02*
G03X560749Y851456I-1J-1968D01*
G01D02*
Y850235D01*
G01X554844D02*
X552088D01*
G01D02*
Y842361D01*
G01D02*
X554883D01*
G01X554844D02*
X554883D01*
G01D02*
Y838621D01*
G01X562717Y853425D02*
G03X560748Y851456I0J-1969D01*
G01D02*
Y850236D01*
G01X554843D02*
X552087D01*
G01D02*
Y842362D01*
G01D02*
X554882D01*
G01X554843D02*
X554882D01*
G01D02*
Y838621D01*
G01X554844Y850235D02*
Y860511D01*
G01X554843Y850236D02*
Y860512D01*
G01X567638Y861299D02*
Y853424D01*
X562697D01*
G01X554844Y861298D02*
X556812D01*
G01X554844Y860511D02*
Y861298D01*
G01X554843Y861299D02*
X556811D01*
G01X554843Y860512D02*
Y861299D01*
G01X556812Y861298D02*
Y979409D01*
G01X556811Y861299D02*
Y979410D01*
G01X562701Y1138857D02*
G03X560749Y1136895I17J-1969D01*
G01Y861299D01*
G01X567638Y853424D02*
X562718D01*
G01X567638Y853425D02*
X562717D01*
G01X560749Y861299D02*
X556812Y861298D01*
G01X567638Y869960D02*
X560749D01*
G01X584517Y991220D02*
G03I-9950J0D01*
G01X556812Y1003031D02*
Y1110157D01*
G01X556811Y1003031D02*
Y1110157D01*
G01X556812D02*
X560749D01*
G01D02*
Y1116456D01*
G01X556812Y1110157D02*
X552678D01*
G01X556811D02*
X560748D01*
G01D02*
Y1116456D01*
G01X556811Y1110157D02*
X552677D01*
G01X560749Y1116456D02*
X556812D01*
G01X552678D02*
X560749D01*
G01X560748D02*
X556811D01*
G01X552677D02*
X560748D01*
G01X556812D02*
Y1132204D01*
G01X556811Y1116456D02*
Y1132205D01*
G01X554883Y1143818D02*
G03X551929Y1146771I-2953J0D01*
G01X554883Y1143818D02*
Y1140078D01*
G01D02*
X552088D01*
G01X554882Y1143818D02*
G03X551929Y1146771I-2952J1D01*
G01X554882Y1143818D02*
Y1140079D01*
G01D02*
X552087D01*
G01X560749Y1148692D02*
G03X562698Y1146731I1967J6D01*
G01X567639D01*
Y1138857D01*
X562701D01*
G01X567638D02*
X562718D01*
G01X567638D02*
X562717D01*
G01X562718D02*
G03X560749Y1136889I-1J-1968D01*
G01X562717Y1138857D02*
G03X560748Y1136890I-1J-1968D01*
G01X556812Y1132204D02*
X560749D01*
G01Y1136889D02*
Y1132204D01*
G01X552088Y1140078D02*
Y1132204D01*
G01D02*
X556812D01*
G01X560748Y1136890D02*
Y1132205D01*
G01X552087Y1140079D02*
Y1132205D01*
G01X556811D02*
X560748D01*
G01X552087D02*
X556811D01*
G01X560749Y1148700D02*
G03X562718Y1146731I1969J0D01*
G01X560749Y1152637D02*
Y1148700D01*
G01X560748Y1148701D02*
G03X562717Y1146731I1969J-1D01*
G01X560748Y1152638D02*
Y1148701D01*
G01X562718Y1146731D02*
X567638D01*
G01X562717D02*
X567638D01*
G01X557749Y1291541D02*
Y1334849D01*
G01X552408Y1291541D02*
X557749D01*
G01X559895Y1319463D02*
Y1345053D01*
G01X563890Y1319463D02*
X559895D01*
G01X552364Y1338256D02*
X551571D01*
G01X552364Y1340856D02*
Y1338256D01*
G01X557749Y1334849D02*
X552408D01*
G01X559895Y1345053D02*
X563890D01*
G01X559369Y1353568D02*
X562569D01*
G01X559369Y1347368D02*
Y1353568D01*
G01X562569Y1347368D02*
X559369D01*
G01X562569Y1353568D02*
Y1347368D01*
G01X554986Y1353568D02*
X558186D01*
G01X554986Y1347368D02*
Y1353568D01*
G01X558186Y1347368D02*
X554986D01*
G01X558186Y1353568D02*
Y1347368D01*
G01X552364Y1361878D02*
Y1359687D01*
G01X551631Y1361878D02*
X552364D01*
G01X551152Y1371291D02*
Y1365091D01*
G01X556120Y1448262D02*
Y1454462D01*
G01X559320Y1448262D02*
X556120D01*
G01X559320Y1454462D02*
Y1448262D01*
G01X550400D02*
Y1454462D01*
G01X553600Y1448262D02*
X550400D01*
G01X553600Y1454462D02*
Y1448262D01*
G01X559230Y1463326D02*
Y1464093D01*
X560160D01*
X560470Y1463863D01*
X560677Y1463594D01*
X560780Y1463211D01*
X560677Y1462828D01*
X560470Y1462559D01*
X560160Y1462329D01*
X559798Y1462176D01*
X559385Y1462099D01*
X559023D01*
X558713Y1462176D01*
X558352Y1462329D01*
X558042Y1462559D01*
X557835Y1462789D01*
X557680Y1463096D01*
Y1463364D01*
X557783Y1463671D01*
X557990Y1463901D01*
G01X560780Y1465314D02*
X557680D01*
X560780Y1467078D01*
X557680D01*
G01X560780Y1468453D02*
X557680D01*
Y1469219D01*
X557835Y1469526D01*
X558042Y1469756D01*
X558352Y1469948D01*
X558713Y1470101D01*
X559230Y1470139D01*
X559747Y1470101D01*
X560108Y1469948D01*
X560418Y1469756D01*
X560625Y1469526D01*
X560780Y1469219D01*
Y1468453D01*
G01X556120Y1454462D02*
X559320D01*
G01X550400D02*
X553600D01*
G01Y1455262D02*
X550400D01*
G01X553600Y1461462D02*
Y1455262D01*
G01X550400Y1461462D02*
X553600D01*
G01X550400Y1455262D02*
Y1461462D01*
G01X562890Y1653582D02*
Y1656682D01*
X562430Y1656062D01*
G01Y1653582D02*
X563350D01*
G01X557087Y1769645D02*
Y1657834D01*
G01D02*
X623622D01*
G01X556693D02*
Y1769645D01*
G01X553898Y1670325D02*
Y1673425D01*
X555662Y1670325D01*
Y1673425D01*
G01X553783Y1675049D02*
Y1678149D01*
X554780Y1675566D01*
X555777Y1678149D01*
Y1675049D01*
G01X554013Y1682873D02*
Y1679773D01*
X555547D01*
G01X554320Y1697047D02*
X555240D01*
G01X554780D02*
Y1693947D01*
G01X554320D02*
X555240D01*
G01X553975Y1698671D02*
Y1701771D01*
G01X555585D02*
Y1698671D01*
G01Y1700221D02*
X553975D01*
G01X553937Y1684498D02*
Y1687598D01*
G01X555393D02*
X553937Y1685686D01*
G01X555623Y1684498D02*
X554588Y1686565D01*
G01X554013Y1689842D02*
X554205Y1689532D01*
X554435Y1689325D01*
X554703Y1689222D01*
X555010Y1689325D01*
X555240Y1689532D01*
X555470Y1689842D01*
X555547Y1690255D01*
Y1692322D01*
G01X555010Y1704946D02*
X555777D01*
Y1704016D01*
X555547Y1703706D01*
X555278Y1703499D01*
X554895Y1703396D01*
X554512Y1703499D01*
X554243Y1703706D01*
X554013Y1704016D01*
X553860Y1704378D01*
X553783Y1704791D01*
Y1705153D01*
X553860Y1705463D01*
X554013Y1705824D01*
X554243Y1706134D01*
X554473Y1706341D01*
X554780Y1706496D01*
X555048D01*
X555355Y1706393D01*
X555585Y1706186D01*
G01X554052Y1708120D02*
Y1711220D01*
X555508D01*
G01X554972Y1709722D02*
X554052D01*
G01X555547Y1712844D02*
X554013D01*
Y1715944D01*
X555547D01*
G01X554933Y1714446D02*
X554013D01*
G01X555623Y1725135D02*
X555393Y1725290D01*
X555125Y1725393D01*
X554818D01*
X554473Y1725238D01*
X554205Y1724980D01*
X554013Y1724670D01*
X553860Y1724153D01*
X553822Y1723688D01*
X553898Y1723223D01*
X554013Y1722913D01*
X554243Y1722603D01*
X554512Y1722396D01*
X554780Y1722293D01*
X555048D01*
X555317Y1722396D01*
X555547Y1722551D01*
X555738Y1722758D01*
G01X555087Y1728671D02*
X555240Y1728826D01*
X555355Y1729085D01*
X555432Y1729446D01*
X555355Y1729756D01*
X555202Y1729963D01*
X554933Y1730118D01*
X553898D01*
Y1727018D01*
X555163D01*
X555432Y1727225D01*
X555585Y1727535D01*
X555662Y1727896D01*
X555585Y1728258D01*
X555355Y1728568D01*
X555087Y1728671D01*
X553898D01*
G01X553937Y1717569D02*
Y1720669D01*
X554703D01*
X555010Y1720514D01*
X555240Y1720307D01*
X555432Y1719997D01*
X555585Y1719636D01*
X555623Y1719119D01*
X555585Y1718602D01*
X555432Y1718241D01*
X555240Y1717931D01*
X555010Y1717724D01*
X554703Y1717569D01*
X553937D01*
G01X564108Y1739812D02*
X562108Y1737812D01*
G01D02*
X566108D01*
G01D02*
X564108Y1739812D01*
G01D02*
Y1736412D01*
G01D02*
X569108D01*
G01X557087Y1740118D02*
X623622D01*
G01Y1769645D02*
X557087D01*
G01X592604Y64567D02*
X575864D01*
G01X570277Y124532D02*
Y122310D01*
X570430Y121845D01*
X570737Y121535D01*
X571120Y121432D01*
X571503Y121535D01*
X571810Y121845D01*
X571963Y122310D01*
Y124532D01*
G01X573492Y124015D02*
X573722Y124325D01*
X573990Y124480D01*
X574297Y124532D01*
X574680Y124429D01*
X574948Y124170D01*
X575025Y123860D01*
X574987Y123550D01*
X574833Y123292D01*
X574067Y122775D01*
X573722Y122414D01*
X573492Y121897D01*
X573415Y121432D01*
X575025D01*
G01X577780D02*
Y124532D01*
X576362Y122310D01*
X578278D01*
G01X580880Y121432D02*
Y124532D01*
X579462Y122310D01*
X581378D01*
G01X575310Y133442D02*
X574310Y134942D01*
G01X576310D02*
X575310Y133442D01*
G01X582110Y134942D02*
Y126142D01*
G01X568510D02*
Y134942D01*
G01X582110D02*
X576310D01*
G01X574310D02*
X568510D01*
G01X582110Y126142D02*
X568510D01*
G01X573210Y147632D02*
X572210Y149132D01*
G01X574210D02*
X573210Y147632D01*
G01X580010Y149132D02*
Y140332D01*
G01X566410D02*
Y149132D01*
G01X580010D02*
X574210D01*
G01X572210D02*
X566410D01*
G01X580010Y140332D02*
X566410D01*
G01X582103Y162945D02*
Y171607D01*
G01X593127Y162945D02*
X582103D01*
G01X574640Y159532D02*
Y156332D01*
G01X568440Y159532D02*
X574640D01*
G01X568440Y156332D02*
Y159532D01*
G01X574640Y156332D02*
X568440D01*
G01X577750Y159284D02*
X583950D01*
G01X577750Y156084D02*
Y159284D01*
G01X583950Y156084D02*
X577750D01*
G01X569120Y165512D02*
Y168712D01*
G01X575320Y165512D02*
X569120D01*
G01X575320Y168712D02*
Y165512D01*
G01X569120Y168712D02*
X575320D01*
G01X569972Y176033D02*
Y173811D01*
X570125Y173346D01*
X570432Y173036D01*
X570815Y172933D01*
X571198Y173036D01*
X571505Y173346D01*
X571658Y173811D01*
Y176033D01*
G01X573187Y175516D02*
X573417Y175826D01*
X573685Y175981D01*
X573992Y176033D01*
X574375Y175930D01*
X574643Y175671D01*
X574720Y175361D01*
X574682Y175051D01*
X574528Y174793D01*
X573762Y174276D01*
X573417Y173915D01*
X573187Y173398D01*
X573110Y172933D01*
X574720D01*
G01X576172Y173553D02*
X576402Y173191D01*
X576708Y172985D01*
X577053Y172933D01*
X577360Y172985D01*
X577667Y173243D01*
X577858Y173553D01*
X577897Y173863D01*
X577820Y174225D01*
X577552Y174483D01*
X577283Y174586D01*
X576938D01*
G01X577283D02*
X577513Y174741D01*
X577705Y175000D01*
X577782Y175310D01*
X577705Y175620D01*
X577513Y175878D01*
X577168Y176033D01*
X576823Y175981D01*
X576478Y175775D01*
G01X579463Y173295D02*
X579732Y173036D01*
X580038Y172933D01*
X580345Y173036D01*
X580613Y173346D01*
X580805Y173811D01*
X580882Y174276D01*
Y174845D01*
X580805Y175310D01*
X580613Y175723D01*
X580383Y175930D01*
X580115Y176033D01*
X579808Y175930D01*
X579578Y175723D01*
X579425Y175413D01*
X579348Y175000D01*
X579425Y174638D01*
X579617Y174276D01*
X579847Y174070D01*
X580115Y174018D01*
X580422Y174121D01*
X580652Y174380D01*
X580882Y174845D01*
G01X593127Y171607D02*
X582103D01*
G01X580350Y188492D02*
Y191692D01*
G01X586550Y188492D02*
X580350D01*
G01Y191692D02*
X586550D01*
G01X580356Y200778D02*
Y203978D01*
G01X586556Y200778D02*
X580356D01*
G01Y195978D02*
X586556D01*
G01X580356Y192778D02*
Y195978D01*
G01X586556Y192778D02*
X580356D01*
G01Y196778D02*
Y199978D01*
G01X586556Y196778D02*
X580356D01*
G01Y199978D02*
X586556D01*
G01X580356Y208778D02*
Y211978D01*
G01X586556Y208778D02*
X580356D01*
G01Y211978D02*
X586556D01*
G01X580356Y203978D02*
X586556D01*
G01X580356Y204778D02*
Y207978D01*
G01X586556Y204778D02*
X580356D01*
G01Y207978D02*
X586556D01*
G01X580120Y232462D02*
X586320D01*
G01X580120Y229262D02*
Y232462D01*
G01X586320Y229262D02*
X580120D01*
G01Y223762D02*
Y226962D01*
G01X586320Y223762D02*
X580120D01*
G01Y226962D02*
X586320D01*
G01X580120Y219762D02*
Y222962D01*
G01X586320Y219762D02*
X580120D01*
G01Y222962D02*
X586320D01*
G01X575320Y226962D02*
Y223762D01*
G01X569120Y226962D02*
X575320D01*
G01X569120Y223762D02*
Y226962D01*
G01X575320Y223762D02*
X569120D01*
G01X575320Y222962D02*
Y219762D01*
G01X569120Y222962D02*
X575320D01*
G01X569120Y219762D02*
Y222962D01*
G01X575320Y219762D02*
X569120D01*
G01X576896Y259063D02*
Y250401D01*
G01X573834Y261032D02*
Y264232D01*
G01X580034Y261032D02*
X573834D01*
G01X580034Y264232D02*
Y261032D01*
G01X573834Y264232D02*
X580034D01*
G01X571289Y306847D02*
Y303647D01*
G01X571189Y312447D02*
Y309247D01*
G01X576982Y361557D02*
Y367757D01*
G01X580182Y361557D02*
X576982D01*
G01X580182Y367757D02*
Y361557D01*
G01X566298Y367802D02*
Y361602D01*
G01X571860D02*
Y367802D01*
G01X575060Y361602D02*
X571860D01*
G01X575060Y367802D02*
Y361602D01*
G01X567740D02*
Y367802D01*
G01X570940Y361602D02*
X567740D01*
G01X570940Y367802D02*
Y361602D01*
G01X567751Y382823D02*
Y377173D01*
G01X569956Y379649D02*
X573156D01*
G01X569956Y373449D02*
Y379649D01*
G01X573156Y373449D02*
X569956D01*
G01X573156Y379649D02*
Y373449D01*
G01X576982Y367757D02*
X580182D01*
G01X571860Y367802D02*
X575060D01*
G01X567740D02*
X570940D01*
G01X569806Y391523D02*
Y389301D01*
X569959Y388836D01*
X570266Y388526D01*
X570649Y388423D01*
X571032Y388526D01*
X571339Y388836D01*
X571492Y389301D01*
Y391523D01*
G01X572906Y389043D02*
X573136Y388681D01*
X573442Y388475D01*
X573787Y388423D01*
X574094Y388475D01*
X574401Y388733D01*
X574592Y389043D01*
X574631Y389353D01*
X574554Y389715D01*
X574286Y389973D01*
X574017Y390076D01*
X573672D01*
G01X574017D02*
X574247Y390231D01*
X574439Y390490D01*
X574516Y390800D01*
X574439Y391110D01*
X574247Y391368D01*
X573902Y391523D01*
X573557Y391471D01*
X573212Y391265D01*
G01X576849Y391523D02*
X576542Y391420D01*
X576312Y391161D01*
X576159Y390851D01*
X576044Y390438D01*
X576006Y389973D01*
X576044Y389508D01*
X576159Y389095D01*
X576312Y388785D01*
X576542Y388526D01*
X576849Y388423D01*
X577156Y388526D01*
X577386Y388785D01*
X577539Y389095D01*
X577654Y389508D01*
X577692Y389973D01*
X577654Y390438D01*
X577539Y390851D01*
X577386Y391161D01*
X577156Y391420D01*
X576849Y391523D01*
G01X579221Y389715D02*
X579489Y390076D01*
X579719Y390283D01*
X580026Y390386D01*
X580294Y390283D01*
X580486Y390076D01*
X580639Y389766D01*
X580677Y389405D01*
X580639Y389095D01*
X580486Y388785D01*
X580256Y388526D01*
X579987Y388423D01*
X579681Y388526D01*
X579412Y388836D01*
X579259Y389301D01*
X579221Y389818D01*
X579297Y390490D01*
X579412Y390851D01*
X579604Y391213D01*
X579872Y391471D01*
X580141Y391523D01*
X580409Y391420D01*
X580601Y391161D01*
G01X567751Y392973D02*
Y387323D01*
G01X570900Y406807D02*
X567700D01*
G01X570900Y413007D02*
Y406807D01*
G01X567700D02*
Y413007D01*
G01X569925Y425992D02*
Y422792D01*
G01X567552Y421087D02*
X570752D01*
G01X567552Y414887D02*
Y421087D01*
G01X570752Y414887D02*
X567552D01*
G01X570752Y421087D02*
Y414887D01*
G01X567700Y413007D02*
X570900D01*
G01X582170Y494812D02*
Y491612D01*
G01X575970D02*
Y494812D01*
G01X582170Y491612D02*
X575970D01*
G01X582170Y489812D02*
Y486612D01*
G01X575970Y489812D02*
X582170D01*
G01X575970Y486612D02*
Y489812D01*
G01X582170Y486612D02*
X575970D01*
G01X580357Y502990D02*
Y500768D01*
X580510Y500303D01*
X580817Y499993D01*
X581200Y499890D01*
X581583Y499993D01*
X581890Y500303D01*
X582043Y500768D01*
Y502990D01*
G01X583572Y502473D02*
X583802Y502783D01*
X584070Y502938D01*
X584377Y502990D01*
X584760Y502887D01*
X585028Y502628D01*
X585105Y502318D01*
X585067Y502008D01*
X584913Y501750D01*
X584147Y501233D01*
X583802Y500872D01*
X583572Y500355D01*
X583495Y499890D01*
X585105D01*
G01X587400D02*
X587668Y499942D01*
X587975Y500097D01*
X588167Y500355D01*
X588243Y500717D01*
X588167Y501078D01*
X587937Y501388D01*
X587592Y501543D01*
X587208D01*
X586978Y501647D01*
X586787Y501905D01*
X586710Y502267D01*
X586825Y502628D01*
X587093Y502887D01*
X587400Y502990D01*
X587707Y502887D01*
X587975Y502628D01*
X588090Y502267D01*
X588013Y501905D01*
X587822Y501647D01*
X587592Y501543D01*
X587208D01*
X586863Y501388D01*
X586633Y501078D01*
X586557Y500717D01*
X586633Y500355D01*
X586825Y500097D01*
X587132Y499942D01*
X587400Y499890D01*
G01X589772Y501182D02*
X590040Y501543D01*
X590270Y501750D01*
X590577Y501853D01*
X590845Y501750D01*
X591037Y501543D01*
X591190Y501233D01*
X591228Y500872D01*
X591190Y500562D01*
X591037Y500252D01*
X590807Y499993D01*
X590538Y499890D01*
X590232Y499993D01*
X589963Y500303D01*
X589810Y500768D01*
X589772Y501285D01*
X589848Y501957D01*
X589963Y502318D01*
X590155Y502680D01*
X590423Y502938D01*
X590692Y502990D01*
X590960Y502887D01*
X591152Y502628D01*
G01X567315Y496946D02*
Y500146D01*
G01X573515Y496946D02*
X567315D01*
G01X573515Y500146D02*
Y496946D01*
G01X567315Y500146D02*
X573515D01*
G01X582170Y498812D02*
Y495612D01*
G01X575970Y498812D02*
X582170D01*
G01X575970Y495612D02*
Y498812D01*
G01X582170Y495612D02*
X575970D01*
G01Y494812D02*
X582170D01*
G01X577400Y515962D02*
X583600D01*
Y512762D01*
X577400D01*
Y515962D01*
G01X567638Y861298D02*
Y860511D01*
G01D02*
Y854212D01*
G01D02*
Y853424D01*
G01Y869960D02*
Y860512D01*
G01D02*
Y854212D01*
G01D02*
Y853425D01*
G01Y1139645D02*
Y1138857D01*
G01Y1145944D02*
Y1139645D01*
G01D02*
Y1138857D01*
G01Y1145944D02*
Y1139645D01*
G01Y1146731D02*
Y1145944D01*
G01Y1146731D02*
Y1145944D01*
G01X574543Y1313462D02*
Y1316562D01*
X575463D01*
X575770Y1316407D01*
X576000Y1316045D01*
X576077Y1315632D01*
X576000Y1315219D01*
X575808Y1314909D01*
X575463Y1314754D01*
X574543D01*
G01X577643Y1316562D02*
Y1313462D01*
X579177D01*
G01X581510D02*
Y1316562D01*
X581050Y1315942D01*
G01Y1313462D02*
X581970D01*
G01X584610Y1316562D02*
X584303Y1316459D01*
X584073Y1316200D01*
X583920Y1315890D01*
X583805Y1315477D01*
X583767Y1315012D01*
X583805Y1314547D01*
X583920Y1314134D01*
X584073Y1313824D01*
X584303Y1313565D01*
X584610Y1313462D01*
X584917Y1313565D01*
X585147Y1313824D01*
X585300Y1314134D01*
X585415Y1314547D01*
X585453Y1315012D01*
X585415Y1315477D01*
X585300Y1315890D01*
X585147Y1316200D01*
X584917Y1316459D01*
X584610Y1316562D01*
G01X586982Y1314754D02*
X587250Y1315115D01*
X587480Y1315322D01*
X587787Y1315425D01*
X588055Y1315322D01*
X588247Y1315115D01*
X588400Y1314805D01*
X588438Y1314444D01*
X588400Y1314134D01*
X588247Y1313824D01*
X588017Y1313565D01*
X587748Y1313462D01*
X587442Y1313565D01*
X587173Y1313875D01*
X587020Y1314340D01*
X586982Y1314857D01*
X587058Y1315529D01*
X587173Y1315890D01*
X587365Y1316252D01*
X587633Y1316510D01*
X587902Y1316562D01*
X588170Y1316459D01*
X588362Y1316200D01*
G01X585485Y1319463D02*
X581490D01*
G01X582200Y1353262D02*
Y1362962D01*
G01Y1351862D02*
Y1353262D01*
G01Y1351862D02*
X655800D01*
Y1353262D01*
G01X581490Y1345053D02*
X585485D01*
G01X572170Y1356847D02*
Y1353647D01*
G01X565970D02*
Y1356847D01*
G01X572170Y1353647D02*
X565970D01*
G01X582200Y1376462D02*
X591400D01*
Y1362962D01*
X582200D01*
Y1376462D01*
G01X572170Y1360377D02*
Y1357177D01*
G01X565970Y1360377D02*
X572170D01*
G01X565970Y1357177D02*
Y1360377D01*
G01X572170Y1357177D02*
X565970D01*
G01Y1356847D02*
X572170D01*
G01X569627Y1432492D02*
X569857Y1432130D01*
X570163Y1431924D01*
X570508Y1431872D01*
X570815Y1431924D01*
X571122Y1432182D01*
X571313Y1432492D01*
X571352Y1432802D01*
X571275Y1433164D01*
X571007Y1433422D01*
X570738Y1433525D01*
X570393D01*
G01X570738D02*
X570968Y1433680D01*
X571160Y1433939D01*
X571237Y1434249D01*
X571160Y1434559D01*
X570968Y1434817D01*
X570623Y1434972D01*
X570278Y1434920D01*
X569933Y1434714D01*
G01X574433Y1446128D02*
Y1436286D01*
G01X566753Y1454762D02*
Y1457862D01*
X567673D01*
X567980Y1457707D01*
X568210Y1457345D01*
X568287Y1456932D01*
X568210Y1456519D01*
X568018Y1456209D01*
X567673Y1456054D01*
X566753D01*
G01X569853Y1455382D02*
X570045Y1455072D01*
X570275Y1454865D01*
X570543Y1454762D01*
X570850Y1454865D01*
X571080Y1455072D01*
X571310Y1455382D01*
X571387Y1455795D01*
Y1457862D01*
G01X572953Y1454762D02*
Y1457862D01*
X573873D01*
X574180Y1457707D01*
X574410Y1457345D01*
X574487Y1456932D01*
X574410Y1456519D01*
X574218Y1456209D01*
X573873Y1456054D01*
X572953D01*
G01X576820Y1454762D02*
Y1457862D01*
X576360Y1457242D01*
G01Y1454762D02*
X577280D01*
G01X570770Y1461911D02*
X571028Y1462218D01*
X571183Y1462563D01*
Y1462869D01*
X571028Y1463176D01*
X570770Y1463406D01*
X570408Y1463521D01*
X570046Y1463444D01*
X569736Y1463253D01*
X569530Y1462908D01*
X569426Y1462448D01*
X569220Y1462179D01*
X568858Y1462064D01*
X568496Y1462141D01*
X568238Y1462333D01*
X568083Y1462601D01*
Y1462869D01*
X568186Y1463138D01*
X568445Y1463368D01*
G01X571183Y1464973D02*
X568083D01*
Y1465739D01*
X568238Y1466046D01*
X568445Y1466276D01*
X568755Y1466468D01*
X569116Y1466621D01*
X569633Y1466659D01*
X570150Y1466621D01*
X570511Y1466468D01*
X570821Y1466276D01*
X571028Y1466046D01*
X571183Y1465739D01*
Y1464973D01*
G01Y1467958D02*
X568083Y1468916D01*
X571183Y1469874D01*
G01X570098Y1469529D02*
Y1468303D01*
G01X568241Y1642369D02*
X568433Y1642059D01*
X568663Y1641852D01*
X568931Y1641749D01*
X569238Y1641852D01*
X569468Y1642059D01*
X569698Y1642369D01*
X569775Y1642782D01*
Y1644849D01*
G01X572108Y1641749D02*
Y1644849D01*
X571648Y1644229D01*
G01Y1641749D02*
X572568D01*
G01X575208Y1644849D02*
X574901Y1644746D01*
X574671Y1644487D01*
X574518Y1644177D01*
X574403Y1643764D01*
X574365Y1643299D01*
X574403Y1642834D01*
X574518Y1642421D01*
X574671Y1642111D01*
X574901Y1641852D01*
X575208Y1641749D01*
X575515Y1641852D01*
X575745Y1642111D01*
X575898Y1642421D01*
X576013Y1642834D01*
X576051Y1643299D01*
X576013Y1643764D01*
X575898Y1644177D01*
X575745Y1644487D01*
X575515Y1644746D01*
X575208Y1644849D01*
G01X577656Y1642111D02*
X577925Y1641852D01*
X578231Y1641749D01*
X578538Y1641852D01*
X578806Y1642162D01*
X578998Y1642627D01*
X579075Y1643092D01*
Y1643661D01*
X578998Y1644126D01*
X578806Y1644539D01*
X578576Y1644746D01*
X578308Y1644849D01*
X578001Y1644746D01*
X577771Y1644539D01*
X577618Y1644229D01*
X577541Y1643816D01*
X577618Y1643454D01*
X577810Y1643092D01*
X578040Y1642886D01*
X578308Y1642834D01*
X578615Y1642937D01*
X578845Y1643196D01*
X579075Y1643661D01*
G01X568504Y1668130D02*
Y1646023D01*
G01X570002Y1656415D02*
X570232Y1656725D01*
X570500Y1656880D01*
X570807Y1656932D01*
X571190Y1656829D01*
X571458Y1656570D01*
X571535Y1656260D01*
X571497Y1655950D01*
X571343Y1655692D01*
X570577Y1655175D01*
X570232Y1654814D01*
X570002Y1654297D01*
X569925Y1653832D01*
X571535D01*
G01X575437Y1654372D02*
X575667Y1654010D01*
X575973Y1653804D01*
X576318Y1653752D01*
X576625Y1653804D01*
X576932Y1654062D01*
X577123Y1654372D01*
X577162Y1654682D01*
X577085Y1655044D01*
X576817Y1655302D01*
X576548Y1655405D01*
X576203D01*
G01X576548D02*
X576778Y1655560D01*
X576970Y1655819D01*
X577047Y1656129D01*
X576970Y1656439D01*
X576778Y1656697D01*
X576433Y1656852D01*
X576088Y1656800D01*
X575743Y1656594D01*
G01X582613Y1653722D02*
Y1656822D01*
X581195Y1654600D01*
X583111D01*
G01X572191Y1736629D02*
X571125D01*
Y1739129D01*
X572191D01*
G01X571765Y1737921D02*
X571125D01*
G01X573271Y1736629D02*
Y1739129D01*
X573805D01*
X574018Y1739004D01*
X574178Y1738837D01*
X574311Y1738587D01*
X574418Y1738296D01*
X574445Y1737879D01*
X574418Y1737462D01*
X574311Y1737171D01*
X574178Y1736921D01*
X574018Y1736754D01*
X573805Y1736629D01*
X573271D01*
G01X576218Y1737879D02*
X576751D01*
Y1737129D01*
X576591Y1736879D01*
X576405Y1736712D01*
X576138Y1736629D01*
X575871Y1736712D01*
X575685Y1736879D01*
X575525Y1737129D01*
X575418Y1737421D01*
X575365Y1737754D01*
Y1738046D01*
X575418Y1738296D01*
X575525Y1738587D01*
X575685Y1738837D01*
X575845Y1739004D01*
X576058Y1739129D01*
X576245D01*
X576458Y1739046D01*
X576618Y1738879D01*
G01X578791Y1736629D02*
X577725D01*
Y1739129D01*
X578791D01*
G01X578365Y1737921D02*
X577725D01*
G01X582658Y1736629D02*
X582445Y1736671D01*
X582258Y1736837D01*
X582098Y1737087D01*
X581991Y1737379D01*
X581938Y1737712D01*
Y1738046D01*
X581991Y1738379D01*
X582098Y1738671D01*
X582258Y1738921D01*
X582445Y1739087D01*
X582658Y1739129D01*
X582871Y1739087D01*
X583058Y1738921D01*
X583218Y1738671D01*
X583325Y1738379D01*
X583378Y1738046D01*
Y1737712D01*
X583325Y1737379D01*
X583218Y1737087D01*
X583058Y1736837D01*
X582871Y1736671D01*
X582658Y1736629D01*
G01X584351D02*
Y1739129D01*
X585365D01*
G01X584991Y1737921D02*
X584351D01*
G01X588671Y1736629D02*
Y1739129D01*
X589205D01*
X589418Y1739004D01*
X589578Y1738837D01*
X589711Y1738587D01*
X589818Y1738296D01*
X589845Y1737879D01*
X589818Y1737462D01*
X589711Y1737171D01*
X589578Y1736921D01*
X589418Y1736754D01*
X589205Y1736629D01*
X588671D01*
G01X590791D02*
X591458Y1739129D01*
X592125Y1736629D01*
G01X591885Y1737504D02*
X591031D01*
G01X593071Y1739129D02*
Y1737337D01*
X593178Y1736962D01*
X593391Y1736712D01*
X593658Y1736629D01*
X593925Y1736712D01*
X594138Y1736962D01*
X594245Y1737337D01*
Y1739129D01*
G01X596018Y1737879D02*
X596551D01*
Y1737129D01*
X596391Y1736879D01*
X596205Y1736712D01*
X595938Y1736629D01*
X595671Y1736712D01*
X595485Y1736879D01*
X595325Y1737129D01*
X595218Y1737421D01*
X595165Y1737754D01*
Y1738046D01*
X595218Y1738296D01*
X595325Y1738587D01*
X595485Y1738837D01*
X595645Y1739004D01*
X595858Y1739129D01*
X596045D01*
X596258Y1739046D01*
X596418Y1738879D01*
G01X597498Y1736629D02*
Y1739129D01*
G01X598618D02*
Y1736629D01*
G01Y1737879D02*
X597498D01*
G01X600258Y1739129D02*
Y1736629D01*
G01X599645Y1739129D02*
X600871D01*
G01X602991Y1736629D02*
X601925D01*
Y1739129D01*
X602991D01*
G01X602565Y1737921D02*
X601925D01*
G01X604125Y1736629D02*
Y1739129D01*
X604791D01*
X605005Y1739004D01*
X605138Y1738837D01*
X605191Y1738504D01*
X605138Y1738171D01*
X604978Y1737962D01*
X604791Y1737837D01*
X604125D01*
G01X604791D02*
X605191Y1736629D01*
G01X609645Y1738921D02*
X609485Y1739046D01*
X609298Y1739129D01*
X609085D01*
X608845Y1739004D01*
X608658Y1738796D01*
X608525Y1738546D01*
X608418Y1738129D01*
X608391Y1737754D01*
X608445Y1737379D01*
X608525Y1737129D01*
X608685Y1736879D01*
X608871Y1736712D01*
X609058Y1736629D01*
X609245D01*
X609431Y1736712D01*
X609591Y1736837D01*
X609725Y1737004D01*
G01X610591Y1736629D02*
X611258Y1739129D01*
X611925Y1736629D01*
G01X611685Y1737504D02*
X610831D01*
G01X612925Y1736629D02*
Y1739129D01*
X613591D01*
X613805Y1739004D01*
X613938Y1738837D01*
X613991Y1738504D01*
X613938Y1738171D01*
X613778Y1737962D01*
X613591Y1737837D01*
X612925D01*
G01X613591D02*
X613991Y1736629D01*
G01X615071D02*
Y1739129D01*
X615605D01*
X615818Y1739004D01*
X615978Y1738837D01*
X616111Y1738587D01*
X616218Y1738296D01*
X616245Y1737879D01*
X616218Y1737462D01*
X616111Y1737171D01*
X615978Y1736921D01*
X615818Y1736754D01*
X615605Y1736629D01*
X615071D01*
G01X569108Y1736412D02*
X570008Y1737312D01*
G01X568504Y1781456D02*
Y1739060D01*
G01X598820Y86762D02*
X595620D01*
G01D02*
Y92962D01*
G01X590930Y86420D02*
X587730D01*
G01X590930Y92620D02*
Y86420D01*
G01X587730D02*
Y92620D01*
G01X591640Y86420D02*
Y92620D01*
X594840D01*
Y86420D01*
X591640D01*
G01X595620Y92962D02*
X598820D01*
G01X587730Y92620D02*
X590930D01*
G01X586720Y128042D02*
Y131242D01*
G01X592920Y128042D02*
X586720D01*
G01X592920Y131242D02*
Y128042D01*
G01X586720Y131242D02*
X592920D01*
G01X596920Y137914D02*
Y134714D01*
G01X590720D02*
Y137914D01*
G01X596920Y134714D02*
X590720D01*
G01X596920Y126914D02*
Y123714D01*
G01X590720Y126914D02*
X596920D01*
G01X590720Y123714D02*
Y126914D01*
G01X596920Y123714D02*
X590720D01*
G01X595640Y143329D02*
Y155129D01*
G01X585840Y143329D02*
X595640D01*
G01X585840Y155129D02*
Y143329D01*
G01X597195Y147752D02*
X600395D01*
G01X597195Y141552D02*
Y147752D01*
G01X600395Y141552D02*
X597195D01*
G01X600324Y148771D02*
X597124D01*
G01D02*
Y154971D01*
G01X590720Y137914D02*
X596920D01*
G01X593127Y171607D02*
Y162945D01*
G01X586590Y156396D02*
Y157791D01*
X585823Y159496D01*
G01X587357D02*
X586590Y157791D01*
G01X589038Y156758D02*
X589307Y156499D01*
X589613Y156396D01*
X589920Y156499D01*
X590188Y156809D01*
X590380Y157274D01*
X590457Y157739D01*
Y158308D01*
X590380Y158773D01*
X590188Y159186D01*
X589958Y159393D01*
X589690Y159496D01*
X589383Y159393D01*
X589153Y159186D01*
X589000Y158876D01*
X588923Y158463D01*
X589000Y158101D01*
X589192Y157739D01*
X589422Y157533D01*
X589690Y157481D01*
X589997Y157584D01*
X590227Y157843D01*
X590457Y158308D01*
G01X595640Y155129D02*
X585840D01*
G01X597124Y154971D02*
X600324D01*
G01X594655Y161080D02*
X600855D01*
G01X594655Y157880D02*
Y161080D01*
G01X600855Y157880D02*
X594655D01*
G01X583950Y159284D02*
Y156084D01*
G01X593620Y173012D02*
Y176212D01*
G01X599820Y173012D02*
X593620D01*
G01Y176212D02*
X599820D01*
G01X594820Y177762D02*
X591620D01*
G01X594820Y183962D02*
Y177762D01*
G01X591620Y183962D02*
X594820D01*
G01X591620Y177762D02*
Y183962D01*
G01X601320Y177762D02*
X598120D01*
G01Y183962D02*
X601320D01*
G01X598120Y177762D02*
Y183962D01*
G01X595250Y200072D02*
Y202025D01*
G01X597203Y200072D02*
X595250D01*
G01X586550Y191692D02*
Y188492D01*
G01X601320Y185762D02*
X598120D01*
G01Y191962D02*
X601320D01*
G01X598120Y185762D02*
Y191962D01*
G01X594820Y185762D02*
X591620D01*
G01X594820Y191962D02*
Y185762D01*
G01X591620Y191962D02*
X594820D01*
G01X591620Y185762D02*
Y191962D01*
G01X586556Y203978D02*
Y200778D01*
G01Y195978D02*
Y192778D01*
G01Y199978D02*
Y196778D01*
G01X595250Y211884D02*
X597203D01*
G01X595250Y209931D02*
Y211884D01*
G01X586556Y211978D02*
Y208778D01*
G01Y207978D02*
Y204778D01*
G01X586320Y232462D02*
Y229262D01*
G01Y226962D02*
Y223762D01*
G01Y222962D02*
Y219762D01*
G01X594714Y255932D02*
Y259132D01*
G01X600914Y255932D02*
X594714D01*
G01Y259132D02*
X600914D01*
G01X584964Y250602D02*
Y253802D01*
G01X591164Y250602D02*
X584964D01*
G01X591164Y253802D02*
Y250602D01*
G01X584964Y253802D02*
X591164D01*
G01X593252Y290127D02*
Y286927D01*
G01X587052Y290127D02*
X593252D01*
G01X587052Y286927D02*
Y290127D01*
G01X593252Y286927D02*
X587052D01*
G01X583445Y295057D02*
Y298257D01*
G01X589645Y295057D02*
X583445D01*
G01X589645Y298257D02*
Y295057D01*
G01X583445Y298257D02*
X589645D01*
G01X583445Y309971D02*
Y313171D01*
G01X589645Y309971D02*
X583445D01*
G01X589645Y313171D02*
Y309971D01*
G01X583445Y313171D02*
X589645D01*
G01X583445Y302452D02*
Y305652D01*
G01X589645Y302452D02*
X583445D01*
G01X589645Y305652D02*
Y302452D01*
G01X583445Y305652D02*
X589645D01*
G01X589705Y361754D02*
Y364954D01*
G01X595905Y361754D02*
X589705D01*
G01X595905Y364954D02*
Y361754D01*
G01X589705Y364954D02*
X595905D01*
G01X584407Y423309D02*
Y421087D01*
X584560Y420622D01*
X584867Y420312D01*
X585250Y420209D01*
X585633Y420312D01*
X585940Y420622D01*
X586093Y421087D01*
Y423309D01*
G01X587622Y422792D02*
X587852Y423102D01*
X588120Y423257D01*
X588427Y423309D01*
X588810Y423206D01*
X589078Y422947D01*
X589155Y422637D01*
X589117Y422327D01*
X588963Y422069D01*
X588197Y421552D01*
X587852Y421191D01*
X587622Y420674D01*
X587545Y420209D01*
X589155D01*
G01X590722Y422792D02*
X590952Y423102D01*
X591220Y423257D01*
X591527Y423309D01*
X591910Y423206D01*
X592178Y422947D01*
X592255Y422637D01*
X592217Y422327D01*
X592063Y422069D01*
X591297Y421552D01*
X590952Y421191D01*
X590722Y420674D01*
X590645Y420209D01*
X592255D01*
G01X593707Y420674D02*
X593937Y420416D01*
X594205Y420261D01*
X594550Y420209D01*
X594895Y420312D01*
X595163Y420519D01*
X595355Y420881D01*
X595393Y421294D01*
X595317Y421707D01*
X595125Y421966D01*
X594857Y422172D01*
X594588Y422224D01*
X594320Y422172D01*
X593975Y421966D01*
X594090Y423309D01*
X595125D01*
G01X606551Y424850D02*
X597889D01*
G01Y435874D02*
Y424850D01*
G01X598120Y417962D02*
X604320D01*
G01X598120Y414762D02*
Y417962D01*
G01X604320Y414762D02*
X598120D01*
G01X597889Y435874D02*
X606551D01*
G01X592620Y435462D02*
X595820D01*
G01X592620Y429262D02*
Y435462D01*
G01X595820Y429262D02*
X592620D01*
G01X595820Y435462D02*
Y429262D01*
G01X598330Y457088D02*
Y460288D01*
G01X604530Y457088D02*
X598330D01*
G01Y460288D02*
X604530D01*
G01X604499Y453000D02*
X598299D01*
Y456200D01*
X604499D01*
Y453000D01*
G01X589534Y470232D02*
X589227Y470284D01*
X588959Y470490D01*
X588729Y470800D01*
X588576Y471162D01*
X588499Y471575D01*
Y471989D01*
X588576Y472402D01*
X588729Y472764D01*
X588959Y473074D01*
X589227Y473280D01*
X589534Y473332D01*
X589841Y473280D01*
X590109Y473074D01*
X590339Y472764D01*
X590492Y472402D01*
X590569Y471989D01*
Y471575D01*
X590492Y471162D01*
X590339Y470800D01*
X590109Y470490D01*
X589841Y470284D01*
X589534Y470232D01*
G01X589841Y471059D02*
X590301Y470232D01*
G01X591791Y470697D02*
X592021Y470439D01*
X592289Y470284D01*
X592634Y470232D01*
X592979Y470335D01*
X593247Y470542D01*
X593439Y470904D01*
X593477Y471317D01*
X593401Y471730D01*
X593209Y471989D01*
X592941Y472195D01*
X592672Y472247D01*
X592404Y472195D01*
X592059Y471989D01*
X592174Y473332D01*
X593209D01*
G01X595734D02*
X595427Y473229D01*
X595197Y472970D01*
X595044Y472660D01*
X594929Y472247D01*
X594891Y471782D01*
X594929Y471317D01*
X595044Y470904D01*
X595197Y470594D01*
X595427Y470335D01*
X595734Y470232D01*
X596041Y470335D01*
X596271Y470594D01*
X596424Y470904D01*
X596539Y471317D01*
X596577Y471782D01*
X596539Y472247D01*
X596424Y472660D01*
X596271Y472970D01*
X596041Y473229D01*
X595734Y473332D01*
G01X598579Y463261D02*
Y466608D01*
X600779Y468508D01*
X598579Y470408D01*
Y473755D01*
X607241D01*
Y463261D01*
X598579D01*
G01X605551Y487850D02*
X596889D01*
G01Y498874D02*
Y487850D01*
G01X598120Y480762D02*
Y483962D01*
G01X604320Y480762D02*
X598120D01*
G01Y483962D02*
X604320D01*
G01X586470Y486612D02*
Y489812D01*
G01X592670Y486612D02*
X586470D01*
G01X592670Y489812D02*
Y486612D01*
G01X586470Y489812D02*
X592670D01*
G01X587090Y507302D02*
X586783Y507354D01*
X586515Y507560D01*
X586285Y507870D01*
X586132Y508232D01*
X586055Y508645D01*
Y509059D01*
X586132Y509472D01*
X586285Y509834D01*
X586515Y510144D01*
X586783Y510350D01*
X587090Y510402D01*
X587397Y510350D01*
X587665Y510144D01*
X587895Y509834D01*
X588048Y509472D01*
X588125Y509059D01*
Y508645D01*
X588048Y508232D01*
X587895Y507870D01*
X587665Y507560D01*
X587397Y507354D01*
X587090Y507302D01*
G01X587397Y508129D02*
X587857Y507302D01*
G01X590190D02*
Y510402D01*
X589730Y509782D01*
G01Y507302D02*
X590650D01*
G01X593750D02*
Y510402D01*
X592332Y508180D01*
X594248D01*
G01X596850Y507302D02*
Y510402D01*
X595432Y508180D01*
X597348D01*
G01X596889Y498874D02*
X605551D01*
G01X598400Y500432D02*
X595200D01*
G01X598400Y506632D02*
Y500432D01*
G01X595200Y506632D02*
X598400D01*
G01X595200Y500432D02*
Y506632D01*
G01X595747Y512531D02*
X592400D01*
X590500Y514731D01*
X588600Y512531D01*
X585253D01*
Y521193D01*
X595747D01*
Y512531D01*
G01X589900Y526462D02*
X596100D01*
Y523262D01*
X589900D01*
Y526462D01*
G01X584542Y995227D02*
Y998327D01*
G01X586152D02*
Y995227D01*
G01Y996777D02*
X584542D01*
G01X587719Y997810D02*
X587949Y998120D01*
X588217Y998275D01*
X588524Y998327D01*
X588907Y998224D01*
X589175Y997965D01*
X589252Y997655D01*
X589214Y997345D01*
X589060Y997087D01*
X588294Y996570D01*
X587949Y996209D01*
X587719Y995692D01*
X587642Y995227D01*
X589252D01*
G01X590819Y996519D02*
X591087Y996880D01*
X591317Y997087D01*
X591624Y997190D01*
X591892Y997087D01*
X592084Y996880D01*
X592237Y996570D01*
X592275Y996209D01*
X592237Y995899D01*
X592084Y995589D01*
X591854Y995330D01*
X591585Y995227D01*
X591279Y995330D01*
X591010Y995640D01*
X590857Y996105D01*
X590819Y996622D01*
X590895Y997294D01*
X591010Y997655D01*
X591202Y998017D01*
X591470Y998275D01*
X591739Y998327D01*
X592007Y998224D01*
X592199Y997965D01*
G01X585485Y1345053D02*
Y1319463D01*
G01X595740Y1367239D02*
X595425Y1367552D01*
X594900Y1367787D01*
X594165Y1367944D01*
X593535Y1367787D01*
X593115Y1367474D01*
X592800Y1366925D01*
Y1364810D01*
X599100D01*
Y1367395D01*
X598680Y1367944D01*
X598050Y1368257D01*
X597315Y1368414D01*
X596580Y1368257D01*
X595950Y1367787D01*
X595740Y1367239D01*
Y1364810D01*
G01X599100Y1373852D02*
X592800D01*
X597315Y1370954D01*
Y1374870D01*
G01X589840Y1364909D02*
X583540D01*
Y1366475D01*
X583855Y1367102D01*
X584275Y1367572D01*
X584905Y1367964D01*
X585640Y1368277D01*
X586690Y1368355D01*
X587740Y1368277D01*
X588475Y1367964D01*
X589105Y1367572D01*
X589525Y1367102D01*
X589840Y1366475D01*
Y1364909D01*
G01Y1373872D02*
X583540D01*
X588055Y1370974D01*
Y1374890D01*
G01X600600Y1362962D02*
X591400D01*
G01Y1376462D02*
X600600D01*
G01X589184Y1654187D02*
X589414Y1653929D01*
X589682Y1653774D01*
X590027Y1653722D01*
X590372Y1653825D01*
X590640Y1654032D01*
X590832Y1654394D01*
X590870Y1654807D01*
X590794Y1655220D01*
X590602Y1655479D01*
X590334Y1655685D01*
X590065Y1655737D01*
X589797Y1655685D01*
X589452Y1655479D01*
X589567Y1656822D01*
X590602D01*
G01X597173Y1655014D02*
X597441Y1655375D01*
X597671Y1655582D01*
X597978Y1655685D01*
X598246Y1655582D01*
X598438Y1655375D01*
X598591Y1655065D01*
X598629Y1654704D01*
X598591Y1654394D01*
X598438Y1654084D01*
X598208Y1653825D01*
X597939Y1653722D01*
X597633Y1653825D01*
X597364Y1654135D01*
X597211Y1654600D01*
X597173Y1655117D01*
X597249Y1655789D01*
X597364Y1656150D01*
X597556Y1656512D01*
X597824Y1656770D01*
X598093Y1656822D01*
X598361Y1656719D01*
X598553Y1656460D01*
G01X598820Y92962D02*
Y86762D01*
G01X608744Y134848D02*
Y137348D01*
X608424Y136848D01*
G01Y134848D02*
X609064D01*
G01X610357Y135223D02*
X610517Y135015D01*
X610704Y134890D01*
X610944Y134848D01*
X611184Y134931D01*
X611371Y135098D01*
X611504Y135390D01*
X611531Y135723D01*
X611477Y136056D01*
X611344Y136265D01*
X611157Y136431D01*
X610971Y136473D01*
X610784Y136431D01*
X610544Y136265D01*
X610624Y137348D01*
X611344D01*
G01X612644Y137281D02*
Y135781D01*
G01X604479Y126492D02*
X607679D01*
G01X604479Y120292D02*
Y126492D01*
G01X607679Y120292D02*
X604479D01*
G01X607679Y126492D02*
Y120292D01*
G01X615984D02*
X612784D01*
G01Y126492D02*
X615984D01*
G01X612784Y120292D02*
Y126492D01*
G01X611704Y120292D02*
X608504D01*
G01X611704Y126492D02*
Y120292D01*
G01X608504Y126492D02*
X611704D01*
G01X608504Y120292D02*
Y126492D01*
G01X603878Y120292D02*
X600678D01*
G01X603878Y126492D02*
Y120292D01*
G01X600678Y126492D02*
X603878D01*
G01X600678Y120292D02*
Y126492D01*
G01X602270Y141722D02*
Y144222D01*
X601950Y143722D01*
G01Y141722D02*
X602590D01*
G01X604790D02*
Y144222D01*
X603803Y142430D01*
X605137D01*
G01X607144Y150781D02*
X604144D01*
G01X608801Y138938D02*
Y141781D01*
G01X611644Y138938D02*
X608801D01*
G01X600395Y147752D02*
Y141552D01*
G01X600324Y154971D02*
Y148771D01*
G01X608750Y159782D02*
X608937Y159824D01*
X609150Y159949D01*
X609283Y160157D01*
X609337Y160449D01*
X609283Y160740D01*
X609123Y160990D01*
X608883Y161115D01*
X608617D01*
X608457Y161199D01*
X608323Y161407D01*
X608270Y161699D01*
X608350Y161990D01*
X608537Y162199D01*
X608750Y162282D01*
X608963Y162199D01*
X609150Y161990D01*
X609230Y161699D01*
X609177Y161407D01*
X609043Y161199D01*
X608883Y161115D01*
X608617D01*
X608377Y160990D01*
X608217Y160740D01*
X608163Y160449D01*
X608217Y160157D01*
X608350Y159949D01*
X608563Y159824D01*
X608750Y159782D01*
G01X611491Y160048D02*
X611544Y160590D01*
X611624Y161048D01*
X611731Y161465D01*
X611864Y161923D01*
X612077Y162548D01*
X611011D01*
G01X608801Y158624D02*
X611644D01*
G01X608801Y155781D02*
Y158624D01*
G01X600855Y161080D02*
Y157880D01*
G01X600120Y163012D02*
Y166212D01*
G01X606320Y163012D02*
X600120D01*
G01X606320Y166212D02*
Y163012D01*
G01X600120Y166212D02*
X606320D01*
G01X614340Y175847D02*
X611140D01*
Y182047D01*
G01X611136Y172675D02*
Y178875D01*
X614336D01*
G01X599820Y176212D02*
Y173012D01*
G01X608235Y182462D02*
Y185662D01*
G01X611110Y182462D02*
X608235D01*
G01X601320Y183962D02*
Y177762D01*
G01X607062Y200072D02*
X605109D01*
G01X607062Y202025D02*
Y200072D01*
G01X609856Y201278D02*
Y204478D01*
G01X616056Y201278D02*
X609856D01*
G01X608235Y185662D02*
X611680D01*
G01X601320Y191962D02*
Y185762D01*
G01X614827Y219102D02*
Y216880D01*
X614980Y216415D01*
X615287Y216105D01*
X615670Y216002D01*
X616053Y216105D01*
X616360Y216415D01*
X616513Y216880D01*
Y219102D01*
G01X618042Y218585D02*
X618272Y218895D01*
X618540Y219050D01*
X618847Y219102D01*
X619230Y218999D01*
X619498Y218740D01*
X619575Y218430D01*
X619537Y218120D01*
X619383Y217862D01*
X618617Y217345D01*
X618272Y216984D01*
X618042Y216467D01*
X617965Y216002D01*
X619575D01*
G01X621142Y217294D02*
X621410Y217655D01*
X621640Y217862D01*
X621947Y217965D01*
X622215Y217862D01*
X622407Y217655D01*
X622560Y217345D01*
X622598Y216984D01*
X622560Y216674D01*
X622407Y216364D01*
X622177Y216105D01*
X621908Y216002D01*
X621602Y216105D01*
X621333Y216415D01*
X621180Y216880D01*
X621142Y217397D01*
X621218Y218069D01*
X621333Y218430D01*
X621525Y218792D01*
X621793Y219050D01*
X622062Y219102D01*
X622330Y218999D01*
X622522Y218740D01*
G01X625430Y216002D02*
Y219102D01*
X624012Y216880D01*
X625928D01*
G01X607062Y211884D02*
Y209931D01*
G01X605109Y211884D02*
X607062D01*
G01X609856Y204478D02*
X616056D01*
G01X609856Y205778D02*
Y208978D01*
G01X616056Y205778D02*
X609856D01*
G01Y208978D02*
X616056D01*
G01X602022Y236226D02*
Y234004D01*
X602175Y233539D01*
X602482Y233229D01*
X602865Y233126D01*
X603248Y233229D01*
X603555Y233539D01*
X603708Y234004D01*
Y236226D01*
G01X605313Y233488D02*
X605582Y233229D01*
X605888Y233126D01*
X606195Y233229D01*
X606463Y233539D01*
X606655Y234004D01*
X606732Y234469D01*
Y235038D01*
X606655Y235503D01*
X606463Y235916D01*
X606233Y236123D01*
X605965Y236226D01*
X605658Y236123D01*
X605428Y235916D01*
X605275Y235606D01*
X605198Y235193D01*
X605275Y234831D01*
X605467Y234469D01*
X605697Y234263D01*
X605965Y234211D01*
X606272Y234314D01*
X606502Y234573D01*
X606732Y235038D01*
G01X609065Y233126D02*
X609333Y233178D01*
X609640Y233333D01*
X609832Y233591D01*
X609908Y233953D01*
X609832Y234314D01*
X609602Y234624D01*
X609257Y234779D01*
X608873D01*
X608643Y234883D01*
X608452Y235141D01*
X608375Y235503D01*
X608490Y235864D01*
X608758Y236123D01*
X609065Y236226D01*
X609372Y236123D01*
X609640Y235864D01*
X609755Y235503D01*
X609678Y235141D01*
X609487Y234883D01*
X609257Y234779D01*
X608873D01*
X608528Y234624D01*
X608298Y234314D01*
X608222Y233953D01*
X608298Y233591D01*
X608490Y233333D01*
X608797Y233178D01*
X609065Y233126D01*
G01X609215Y232130D02*
X612415D01*
G01X607215Y230063D02*
X609215Y232130D01*
G01X605215D02*
X607215Y230063D01*
G01X602015Y232130D02*
X605215D01*
G01X602015Y220122D02*
Y232130D01*
G01X612415Y220122D02*
X602015D01*
G01X612415Y232130D02*
Y220122D01*
G01X607666Y248633D02*
Y246411D01*
X607819Y245946D01*
X608126Y245636D01*
X608509Y245533D01*
X608892Y245636D01*
X609199Y245946D01*
X609352Y246411D01*
Y248633D01*
G01X611609Y245533D02*
Y248633D01*
X611149Y248013D01*
G01Y245533D02*
X612069D01*
G01X613866Y246153D02*
X614096Y245791D01*
X614402Y245585D01*
X614747Y245533D01*
X615054Y245585D01*
X615361Y245843D01*
X615552Y246153D01*
X615591Y246463D01*
X615514Y246825D01*
X615246Y247083D01*
X614977Y247186D01*
X614632D01*
G01X614977D02*
X615207Y247341D01*
X615399Y247600D01*
X615476Y247910D01*
X615399Y248220D01*
X615207Y248478D01*
X614862Y248633D01*
X614517Y248581D01*
X614172Y248375D01*
G01X618269Y245533D02*
Y248633D01*
X616851Y246411D01*
X618767D01*
G01X615490Y259297D02*
X613159Y256966D01*
G01X607719Y250635D02*
X618599D01*
G01X607719Y259297D02*
Y250635D01*
G01X610828Y259297D02*
X607719D01*
G01X613159Y256966D02*
X610828Y259297D01*
G01X600914Y259132D02*
Y255932D01*
G01X603125Y279730D02*
X606325D01*
G01X603125Y273530D02*
Y279730D01*
G01X606325Y273530D02*
X603125D01*
G01X606325Y279730D02*
Y273530D01*
G01X615695D02*
X612495D01*
G01Y279730D02*
X615695D01*
G01X612495Y273530D02*
Y279730D01*
G01X610495Y273530D02*
X607295D01*
G01X610495Y279730D02*
Y273530D01*
G01X607295Y279730D02*
X610495D01*
G01X607295Y273530D02*
Y279730D01*
G01X610772Y290177D02*
X606780Y287185D01*
G01D02*
X602264D01*
G01D02*
Y313169D01*
G01X614764Y287185D02*
X610772Y290177D01*
G01X602264Y313169D02*
X619280D01*
G01X606075Y325499D02*
X609275D01*
G01X606075Y319299D02*
Y325499D01*
G01X609275Y319299D02*
X606075D01*
G01X609275Y325499D02*
Y319299D01*
G01X614035Y325555D02*
X617235D01*
G01X614035Y319355D02*
Y325555D01*
G01X617235Y319355D02*
X614035D01*
G01X613209Y319320D02*
X610009D01*
G01X613209Y325520D02*
Y319320D01*
G01X610009Y325520D02*
X613209D01*
G01X610009Y319320D02*
Y325520D01*
G01X605422Y319270D02*
X602222D01*
G01X605422Y325470D02*
Y319270D01*
G01X602222Y325470D02*
X605422D01*
G01X602222Y319270D02*
Y325470D01*
G01X606551Y435874D02*
Y424850D01*
G01X604320Y417962D02*
Y414762D01*
G01X606320Y445962D02*
Y442762D01*
G01X600120D02*
Y445962D01*
G01X606320Y442762D02*
X600120D01*
G01X604530Y460288D02*
Y457088D01*
G01X606320Y450962D02*
Y447762D01*
G01X600120Y450962D02*
X606320D01*
G01X600120Y447762D02*
Y450962D01*
G01X606320Y447762D02*
X600120D01*
G01Y445962D02*
X606320D01*
G01X605551Y498874D02*
Y487850D01*
G01X604320Y483962D02*
Y480762D01*
G01X614650Y506299D02*
Y488701D01*
X607350D01*
Y506299D01*
X614650D01*
G01X625126Y510050D02*
X613314D01*
G01D02*
Y522674D01*
G01X605320Y508462D02*
Y505262D01*
G01X599120Y508462D02*
X605320D01*
G01X599120Y505262D02*
Y508462D01*
G01X605320Y505262D02*
X599120D01*
G01X605320Y512462D02*
Y509262D01*
G01X599120D02*
Y512462D01*
G01X605320Y509262D02*
X599120D01*
G01X613314Y522674D02*
X625126D01*
G01X599120Y512462D02*
X605320D01*
G01X599120Y513262D02*
Y516462D01*
G01X605320Y513262D02*
X599120D01*
G01X605320Y516462D02*
Y513262D01*
G01X599120Y516462D02*
X605320D01*
G01X604875Y699751D02*
Y695236D01*
X605188Y694291D01*
X605815Y693661D01*
X606598Y693451D01*
X607381Y693661D01*
X608008Y694291D01*
X608321Y695236D01*
Y699751D01*
G01X612898Y693451D02*
Y699751D01*
X611958Y698491D01*
G01Y693451D02*
X613838D01*
G01X608627Y1354262D02*
Y1360562D01*
X610193D01*
X610820Y1360247D01*
X611290Y1359827D01*
X611682Y1359197D01*
X611995Y1358462D01*
X612073Y1357412D01*
X611995Y1356362D01*
X611682Y1355627D01*
X611290Y1354997D01*
X610820Y1354577D01*
X610193Y1354262D01*
X608627D01*
G01X615710Y1360562D02*
X617590D01*
G01X616650D02*
Y1354262D01*
G01X615710D02*
X617590D01*
G01X620913D02*
Y1360562D01*
X622950Y1355312D01*
X624987Y1360562D01*
Y1354262D01*
G01X627213D02*
Y1360562D01*
X629250Y1355312D01*
X631287Y1360562D01*
Y1354262D01*
G01X614240Y1367139D02*
X613925Y1367452D01*
X613400Y1367687D01*
X612665Y1367844D01*
X612035Y1367687D01*
X611615Y1367374D01*
X611300Y1366825D01*
Y1364710D01*
X617600D01*
Y1367295D01*
X617180Y1367844D01*
X616550Y1368157D01*
X615815Y1368314D01*
X615080Y1368157D01*
X614450Y1367687D01*
X614240Y1367139D01*
Y1364710D01*
G01X616655Y1371089D02*
X617180Y1371559D01*
X617495Y1372107D01*
X617600Y1372812D01*
X617390Y1373517D01*
X616970Y1374065D01*
X616235Y1374457D01*
X615395Y1374535D01*
X614555Y1374379D01*
X614030Y1373987D01*
X613610Y1373439D01*
X613505Y1372890D01*
X613610Y1372342D01*
X614030Y1371637D01*
X611300Y1371872D01*
Y1373987D01*
G01X608400Y1364689D02*
X602100D01*
Y1366255D01*
X602415Y1366882D01*
X602835Y1367352D01*
X603465Y1367744D01*
X604200Y1368057D01*
X605250Y1368135D01*
X606300Y1368057D01*
X607035Y1367744D01*
X607665Y1367352D01*
X608085Y1366882D01*
X608400Y1366255D01*
Y1364689D01*
G01X607455Y1370989D02*
X607980Y1371459D01*
X608295Y1372007D01*
X608400Y1372712D01*
X608190Y1373417D01*
X607770Y1373965D01*
X607035Y1374357D01*
X606195Y1374435D01*
X605355Y1374279D01*
X604830Y1373887D01*
X604410Y1373339D01*
X604305Y1372790D01*
X604410Y1372242D01*
X604830Y1371537D01*
X602100Y1371772D01*
Y1373887D01*
G01X600600Y1376462D02*
Y1362962D01*
G01X609800D02*
X600600D01*
G01X609800Y1376462D02*
Y1362962D01*
G01X619000D02*
X609800D01*
G01X600600Y1376462D02*
X609800D01*
G01D02*
X619000D01*
G01X613649Y1653722D02*
X613917Y1653774D01*
X614224Y1653929D01*
X614416Y1654187D01*
X614492Y1654549D01*
X614416Y1654910D01*
X614186Y1655220D01*
X613841Y1655375D01*
X613457D01*
X613227Y1655479D01*
X613036Y1655737D01*
X612959Y1656099D01*
X613074Y1656460D01*
X613342Y1656719D01*
X613649Y1656822D01*
X613956Y1656719D01*
X614224Y1656460D01*
X614339Y1656099D01*
X614262Y1655737D01*
X614071Y1655479D01*
X613841Y1655375D01*
X613457D01*
X613112Y1655220D01*
X612882Y1654910D01*
X612806Y1654549D01*
X612882Y1654187D01*
X613074Y1653929D01*
X613381Y1653774D01*
X613649Y1653722D01*
G01X605698D02*
X605775Y1654394D01*
X605890Y1654962D01*
X606043Y1655479D01*
X606235Y1656047D01*
X606542Y1656822D01*
X605008D01*
G01X639104Y64567D02*
X625904D01*
G01X636017Y86439D02*
X629817D01*
G01D02*
Y89639D01*
G01X623600Y86762D02*
X620400D01*
G01X623600Y92962D02*
Y86762D01*
G01X620400D02*
Y92962D01*
G01X629817Y89639D02*
X636017D01*
G01Y90519D02*
X629817D01*
G01D02*
Y93719D01*
G01D02*
X636017D01*
G01X620400Y92962D02*
X623600D01*
G01X623957Y136781D02*
X624117Y137031D01*
X624304Y137156D01*
X624517Y137198D01*
X624784Y137115D01*
X624971Y136906D01*
X625024Y136656D01*
X624997Y136406D01*
X624891Y136198D01*
X624357Y135781D01*
X624117Y135490D01*
X623957Y135073D01*
X623904Y134698D01*
X625024D01*
G01X626664D02*
Y137198D01*
X626344Y136698D01*
G01Y134698D02*
X626984D01*
G01X622644Y137281D02*
Y134281D01*
G01X616860Y126492D02*
X620060D01*
G01X616860Y120292D02*
Y126492D01*
G01X620060Y120292D02*
X616860D01*
G01X620060Y126492D02*
Y120292D01*
G01X632551D02*
X629351D01*
G01Y126492D02*
X632551D01*
G01X629351Y120292D02*
Y126492D01*
G01X615984D02*
Y120292D01*
G01X628299D02*
X625099D01*
G01X628299Y126492D02*
Y120292D01*
G01X625099Y126492D02*
X628299D01*
G01X625099Y120292D02*
Y126492D01*
G01X624192Y120292D02*
X620992D01*
G01X624192Y126492D02*
Y120292D01*
G01X620992Y126492D02*
X624192D01*
G01X620992Y120292D02*
Y126492D01*
G01X630144Y148781D02*
X631644D01*
G01X628487Y138938D02*
X625644D01*
G01X628487Y141781D02*
Y138938D01*
G01X631272Y165036D02*
Y162814D01*
X631425Y162349D01*
X631732Y162039D01*
X632115Y161936D01*
X632498Y162039D01*
X632805Y162349D01*
X632958Y162814D01*
Y165036D01*
G01X634372Y162556D02*
X634602Y162194D01*
X634908Y161988D01*
X635253Y161936D01*
X635560Y161988D01*
X635867Y162246D01*
X636058Y162556D01*
X636097Y162866D01*
X636020Y163228D01*
X635752Y163486D01*
X635483Y163589D01*
X635138D01*
G01X635483D02*
X635713Y163744D01*
X635905Y164003D01*
X635982Y164313D01*
X635905Y164623D01*
X635713Y164881D01*
X635368Y165036D01*
X635023Y164984D01*
X634678Y164778D01*
G01X638315Y161936D02*
Y165036D01*
X637855Y164416D01*
G01Y161936D02*
X638775D01*
G01X640572Y162556D02*
X640802Y162194D01*
X641108Y161988D01*
X641453Y161936D01*
X641760Y161988D01*
X642067Y162246D01*
X642258Y162556D01*
X642297Y162866D01*
X642220Y163228D01*
X641952Y163486D01*
X641683Y163589D01*
X641338D01*
G01X641683D02*
X641913Y163744D01*
X642105Y164003D01*
X642182Y164313D01*
X642105Y164623D01*
X641913Y164881D01*
X641568Y165036D01*
X641223Y164984D01*
X640878Y164778D01*
G01X630663Y157975D02*
X630823Y158225D01*
X631010Y158350D01*
X631223Y158392D01*
X631490Y158309D01*
X631677Y158100D01*
X631730Y157850D01*
X631703Y157600D01*
X631597Y157392D01*
X631063Y156975D01*
X630823Y156684D01*
X630663Y156267D01*
X630610Y155892D01*
X631730D01*
G01X633370D02*
X633557Y155934D01*
X633770Y156059D01*
X633903Y156267D01*
X633957Y156559D01*
X633903Y156850D01*
X633743Y157100D01*
X633503Y157225D01*
X633237D01*
X633077Y157309D01*
X632943Y157517D01*
X632890Y157809D01*
X632970Y158100D01*
X633157Y158309D01*
X633370Y158392D01*
X633583Y158309D01*
X633770Y158100D01*
X633850Y157809D01*
X633797Y157517D01*
X633663Y157309D01*
X633503Y157225D01*
X633237D01*
X632997Y157100D01*
X632837Y156850D01*
X632783Y156559D01*
X632837Y156267D01*
X632970Y156059D01*
X633183Y155934D01*
X633370Y155892D01*
G01X616644Y160281D02*
Y161781D01*
G01X625644Y158624D02*
X628487D01*
G01D02*
Y155781D01*
G01X629425Y175669D02*
X632625D01*
Y169469D01*
G01Y178819D02*
Y172619D01*
X629425D01*
G01X623996Y169469D02*
Y175669D01*
X627196D01*
G01X623996Y172619D02*
Y178819D01*
G01X627196Y172619D02*
X623996D01*
G01X619952Y182087D02*
Y175887D01*
X616752D01*
G01Y178937D02*
X619952D01*
Y172737D01*
G01X622907Y182422D02*
X619970D01*
G01X622907Y185622D02*
Y182422D01*
G01X616056Y204478D02*
Y201278D01*
G01X619770Y185622D02*
X622907D01*
G01X619936Y213176D02*
X623136D01*
G01X619936Y206976D02*
Y213176D01*
G01X623136Y206976D02*
X619936D01*
G01X623136Y213176D02*
Y206976D01*
G01X616056Y208978D02*
Y205778D01*
G01X630136Y209676D02*
Y206476D01*
G01X623936Y209676D02*
X630136D01*
G01X623936Y206476D02*
Y209676D01*
G01X630136Y206476D02*
X623936D01*
G01X630136Y213676D02*
Y210476D01*
G01X623936Y213676D02*
X630136D01*
G01X623936Y210476D02*
Y213676D01*
G01X630136Y210476D02*
X623936D01*
G01X626120Y232762D02*
Y235962D01*
G01X632320Y232762D02*
X626120D01*
G01Y231962D02*
X632320D01*
G01X626120Y228762D02*
Y231962D01*
G01X632320Y228762D02*
X626120D01*
G01Y235962D02*
X632320D01*
G01X625464Y247602D02*
Y250802D01*
G01X631664Y247602D02*
X625464D01*
G01X618599Y259297D02*
X615490D01*
G01X618599Y250635D02*
Y259297D01*
G01X628664Y251602D02*
X625464D01*
G01X628664Y257802D02*
Y251602D01*
G01X625464Y257802D02*
X628664D01*
G01X625464Y251602D02*
Y257802D01*
G01Y258602D02*
Y261802D01*
G01X631664Y258602D02*
X625464D01*
G01Y261802D02*
X631664D01*
G01X625464Y250802D02*
X631664D01*
G01X622315Y284454D02*
Y282232D01*
X622468Y281767D01*
X622775Y281457D01*
X623158Y281354D01*
X623541Y281457D01*
X623848Y281767D01*
X624001Y282232D01*
Y284454D01*
G01X626258Y281354D02*
Y284454D01*
X625798Y283834D01*
G01Y281354D02*
X626718D01*
G01X629818D02*
Y284454D01*
X628400Y282232D01*
X630316D01*
G01X631615Y281974D02*
X631845Y281612D01*
X632151Y281406D01*
X632496Y281354D01*
X632803Y281406D01*
X633110Y281664D01*
X633301Y281974D01*
X633340Y282284D01*
X633263Y282646D01*
X632995Y282904D01*
X632726Y283007D01*
X632381D01*
G01X632726D02*
X632956Y283162D01*
X633148Y283421D01*
X633225Y283731D01*
X633148Y284041D01*
X632956Y284299D01*
X632611Y284454D01*
X632266Y284402D01*
X631921Y284196D01*
G01X616515Y279730D02*
X619715D01*
G01X616515Y273530D02*
Y279730D01*
G01X619715Y273530D02*
X616515D01*
G01X619715Y279730D02*
Y273530D01*
G01X615695Y279730D02*
Y273530D01*
G01X619280Y313169D02*
Y287185D01*
G01D02*
X614764D01*
G01X617235Y325555D02*
Y319355D01*
G01X629546Y325590D02*
X632746D01*
G01X629546Y319390D02*
Y325590D01*
G01X632746Y319390D02*
X629546D01*
G01X621765Y325575D02*
X624965D01*
G01X621765Y319375D02*
Y325575D01*
G01X624965Y319375D02*
X621765D01*
G01X624965Y325575D02*
Y319375D01*
G01X621096Y319370D02*
X617896D01*
G01X621096Y325570D02*
Y319370D01*
G01X617896Y325570D02*
X621096D01*
G01X617896Y319370D02*
Y325570D01*
G01X628836Y319351D02*
X625636D01*
G01X628836Y325551D02*
Y319351D01*
G01X625636Y325551D02*
X628836D01*
G01X625636Y319351D02*
Y325551D01*
G01X630120Y409762D02*
Y412962D01*
G01X636320Y409762D02*
X630120D01*
G01X629900Y405262D02*
Y408462D01*
G01X636100Y405262D02*
X629900D01*
G01Y408462D02*
X636100D01*
G01X630120Y417962D02*
X636320D01*
G01X630120Y414762D02*
Y417962D01*
G01X636320Y414762D02*
X630120D01*
G01Y412962D02*
X636320D01*
G01X630120Y424762D02*
Y427962D01*
G01X636320Y424762D02*
X630120D01*
G01Y427962D02*
X636320D01*
G01X630120Y419762D02*
Y422962D01*
G01X636320Y419762D02*
X630120D01*
G01Y422962D02*
X636320D01*
G01X622320Y427962D02*
Y424762D01*
G01X616120Y427962D02*
X622320D01*
G01X616120Y424762D02*
Y427962D01*
G01X622320Y424762D02*
X616120D01*
G01X630120Y440262D02*
Y443462D01*
G01X636320Y440262D02*
X630120D01*
G01Y443462D02*
X636320D01*
G01X630120Y429762D02*
Y432962D01*
G01X636320Y429762D02*
X630120D01*
G01Y432962D02*
X636320D01*
G01X615120Y441262D02*
Y444462D01*
G01X621320Y441262D02*
X615120D01*
G01X621320Y444462D02*
Y441262D01*
G01X615120Y444462D02*
X621320D01*
G01X630123Y435050D02*
Y438250D01*
G01X636323Y435050D02*
X630123D01*
G01Y438250D02*
X636323D01*
G01X630120Y461262D02*
Y464462D01*
G01X636320Y461262D02*
X630120D01*
G01Y456262D02*
Y459462D01*
G01X636320Y456262D02*
X630120D01*
G01Y459462D02*
X636320D01*
G01X630120Y451262D02*
Y454462D01*
G01X636320Y451262D02*
X630120D01*
G01Y454462D02*
X636320D01*
G01X630120Y446262D02*
Y449462D01*
G01X636320Y446262D02*
X630120D01*
G01Y449462D02*
X636320D01*
G01X615120Y456262D02*
Y459462D01*
G01X621320Y456262D02*
X615120D01*
G01X621320Y459462D02*
Y456262D01*
G01X615120Y459462D02*
X621320D01*
G01Y464462D02*
Y461262D01*
G01X615120D02*
Y464462D01*
G01X621320Y461262D02*
X615120D01*
G01X630120Y474462D02*
X636320D01*
G01X630120Y471262D02*
Y474462D01*
G01X636320Y471262D02*
X630120D01*
G01Y476262D02*
Y479462D01*
G01X636320Y476262D02*
X630120D01*
G01Y469462D02*
X636320D01*
G01X630120Y466262D02*
Y469462D01*
G01X636320Y466262D02*
X630120D01*
G01Y464462D02*
X636320D01*
G01X621320Y474462D02*
Y471262D01*
G01X615120Y474462D02*
X621320D01*
G01X615120Y471262D02*
Y474462D01*
G01X621320Y471262D02*
X615120D01*
G01X621320Y479462D02*
Y476262D01*
G01X615120D02*
Y479462D01*
G01X621320Y476262D02*
X615120D01*
G01Y464462D02*
X621320D01*
G01Y469462D02*
Y466262D01*
G01X615120Y469462D02*
X621320D01*
G01X615120Y466262D02*
Y469462D01*
G01X621320Y466262D02*
X615120D01*
G01X630120Y479462D02*
X636320D01*
G01X615120D02*
X621320D01*
G01X630100Y484262D02*
X636300D01*
Y481062D01*
X630100D01*
Y484262D01*
G01X630650Y506299D02*
Y488701D01*
X623350D01*
Y506299D01*
X630650D01*
G01X622650D02*
Y488701D01*
X615350D01*
Y506299D01*
X622650D01*
G01X639126Y510050D02*
X627314D01*
G01D02*
Y522674D01*
G01X625126D02*
Y510050D01*
G01X627314Y522674D02*
X639126D01*
G01X616960Y525042D02*
X616653Y525094D01*
X616385Y525300D01*
X616155Y525610D01*
X616002Y525972D01*
X615925Y526385D01*
Y526799D01*
X616002Y527212D01*
X616155Y527574D01*
X616385Y527884D01*
X616653Y528090D01*
X616960Y528142D01*
X617267Y528090D01*
X617535Y527884D01*
X617765Y527574D01*
X617918Y527212D01*
X617995Y526799D01*
Y526385D01*
X617918Y525972D01*
X617765Y525610D01*
X617535Y525300D01*
X617267Y525094D01*
X616960Y525042D01*
G01X617267Y525869D02*
X617727Y525042D01*
G01X619217Y525507D02*
X619447Y525249D01*
X619715Y525094D01*
X620060Y525042D01*
X620405Y525145D01*
X620673Y525352D01*
X620865Y525714D01*
X620903Y526127D01*
X620827Y526540D01*
X620635Y526799D01*
X620367Y527005D01*
X620098Y527057D01*
X619830Y527005D01*
X619485Y526799D01*
X619600Y528142D01*
X620635D01*
G01X622432Y527625D02*
X622662Y527935D01*
X622930Y528090D01*
X623237Y528142D01*
X623620Y528039D01*
X623888Y527780D01*
X623965Y527470D01*
X623927Y527160D01*
X623773Y526902D01*
X623007Y526385D01*
X622662Y526024D01*
X622432Y525507D01*
X622355Y525042D01*
X623965D01*
G01X632030Y530462D02*
X631723Y530514D01*
X631455Y530720D01*
X631225Y531030D01*
X631072Y531392D01*
X630995Y531805D01*
Y532219D01*
X631072Y532632D01*
X631225Y532994D01*
X631455Y533304D01*
X631723Y533510D01*
X632030Y533562D01*
X632337Y533510D01*
X632605Y533304D01*
X632835Y532994D01*
X632988Y532632D01*
X633065Y532219D01*
Y531805D01*
X632988Y531392D01*
X632835Y531030D01*
X632605Y530720D01*
X632337Y530514D01*
X632030Y530462D01*
G01X632337Y531289D02*
X632797Y530462D01*
G01X634287Y530927D02*
X634517Y530669D01*
X634785Y530514D01*
X635130Y530462D01*
X635475Y530565D01*
X635743Y530772D01*
X635935Y531134D01*
X635973Y531547D01*
X635897Y531960D01*
X635705Y532219D01*
X635437Y532425D01*
X635168Y532477D01*
X634900Y532425D01*
X634555Y532219D01*
X634670Y533562D01*
X635705D01*
G01X637387Y531082D02*
X637617Y530720D01*
X637923Y530514D01*
X638268Y530462D01*
X638575Y530514D01*
X638882Y530772D01*
X639073Y531082D01*
X639112Y531392D01*
X639035Y531754D01*
X638767Y532012D01*
X638498Y532115D01*
X638153D01*
G01X638498D02*
X638728Y532270D01*
X638920Y532529D01*
X638997Y532839D01*
X638920Y533149D01*
X638728Y533407D01*
X638383Y533562D01*
X638038Y533510D01*
X637693Y533304D01*
G01X646115Y1335007D02*
X620525D01*
Y697211D01*
X646115D01*
Y1335007D01*
G01Y732644D02*
X620525D01*
G01X646115Y1299574D02*
X620525D01*
G01X619203Y1336996D02*
X619395Y1336686D01*
X619625Y1336479D01*
X619893Y1336376D01*
X620200Y1336479D01*
X620430Y1336686D01*
X620660Y1336996D01*
X620737Y1337409D01*
Y1339476D01*
G01X622342Y1338959D02*
X622572Y1339269D01*
X622840Y1339424D01*
X623147Y1339476D01*
X623530Y1339373D01*
X623798Y1339114D01*
X623875Y1338804D01*
X623837Y1338494D01*
X623683Y1338236D01*
X622917Y1337719D01*
X622572Y1337358D01*
X622342Y1336841D01*
X622265Y1336376D01*
X623875D01*
G01X625442Y1337668D02*
X625710Y1338029D01*
X625940Y1338236D01*
X626247Y1338339D01*
X626515Y1338236D01*
X626707Y1338029D01*
X626860Y1337719D01*
X626898Y1337358D01*
X626860Y1337048D01*
X626707Y1336738D01*
X626477Y1336479D01*
X626208Y1336376D01*
X625902Y1336479D01*
X625633Y1336789D01*
X625480Y1337254D01*
X625442Y1337771D01*
X625518Y1338443D01*
X625633Y1338804D01*
X625825Y1339166D01*
X626093Y1339424D01*
X626362Y1339476D01*
X626630Y1339373D01*
X626822Y1339114D01*
G01X626900Y1364689D02*
X620600D01*
Y1366255D01*
X620915Y1366882D01*
X621335Y1367352D01*
X621965Y1367744D01*
X622700Y1368057D01*
X623750Y1368135D01*
X624800Y1368057D01*
X625535Y1367744D01*
X626165Y1367352D01*
X626585Y1366882D01*
X626900Y1366255D01*
Y1364689D01*
G01X624275Y1371224D02*
X623540Y1371772D01*
X623120Y1372242D01*
X622910Y1372869D01*
X623120Y1373417D01*
X623540Y1373809D01*
X624170Y1374122D01*
X624905Y1374200D01*
X625535Y1374122D01*
X626165Y1373809D01*
X626690Y1373339D01*
X626900Y1372790D01*
X626690Y1372164D01*
X626060Y1371615D01*
X625115Y1371302D01*
X624065Y1371224D01*
X622700Y1371380D01*
X621965Y1371615D01*
X621230Y1372007D01*
X620705Y1372555D01*
X620600Y1373104D01*
X620810Y1373652D01*
X621335Y1374044D01*
G01X632640Y1367039D02*
X632325Y1367352D01*
X631800Y1367587D01*
X631065Y1367744D01*
X630435Y1367587D01*
X630015Y1367274D01*
X629700Y1366725D01*
Y1364610D01*
X636000D01*
Y1367195D01*
X635580Y1367744D01*
X634950Y1368057D01*
X634215Y1368214D01*
X633480Y1368057D01*
X632850Y1367587D01*
X632640Y1367039D01*
Y1364610D01*
G01X633375Y1371224D02*
X632640Y1371772D01*
X632220Y1372242D01*
X632010Y1372869D01*
X632220Y1373417D01*
X632640Y1373809D01*
X633270Y1374122D01*
X634005Y1374200D01*
X634635Y1374122D01*
X635265Y1373809D01*
X635790Y1373339D01*
X636000Y1372790D01*
X635790Y1372164D01*
X635160Y1371615D01*
X634215Y1371302D01*
X633165Y1371224D01*
X631800Y1371380D01*
X631065Y1371615D01*
X630330Y1372007D01*
X629805Y1372555D01*
X629700Y1373104D01*
X629910Y1373652D01*
X630435Y1374044D01*
G01X619000Y1376462D02*
Y1362962D01*
G01X628200D02*
X619000D01*
G01X628200Y1376462D02*
Y1362962D01*
G01X637400D02*
X628200D01*
G01X619000Y1376462D02*
X628200D01*
G01D02*
X637400D01*
G01X623622Y1657834D02*
Y1769645D01*
G01X633260Y1670099D02*
X625760D01*
Y1672339D01*
X626135Y1673086D01*
X627010Y1673646D01*
X628010Y1673833D01*
X629010Y1673646D01*
X629760Y1673179D01*
X630135Y1672339D01*
Y1670099D01*
G01X633260Y1677599D02*
X625760D01*
Y1679933D01*
X626135Y1680679D01*
X626635Y1681146D01*
X627635Y1681333D01*
X628635Y1681146D01*
X629260Y1680586D01*
X629635Y1679933D01*
Y1677599D01*
G01Y1679933D02*
X633260Y1681333D01*
G01Y1688833D02*
Y1685099D01*
X625760D01*
Y1688833D01*
G01X629385Y1687339D02*
Y1685099D01*
G01X632260Y1692506D02*
X632885Y1693253D01*
X633260Y1694093D01*
Y1694839D01*
X632885Y1695586D01*
X632260Y1696146D01*
X631385Y1696426D01*
X630510Y1696239D01*
X629760Y1695773D01*
X629260Y1694933D01*
X629010Y1693813D01*
X628510Y1693159D01*
X627635Y1692879D01*
X626760Y1693066D01*
X626135Y1693533D01*
X625760Y1694186D01*
Y1694839D01*
X626010Y1695493D01*
X626635Y1696053D01*
G01X632260Y1700006D02*
X632885Y1700753D01*
X633260Y1701593D01*
Y1702339D01*
X632885Y1703086D01*
X632260Y1703646D01*
X631385Y1703926D01*
X630510Y1703739D01*
X629760Y1703273D01*
X629260Y1702433D01*
X629010Y1701313D01*
X628510Y1700659D01*
X627635Y1700379D01*
X626760Y1700566D01*
X626135Y1701033D01*
X625760Y1701686D01*
Y1702339D01*
X626010Y1702993D01*
X626635Y1703553D01*
G01X630760Y1708253D02*
Y1710679D01*
G01X633260Y1715193D02*
X625760D01*
Y1718739D01*
G01X629385Y1717433D02*
Y1715193D01*
G01X625760Y1723346D02*
Y1725586D01*
G01Y1724466D02*
X633260D01*
G01Y1723346D02*
Y1725586D01*
G01X625760Y1731966D02*
X633260D01*
G01X625760Y1729819D02*
Y1734113D01*
G01X632900Y84462D02*
X636100D01*
G01X632900Y78262D02*
Y84462D01*
G01X636100Y78262D02*
X632900D01*
G01X636100Y84462D02*
Y78262D01*
G01X636900Y84462D02*
X640100D01*
G01X636900Y78262D02*
Y84462D01*
G01X640100Y78262D02*
X636900D01*
G01X640100Y84462D02*
Y78262D01*
G01X643153Y89635D02*
Y86435D01*
G01D02*
X636953D01*
G01D02*
Y89635D01*
G01X636017Y89639D02*
Y86439D01*
G01X649920Y82662D02*
X646720D01*
G01D02*
Y88862D01*
G01X636953Y89635D02*
X643153D01*
G01X636913Y93685D02*
X643113D01*
G01D02*
Y90485D01*
G01D02*
X636913D01*
G01D02*
Y93685D01*
G01X636017Y93719D02*
Y90519D01*
G01X646720Y88862D02*
X649920D01*
G01X644900Y94962D02*
X651100D01*
Y91762D01*
X644900D01*
Y94962D01*
G01X632513Y138155D02*
X632673Y138405D01*
X632860Y138530D01*
X633073Y138572D01*
X633340Y138489D01*
X633527Y138280D01*
X633580Y138030D01*
X633553Y137780D01*
X633447Y137572D01*
X632913Y137155D01*
X632673Y136864D01*
X632513Y136447D01*
X632460Y136072D01*
X633580D01*
G01X634713Y138155D02*
X634873Y138405D01*
X635060Y138530D01*
X635273Y138572D01*
X635540Y138489D01*
X635727Y138280D01*
X635780Y138030D01*
X635753Y137780D01*
X635647Y137572D01*
X635113Y137155D01*
X634873Y136864D01*
X634713Y136447D01*
X634660Y136072D01*
X635780D01*
G01X643561Y132906D02*
Y136106D01*
G01X649761Y132906D02*
X643561D01*
G01Y136106D02*
X649761D01*
G01X632551Y126492D02*
Y120292D01*
G01X643544Y142299D02*
X649744D01*
G01X643544Y139099D02*
Y142299D01*
G01X649744Y139099D02*
X643544D01*
G01Y143382D02*
Y146582D01*
G01X649744Y143382D02*
X643544D01*
G01Y146582D02*
X649744D01*
G01X643544Y151471D02*
X649744D01*
G01X643544Y148271D02*
Y151471D01*
G01X649744Y148271D02*
X643544D01*
G01Y155945D02*
X649744D01*
G01X643544Y152745D02*
Y155945D01*
G01X649744Y152745D02*
X643544D01*
G01X644620Y160262D02*
Y163462D01*
G01X650820Y160262D02*
X644620D01*
G01Y163462D02*
X650820D01*
G01X644620Y164762D02*
Y167962D01*
G01X650820Y164762D02*
X644620D01*
G01Y167962D02*
X650820D01*
G01X644620Y183262D02*
Y186462D01*
G01X650820Y183262D02*
X644620D01*
G01Y169762D02*
Y172962D01*
G01X650820Y169762D02*
X644620D01*
G01Y172962D02*
X650820D01*
G01X633346Y193816D02*
Y225616D01*
X647146D01*
Y193816D01*
X633346D01*
G01X644620Y186462D02*
X650820D01*
G01X632320Y235962D02*
Y232762D01*
G01X635620Y228762D02*
Y231962D01*
G01X641820Y228762D02*
X635620D01*
G01X641820Y231962D02*
Y228762D01*
G01X635620Y231962D02*
X641820D01*
G01X632320D02*
Y228762D01*
G01X631664Y250802D02*
Y247602D01*
G01X644234Y250802D02*
Y247602D01*
G01X638034D02*
Y250802D01*
G01X644234Y247602D02*
X638034D01*
G01X631664Y261802D02*
Y258602D01*
G01X644234Y261802D02*
Y258602D01*
G01X638034Y261802D02*
X644234D01*
G01X638034Y258602D02*
Y261802D01*
G01X644234Y258602D02*
X638034D01*
G01Y250802D02*
X644234D01*
G01X642245Y295927D02*
Y292727D01*
G01X636045Y295927D02*
X642245D01*
G01X636045Y292727D02*
Y295927D01*
G01X642245Y292727D02*
X636045D01*
G01X642245Y291867D02*
Y288667D01*
G01X636045Y291867D02*
X642245D01*
G01X636045Y288667D02*
Y291867D01*
G01X642245Y288667D02*
X636045D01*
G01Y296697D02*
Y299897D01*
G01X642245Y296697D02*
X636045D01*
G01X642245Y299897D02*
Y296697D01*
G01X636045Y313987D02*
Y317187D01*
G01X642245Y313987D02*
X636045D01*
G01X642245Y317187D02*
Y313987D01*
G01X636045Y309362D02*
Y312562D01*
G01X642245Y309362D02*
X636045D01*
G01X642245Y312562D02*
Y309362D01*
G01X636045Y312562D02*
X642245D01*
G01X636045Y300647D02*
Y303847D01*
G01X642245Y300647D02*
X636045D01*
G01X642245Y303847D02*
Y300647D01*
G01X636045Y303847D02*
X642245D01*
G01X636045Y299897D02*
X642245D01*
G01Y308147D02*
Y304947D01*
G01X636045Y308147D02*
X642245D01*
G01X636045Y304947D02*
Y308147D01*
G01X642245Y304947D02*
X636045D01*
G01X632746Y325590D02*
Y319390D01*
G01X636045Y317187D02*
X642245D01*
G01X631400Y391262D02*
Y394462D01*
G01X637600Y391262D02*
X631400D01*
G01X637600Y394462D02*
Y391262D01*
G01X631400Y394462D02*
X637600D01*
G01X644400Y391262D02*
Y394462D01*
G01X650600Y391262D02*
X644400D01*
G01Y394462D02*
X650600D01*
G01X645120Y409762D02*
Y412962D01*
G01X651320Y409762D02*
X645120D01*
G01X636320Y412962D02*
Y409762D01*
G01X636100Y408462D02*
Y405262D01*
G01X644900D02*
Y408462D01*
G01X651100Y405262D02*
X644900D01*
G01Y408462D02*
X651100D01*
G01X644900Y400762D02*
Y403962D01*
G01X651100Y400762D02*
X644900D01*
G01Y403962D02*
X651100D01*
G01X645120Y414762D02*
Y417962D01*
G01X651320Y414762D02*
X645120D01*
G01Y417962D02*
X651320D01*
G01X645120Y412962D02*
X651320D01*
G01X636320Y417962D02*
Y414762D01*
G01X645120Y422962D02*
X651320D01*
G01X645120Y419762D02*
Y422962D01*
G01X651320Y419762D02*
X645120D01*
G01Y427962D02*
X651320D01*
G01X645120Y424762D02*
Y427962D01*
G01X651320Y424762D02*
X645120D01*
G01X636320Y427962D02*
Y424762D01*
G01Y422962D02*
Y419762D01*
G01X645120Y440262D02*
Y443462D01*
G01X651320Y440262D02*
X645120D01*
G01Y443462D02*
X651320D01*
G01X645120Y429762D02*
Y432962D01*
G01X651320Y429762D02*
X645120D01*
G01Y432962D02*
X651320D01*
G01X636320Y443462D02*
Y440262D01*
G01Y432962D02*
Y429762D01*
G01X636323Y438250D02*
Y435050D01*
G01X645120Y451262D02*
Y454462D01*
G01X651320Y451262D02*
X645120D01*
G01Y454462D02*
X651320D01*
G01X645120Y456262D02*
Y459462D01*
G01X651320Y456262D02*
X645120D01*
G01Y459462D02*
X651320D01*
G01X645120Y461262D02*
Y464462D01*
G01X651320Y461262D02*
X645120D01*
G01Y446262D02*
Y449462D01*
G01X651320Y446262D02*
X645120D01*
G01Y449462D02*
X651320D01*
G01X636320Y464462D02*
Y461262D01*
G01Y459462D02*
Y456262D01*
G01Y454462D02*
Y451262D01*
G01Y449462D02*
Y446262D01*
G01X645120Y476262D02*
Y479462D01*
G01X651320Y476262D02*
X645120D01*
G01Y474462D02*
X651320D01*
G01X645120Y471262D02*
Y474462D01*
G01X651320Y471262D02*
X645120D01*
G01Y466262D02*
Y469462D01*
G01X651320Y466262D02*
X645120D01*
G01Y469462D02*
X651320D01*
G01X645120Y464462D02*
X651320D01*
G01X636320Y474462D02*
Y471262D01*
G01Y479462D02*
Y476262D01*
G01Y469462D02*
Y466262D01*
G01X640188Y489094D02*
Y500906D01*
X652812D01*
Y489094D01*
X640188D01*
G01X645120Y484462D02*
X651320D01*
G01X645120Y481262D02*
Y484462D01*
G01X651320Y481262D02*
X645120D01*
G01Y479462D02*
X651320D01*
G01X638650Y506299D02*
Y488701D01*
X631350D01*
Y506299D01*
X638650D01*
G01X639126Y522674D02*
Y510050D01*
G01X645215Y516984D02*
X648415D01*
G01X645215Y510784D02*
Y516984D01*
G01X648415Y510784D02*
X645215D01*
G01X637820Y527962D02*
Y524762D01*
G01X631620D02*
Y527962D01*
G01X637820Y524762D02*
X631620D01*
G01Y527962D02*
X637820D01*
G01X638855Y648430D02*
Y651530D01*
G01X640465D02*
Y648430D01*
G01Y649980D02*
X638855D01*
G01X642760Y648430D02*
X643028Y648482D01*
X643335Y648637D01*
X643527Y648895D01*
X643603Y649257D01*
X643527Y649618D01*
X643297Y649928D01*
X642952Y650083D01*
X642568D01*
X642338Y650187D01*
X642147Y650445D01*
X642070Y650807D01*
X642185Y651168D01*
X642453Y651427D01*
X642760Y651530D01*
X643067Y651427D01*
X643335Y651168D01*
X643450Y650807D01*
X643373Y650445D01*
X643182Y650187D01*
X642952Y650083D01*
X642568D01*
X642223Y649928D01*
X641993Y649618D01*
X641917Y649257D01*
X641993Y648895D01*
X642185Y648637D01*
X642492Y648482D01*
X642760Y648430D01*
G01X645132Y649722D02*
X645400Y650083D01*
X645630Y650290D01*
X645937Y650393D01*
X646205Y650290D01*
X646397Y650083D01*
X646550Y649773D01*
X646588Y649412D01*
X646550Y649102D01*
X646397Y648792D01*
X646167Y648533D01*
X645898Y648430D01*
X645592Y648533D01*
X645323Y648843D01*
X645170Y649308D01*
X645132Y649825D01*
X645208Y650497D01*
X645323Y650858D01*
X645515Y651220D01*
X645783Y651478D01*
X646052Y651530D01*
X646320Y651427D01*
X646512Y651168D01*
G01X645100Y1364789D02*
X638800D01*
Y1366355D01*
X639115Y1366982D01*
X639535Y1367452D01*
X640165Y1367844D01*
X640900Y1368157D01*
X641950Y1368235D01*
X643000Y1368157D01*
X643735Y1367844D01*
X644365Y1367452D01*
X644785Y1366982D01*
X645100Y1366355D01*
Y1364789D01*
G01Y1372655D02*
X643735Y1372812D01*
X642580Y1373047D01*
X641530Y1373360D01*
X640375Y1373752D01*
X638800Y1374379D01*
Y1371245D01*
G01X637400Y1376462D02*
Y1362962D01*
G01X646600D02*
X637400D01*
G01X646600Y1376462D02*
Y1362962D01*
G01X655800D02*
X646600D01*
G01X637400Y1376462D02*
X646600D01*
G01D02*
X655800D01*
G01X635433Y1781456D02*
Y1646023D01*
G01X646125Y1644594D02*
Y1650794D01*
G01X649325Y1644594D02*
X646125D01*
G01X642125D02*
Y1650794D01*
G01X645325D02*
Y1644594D01*
G01D02*
X642125D01*
G01X646125Y1650794D02*
X649325D01*
G01X642125D02*
X645325D01*
G01X642125Y1654794D02*
X648325D01*
G01Y1651594D02*
X642125D01*
G01D02*
Y1654794D01*
G01X651225Y1668794D02*
X639225D01*
G01D02*
Y1679594D01*
G01D02*
X651225D01*
G01X640625Y1697294D02*
X646825D01*
G01D02*
Y1694094D01*
G01D02*
X640625D01*
G01D02*
Y1697294D01*
G01X646820Y1712762D02*
X640620D01*
G01D02*
Y1715962D01*
G01X646820D02*
Y1712762D01*
G01X643825Y1707294D02*
Y1701094D01*
G01D02*
X640625D01*
G01D02*
Y1707294D01*
G01D02*
X643825D01*
G01X647825Y1701094D02*
X644625D01*
G01D02*
Y1707294D01*
G01D02*
X647825D01*
G01X640620Y1715962D02*
X646820D01*
G01Y1724762D02*
X640620D01*
G01D02*
Y1727962D01*
G01D02*
X646820D01*
G01D02*
Y1724762D01*
G01X640620Y1719962D02*
X646820D01*
G01D02*
Y1716762D01*
G01D02*
X640620D01*
G01D02*
Y1719962D01*
G01Y1723962D02*
X646820D01*
G01D02*
Y1720762D01*
G01D02*
X640620D01*
G01D02*
Y1723962D01*
G01X652220Y82662D02*
Y88862D01*
G01X655420D02*
Y82662D01*
G01D02*
X652220D01*
G01X649920Y88862D02*
Y82662D01*
G01X655197Y102189D02*
Y99967D01*
X655350Y99502D01*
X655657Y99192D01*
X656040Y99089D01*
X656423Y99192D01*
X656730Y99502D01*
X656883Y99967D01*
Y102189D01*
G01X658297Y99709D02*
X658527Y99347D01*
X658833Y99141D01*
X659178Y99089D01*
X659485Y99141D01*
X659792Y99399D01*
X659983Y99709D01*
X660022Y100019D01*
X659945Y100381D01*
X659677Y100639D01*
X659408Y100742D01*
X659063D01*
G01X659408D02*
X659638Y100897D01*
X659830Y101156D01*
X659907Y101466D01*
X659830Y101776D01*
X659638Y102034D01*
X659293Y102189D01*
X658948Y102137D01*
X658603Y101931D01*
G01X662240Y102189D02*
X661933Y102086D01*
X661703Y101827D01*
X661550Y101517D01*
X661435Y101104D01*
X661397Y100639D01*
X661435Y100174D01*
X661550Y99761D01*
X661703Y99451D01*
X661933Y99192D01*
X662240Y99089D01*
X662547Y99192D01*
X662777Y99451D01*
X662930Y99761D01*
X663045Y100174D01*
X663083Y100639D01*
X663045Y101104D01*
X662930Y101517D01*
X662777Y101827D01*
X662547Y102086D01*
X662240Y102189D01*
G01X665263Y99089D02*
X665340Y99761D01*
X665455Y100329D01*
X665608Y100846D01*
X665800Y101414D01*
X666107Y102189D01*
X664573D01*
G01X652220Y88862D02*
X655420D01*
G01X656600Y90262D02*
X653400D01*
G01X656600Y96462D02*
Y90262D01*
G01X653400Y96462D02*
X656600D01*
G01X653400Y90262D02*
Y96462D01*
G01X657400D02*
X660600D01*
G01X657400Y90262D02*
Y96462D01*
G01X660600Y90262D02*
X657400D01*
G01X660600Y96462D02*
Y90262D01*
G01X648933Y116751D02*
X664287D01*
G01X648933Y104073D02*
Y116751D01*
G01X664287Y104073D02*
X648933D01*
G01X650510Y118812D02*
Y122012D01*
G01X656710Y118812D02*
X650510D01*
G01X656710Y122012D02*
Y118812D01*
G01X658103Y127082D02*
Y130182D01*
X659023D01*
X659330Y130027D01*
X659560Y129665D01*
X659637Y129252D01*
X659560Y128839D01*
X659368Y128529D01*
X659023Y128374D01*
X658103D01*
G01X661127Y130182D02*
Y127960D01*
X661280Y127495D01*
X661587Y127185D01*
X661970Y127082D01*
X662353Y127185D01*
X662660Y127495D01*
X662813Y127960D01*
Y130182D01*
G01X664342Y129665D02*
X664572Y129975D01*
X664840Y130130D01*
X665147Y130182D01*
X665530Y130079D01*
X665798Y129820D01*
X665875Y129510D01*
X665837Y129200D01*
X665683Y128942D01*
X664917Y128425D01*
X664572Y128064D01*
X664342Y127547D01*
X664265Y127082D01*
X665875D01*
G01X667518Y127444D02*
X667787Y127185D01*
X668093Y127082D01*
X668400Y127185D01*
X668668Y127495D01*
X668860Y127960D01*
X668937Y128425D01*
Y128994D01*
X668860Y129459D01*
X668668Y129872D01*
X668438Y130079D01*
X668170Y130182D01*
X667863Y130079D01*
X667633Y129872D01*
X667480Y129562D01*
X667403Y129149D01*
X667480Y128787D01*
X667672Y128425D01*
X667902Y128219D01*
X668170Y128167D01*
X668477Y128270D01*
X668707Y128529D01*
X668937Y128994D01*
G01X670618Y127444D02*
X670887Y127185D01*
X671193Y127082D01*
X671500Y127185D01*
X671768Y127495D01*
X671960Y127960D01*
X672037Y128425D01*
Y128994D01*
X671960Y129459D01*
X671768Y129872D01*
X671538Y130079D01*
X671270Y130182D01*
X670963Y130079D01*
X670733Y129872D01*
X670580Y129562D01*
X670503Y129149D01*
X670580Y128787D01*
X670772Y128425D01*
X671002Y128219D01*
X671270Y128167D01*
X671577Y128270D01*
X671807Y128529D01*
X672037Y128994D01*
G01X649761Y136106D02*
Y132906D01*
G01X650510Y122012D02*
X656710D01*
G01X657413Y143752D02*
X657490Y144424D01*
X657605Y144992D01*
X657758Y145509D01*
X657950Y146077D01*
X658257Y146852D01*
X656723D01*
G01X661050Y143752D02*
Y146852D01*
X659632Y144630D01*
X661548D01*
G01X649744Y142299D02*
Y139099D01*
G01Y146582D02*
Y143382D01*
G01Y151471D02*
Y148271D01*
G01X658127Y165157D02*
X658357Y164899D01*
X658625Y164744D01*
X658970Y164692D01*
X659315Y164795D01*
X659583Y165002D01*
X659775Y165364D01*
X659813Y165777D01*
X659737Y166190D01*
X659545Y166449D01*
X659277Y166655D01*
X659008Y166707D01*
X658740Y166655D01*
X658395Y166449D01*
X658510Y167792D01*
X659545D01*
G01X662070Y164692D02*
X662338Y164744D01*
X662645Y164899D01*
X662837Y165157D01*
X662913Y165519D01*
X662837Y165880D01*
X662607Y166190D01*
X662262Y166345D01*
X661878D01*
X661648Y166449D01*
X661457Y166707D01*
X661380Y167069D01*
X661495Y167430D01*
X661763Y167689D01*
X662070Y167792D01*
X662377Y167689D01*
X662645Y167430D01*
X662760Y167069D01*
X662683Y166707D01*
X662492Y166449D01*
X662262Y166345D01*
X661878D01*
X661533Y166190D01*
X661303Y165880D01*
X661227Y165519D01*
X661303Y165157D01*
X661495Y164899D01*
X661802Y164744D01*
X662070Y164692D01*
G01X657602Y156354D02*
X657870Y156715D01*
X658100Y156922D01*
X658407Y157025D01*
X658675Y156922D01*
X658867Y156715D01*
X659020Y156405D01*
X659058Y156044D01*
X659020Y155734D01*
X658867Y155424D01*
X658637Y155165D01*
X658368Y155062D01*
X658062Y155165D01*
X657793Y155475D01*
X657640Y155940D01*
X657602Y156457D01*
X657678Y157129D01*
X657793Y157490D01*
X657985Y157852D01*
X658253Y158110D01*
X658522Y158162D01*
X658790Y158059D01*
X658982Y157800D01*
G01X661430Y155062D02*
X661698Y155114D01*
X662005Y155269D01*
X662197Y155527D01*
X662273Y155889D01*
X662197Y156250D01*
X661967Y156560D01*
X661622Y156715D01*
X661238D01*
X661008Y156819D01*
X660817Y157077D01*
X660740Y157439D01*
X660855Y157800D01*
X661123Y158059D01*
X661430Y158162D01*
X661737Y158059D01*
X662005Y157800D01*
X662120Y157439D01*
X662043Y157077D01*
X661852Y156819D01*
X661622Y156715D01*
X661238D01*
X660893Y156560D01*
X660663Y156250D01*
X660587Y155889D01*
X660663Y155527D01*
X660855Y155269D01*
X661162Y155114D01*
X661430Y155062D01*
G01X649744Y155945D02*
Y152745D01*
G01X650820Y163462D02*
Y160262D01*
G01Y167962D02*
Y164762D01*
G01Y186462D02*
Y183262D01*
G01Y172962D02*
Y169762D01*
G01X649190Y223702D02*
X653790D01*
G01Y218602D02*
X649190D01*
G01X653790Y228802D02*
Y218602D01*
G01X649190Y228802D02*
X653790D01*
G01X649190Y218602D02*
Y228802D01*
G01X654626Y223697D02*
X659226D01*
G01Y218597D02*
X654626D01*
G01X659226Y228797D02*
Y218597D01*
G01X654626Y228797D02*
X659226D01*
G01X654626Y218597D02*
Y228797D01*
G01X661092Y222245D02*
X661322Y222555D01*
X661590Y222710D01*
X661897Y222762D01*
X662280Y222659D01*
X662548Y222400D01*
X662625Y222090D01*
X662587Y221780D01*
X662433Y221522D01*
X661667Y221005D01*
X661322Y220644D01*
X661092Y220127D01*
X661015Y219662D01*
X662625D01*
G01X651627Y233484D02*
X651467Y233609D01*
X651280Y233692D01*
X651067D01*
X650827Y233567D01*
X650640Y233359D01*
X650507Y233109D01*
X650400Y232692D01*
X650373Y232317D01*
X650427Y231942D01*
X650507Y231692D01*
X650667Y231442D01*
X650853Y231275D01*
X651040Y231192D01*
X651227D01*
X651413Y231275D01*
X651573Y231400D01*
X651707Y231567D01*
G01X653240Y231192D02*
X653027Y231234D01*
X652840Y231400D01*
X652680Y231650D01*
X652573Y231942D01*
X652520Y232275D01*
Y232609D01*
X652573Y232942D01*
X652680Y233234D01*
X652840Y233484D01*
X653027Y233650D01*
X653240Y233692D01*
X653453Y233650D01*
X653640Y233484D01*
X653800Y233234D01*
X653907Y232942D01*
X653960Y232609D01*
Y232275D01*
X653907Y231942D01*
X653800Y231650D01*
X653640Y231400D01*
X653453Y231234D01*
X653240Y231192D01*
G01X654827D02*
Y233692D01*
X656053Y231192D01*
Y233692D01*
G01X657027Y231192D02*
Y233692D01*
X658253Y231192D01*
Y233692D01*
G01X660373Y231192D02*
X659307D01*
Y233692D01*
X660373D01*
G01X659947Y232484D02*
X659307D01*
G01X662627Y233484D02*
X662467Y233609D01*
X662280Y233692D01*
X662067D01*
X661827Y233567D01*
X661640Y233359D01*
X661507Y233109D01*
X661400Y232692D01*
X661373Y232317D01*
X661427Y231942D01*
X661507Y231692D01*
X661667Y231442D01*
X661853Y231275D01*
X662040Y231192D01*
X662227D01*
X662413Y231275D01*
X662573Y231400D01*
X662707Y231567D01*
G01X664240Y233692D02*
Y231192D01*
G01X663627Y233692D02*
X664853D01*
G01X666440Y231192D02*
X666227Y231234D01*
X666040Y231400D01*
X665880Y231650D01*
X665773Y231942D01*
X665720Y232275D01*
Y232609D01*
X665773Y232942D01*
X665880Y233234D01*
X666040Y233484D01*
X666227Y233650D01*
X666440Y233692D01*
X666653Y233650D01*
X666840Y233484D01*
X667000Y233234D01*
X667107Y232942D01*
X667160Y232609D01*
Y232275D01*
X667107Y231942D01*
X667000Y231650D01*
X666840Y231400D01*
X666653Y231234D01*
X666440Y231192D01*
G01X668107D02*
Y233692D01*
X668773D01*
X668987Y233567D01*
X669120Y233400D01*
X669173Y233067D01*
X669120Y232734D01*
X668960Y232525D01*
X668773Y232400D01*
X668107D01*
G01X668773D02*
X669173Y231192D01*
G01X672453D02*
Y233692D01*
G01X673467D02*
X672453Y232150D01*
G01X673627Y231192D02*
X672907Y232859D01*
G01X675773Y231192D02*
X674707D01*
Y233692D01*
X675773D01*
G01X675347Y232484D02*
X674707D01*
G01X677973Y231192D02*
X676907D01*
Y233692D01*
X677973D01*
G01X677547Y232484D02*
X676907D01*
G01X679107Y231192D02*
Y233692D01*
X679747D01*
X679960Y233567D01*
X680120Y233275D01*
X680173Y232942D01*
X680120Y232609D01*
X679987Y232359D01*
X679747Y232234D01*
X679107D01*
G01X681840Y231192D02*
X681627Y231234D01*
X681440Y231400D01*
X681280Y231650D01*
X681173Y231942D01*
X681120Y232275D01*
Y232609D01*
X681173Y232942D01*
X681280Y233234D01*
X681440Y233484D01*
X681627Y233650D01*
X681840Y233692D01*
X682053Y233650D01*
X682240Y233484D01*
X682400Y233234D01*
X682507Y232942D01*
X682560Y232609D01*
Y232275D01*
X682507Y231942D01*
X682400Y231650D01*
X682240Y231400D01*
X682053Y231234D01*
X681840Y231192D01*
G01X683453Y233692D02*
Y231900D01*
X683560Y231525D01*
X683773Y231275D01*
X684040Y231192D01*
X684307Y231275D01*
X684520Y231525D01*
X684627Y231900D01*
Y233692D01*
G01X686240D02*
Y231192D01*
G01X685627Y233692D02*
X686853D01*
G01X690133D02*
X691147D01*
X690133Y231192D01*
X691147D01*
G01X692840D02*
X692627Y231234D01*
X692440Y231400D01*
X692280Y231650D01*
X692173Y231942D01*
X692120Y232275D01*
Y232609D01*
X692173Y232942D01*
X692280Y233234D01*
X692440Y233484D01*
X692627Y233650D01*
X692840Y233692D01*
X693053Y233650D01*
X693240Y233484D01*
X693400Y233234D01*
X693507Y232942D01*
X693560Y232609D01*
Y232275D01*
X693507Y231942D01*
X693400Y231650D01*
X693240Y231400D01*
X693053Y231234D01*
X692840Y231192D01*
G01X694427D02*
Y233692D01*
X695653Y231192D01*
Y233692D01*
G01X697773Y231192D02*
X696707D01*
Y233692D01*
X697773D01*
G01X697347Y232484D02*
X696707D01*
G01X651145Y288771D02*
Y291971D01*
G01X657345Y288771D02*
X651145D01*
G01X657345Y291971D02*
Y288771D01*
G01X651145Y291971D02*
X657345D01*
G01X650600Y394462D02*
Y391262D01*
G01X656695Y400954D02*
Y398732D01*
X656848Y398267D01*
X657155Y397957D01*
X657538Y397854D01*
X657921Y397957D01*
X658228Y398267D01*
X658381Y398732D01*
Y400954D01*
G01X659910Y400437D02*
X660140Y400747D01*
X660408Y400902D01*
X660715Y400954D01*
X661098Y400851D01*
X661366Y400592D01*
X661443Y400282D01*
X661405Y399972D01*
X661251Y399714D01*
X660485Y399197D01*
X660140Y398836D01*
X659910Y398319D01*
X659833Y397854D01*
X661443D01*
G01X664198D02*
Y400954D01*
X662780Y398732D01*
X664696D01*
G01X666186Y398216D02*
X666455Y397957D01*
X666761Y397854D01*
X667068Y397957D01*
X667336Y398267D01*
X667528Y398732D01*
X667605Y399197D01*
Y399766D01*
X667528Y400231D01*
X667336Y400644D01*
X667106Y400851D01*
X666838Y400954D01*
X666531Y400851D01*
X666301Y400644D01*
X666148Y400334D01*
X666071Y399921D01*
X666148Y399559D01*
X666340Y399197D01*
X666570Y398991D01*
X666838Y398939D01*
X667145Y399042D01*
X667375Y399301D01*
X667605Y399766D01*
G01X651320Y412962D02*
Y409762D01*
G01X651100Y408462D02*
Y405262D01*
G01Y403962D02*
Y400762D01*
G01X651320Y417962D02*
Y414762D01*
G01Y422962D02*
Y419762D01*
G01Y427962D02*
Y424762D01*
G01Y443462D02*
Y440262D01*
G01Y432962D02*
Y429762D01*
G01Y454462D02*
Y451262D01*
G01Y459462D02*
Y456262D01*
G01Y464462D02*
Y461262D01*
G01Y449462D02*
Y446262D01*
G01Y479462D02*
Y476262D01*
G01Y474462D02*
Y471262D01*
G01Y469462D02*
Y466262D01*
G01X656910Y486117D02*
X659132D01*
X659597Y486270D01*
X659907Y486577D01*
X660010Y486960D01*
X659907Y487343D01*
X659597Y487650D01*
X659132Y487803D01*
X656910D01*
G01X659390Y489217D02*
X659752Y489447D01*
X659958Y489753D01*
X660010Y490098D01*
X659958Y490405D01*
X659700Y490712D01*
X659390Y490903D01*
X659080Y490942D01*
X658718Y490865D01*
X658460Y490597D01*
X658357Y490328D01*
Y489983D01*
G01Y490328D02*
X658202Y490558D01*
X657943Y490750D01*
X657633Y490827D01*
X657323Y490750D01*
X657065Y490558D01*
X656910Y490213D01*
X656962Y489868D01*
X657168Y489523D01*
G01X657427Y492432D02*
X657117Y492662D01*
X656962Y492930D01*
X656910Y493237D01*
X657013Y493620D01*
X657272Y493888D01*
X657582Y493965D01*
X657892Y493927D01*
X658150Y493773D01*
X658667Y493007D01*
X659028Y492662D01*
X659545Y492432D01*
X660010Y492355D01*
Y493965D01*
G01Y496720D02*
X656910D01*
X659132Y495302D01*
Y497218D01*
G01X651320Y484462D02*
Y481262D01*
G01X660290Y498640D02*
X659983Y498692D01*
X659715Y498898D01*
X659485Y499208D01*
X659332Y499570D01*
X659255Y499983D01*
Y500397D01*
X659332Y500810D01*
X659485Y501172D01*
X659715Y501482D01*
X659983Y501688D01*
X660290Y501740D01*
X660597Y501688D01*
X660865Y501482D01*
X661095Y501172D01*
X661248Y500810D01*
X661325Y500397D01*
Y499983D01*
X661248Y499570D01*
X661095Y499208D01*
X660865Y498898D01*
X660597Y498692D01*
X660290Y498640D01*
G01X660597Y499467D02*
X661057Y498640D01*
G01X662547Y499260D02*
X662777Y498898D01*
X663083Y498692D01*
X663428Y498640D01*
X663735Y498692D01*
X664042Y498950D01*
X664233Y499260D01*
X664272Y499570D01*
X664195Y499932D01*
X663927Y500190D01*
X663658Y500293D01*
X663313D01*
G01X663658D02*
X663888Y500448D01*
X664080Y500707D01*
X664157Y501017D01*
X664080Y501327D01*
X663888Y501585D01*
X663543Y501740D01*
X663198Y501688D01*
X662853Y501482D01*
G01X666413Y498640D02*
X666490Y499312D01*
X666605Y499880D01*
X666758Y500397D01*
X666950Y500965D01*
X667257Y501740D01*
X665723D01*
G01X649987Y502770D02*
Y513264D01*
G01X658649Y502770D02*
X649987D01*
G01X658649Y506117D02*
Y502770D01*
G01X656449Y508017D02*
X658649Y506117D01*
G01Y509917D02*
X656449Y508017D01*
G01X658649Y513264D02*
Y509917D01*
G01X663465Y506954D02*
X660265D01*
G01X663465Y513154D02*
Y506954D01*
G01X660265D02*
Y513154D01*
G01X649987Y513264D02*
X658649D01*
G01X656527Y523580D02*
X653327D01*
G01X656527Y529780D02*
Y523580D01*
G01X653327D02*
Y529780D01*
G01X660265Y513154D02*
X663465D01*
G01X649245Y523580D02*
Y529780D01*
G01X652445Y523580D02*
X649245D01*
G01X652445Y529780D02*
Y523580D01*
G01X648415Y516984D02*
Y510784D01*
G01X660639Y516491D02*
X657439D01*
G01X660639Y522691D02*
Y516491D01*
G01X657439Y522691D02*
X660639D01*
G01X657439Y516491D02*
Y522691D01*
G01X653295Y522694D02*
X656495D01*
G01X653295Y516494D02*
Y522694D01*
G01X656495Y516494D02*
X653295D01*
G01X656495Y522694D02*
Y516494D01*
G01X649194Y522707D02*
X652394D01*
G01X649194Y516507D02*
Y522707D01*
G01X652394Y516507D02*
X649194D01*
G01X652394Y522707D02*
Y516507D01*
G01X653327Y529780D02*
X656527D01*
G01X649245D02*
X652445D01*
G01X663890Y1335007D02*
X650225D01*
Y697211D01*
X675815D01*
Y1312340D01*
G01Y732644D02*
X650225D01*
G01X675815Y1299574D02*
X650225D01*
G01X683920Y1324715D02*
G03I-10827J0D01*
G01X662532Y1337715D02*
Y1357400D01*
G01X668496Y1337715D02*
X662532D01*
G01X648903Y1336996D02*
X649095Y1336686D01*
X649325Y1336479D01*
X649593Y1336376D01*
X649900Y1336479D01*
X650130Y1336686D01*
X650360Y1336996D01*
X650437Y1337409D01*
Y1339476D01*
G01X652042Y1338959D02*
X652272Y1339269D01*
X652540Y1339424D01*
X652847Y1339476D01*
X653230Y1339373D01*
X653498Y1339114D01*
X653575Y1338804D01*
X653537Y1338494D01*
X653383Y1338236D01*
X652617Y1337719D01*
X652272Y1337358D01*
X652042Y1336841D01*
X651965Y1336376D01*
X653575D01*
G01X655027Y1336841D02*
X655257Y1336583D01*
X655525Y1336428D01*
X655870Y1336376D01*
X656215Y1336479D01*
X656483Y1336686D01*
X656675Y1337048D01*
X656713Y1337461D01*
X656637Y1337874D01*
X656445Y1338133D01*
X656177Y1338339D01*
X655908Y1338391D01*
X655640Y1338339D01*
X655295Y1338133D01*
X655410Y1339476D01*
X656445D01*
G01X683920Y1324715D02*
X662266D01*
G01X655800Y1353262D02*
Y1376462D01*
G01X650940Y1367239D02*
X650625Y1367552D01*
X650100Y1367787D01*
X649365Y1367944D01*
X648735Y1367787D01*
X648315Y1367474D01*
X648000Y1366925D01*
Y1364810D01*
X654300D01*
Y1367395D01*
X653880Y1367944D01*
X653250Y1368257D01*
X652515Y1368414D01*
X651780Y1368257D01*
X651150Y1367787D01*
X650940Y1367239D01*
Y1364810D01*
G01X654300Y1372755D02*
X652935Y1372912D01*
X651780Y1373147D01*
X650730Y1373460D01*
X649575Y1373852D01*
X648000Y1374479D01*
Y1371345D01*
G01X662532Y1357400D02*
Y1377085D01*
G01D02*
X668446D01*
G01X661587Y1388095D02*
Y1394295D01*
G01X664787Y1388095D02*
X661587D01*
G01X664787Y1398595D02*
X661587D01*
G01Y1404795D02*
X664787D01*
G01X661587Y1398595D02*
Y1404795D01*
G01Y1394295D02*
X664787D01*
G01X654636Y1391170D02*
Y1394370D01*
G01X660836Y1391170D02*
X654636D01*
G01X660836Y1394370D02*
Y1391170D01*
G01X654636Y1394370D02*
X660836D01*
G01X654636Y1394700D02*
Y1397900D01*
G01X660836Y1394700D02*
X654636D01*
G01X660836Y1397900D02*
Y1394700D01*
G01X654636Y1397900D02*
X660836D01*
G01X653325Y1650794D02*
Y1644594D01*
G01D02*
X650125D01*
G01D02*
Y1650794D01*
G01X649325D02*
Y1644594D01*
G01X655825Y1662294D02*
Y1656094D01*
G01D02*
X652625D01*
G01D02*
Y1662294D01*
G01D02*
X655825D01*
G01X650125Y1650794D02*
X653325D01*
G01X648325Y1654794D02*
Y1651594D01*
G01X653523Y1668275D02*
X655745D01*
X656210Y1668428D01*
X656520Y1668735D01*
X656623Y1669118D01*
X656520Y1669501D01*
X656210Y1669808D01*
X655745Y1669961D01*
X653523D01*
G01X656623Y1672218D02*
X653523D01*
X654143Y1671758D01*
G01X656623D02*
Y1672678D01*
G01Y1675241D02*
X655951Y1675318D01*
X655383Y1675433D01*
X654866Y1675586D01*
X654298Y1675778D01*
X653523Y1676085D01*
Y1674551D01*
G01X656158Y1677575D02*
X656416Y1677805D01*
X656571Y1678073D01*
X656623Y1678418D01*
X656520Y1678763D01*
X656313Y1679031D01*
X655951Y1679223D01*
X655538Y1679261D01*
X655125Y1679185D01*
X654866Y1678993D01*
X654660Y1678725D01*
X654608Y1678456D01*
X654660Y1678188D01*
X654866Y1677843D01*
X653523Y1677958D01*
Y1678993D01*
G01X651225Y1679594D02*
Y1676194D01*
G01D02*
X649225Y1674194D01*
G01D02*
X651225Y1672194D01*
G01D02*
Y1668794D01*
G01X651825Y1700294D02*
Y1694094D01*
G01D02*
X648625D01*
G01D02*
Y1700294D01*
G01D02*
X651825D01*
G01X648625Y1701094D02*
Y1707294D01*
G01D02*
X651825D01*
G01D02*
Y1701094D01*
G01D02*
X648625D01*
G01X647825Y1707294D02*
Y1701094D01*
G01X649887Y1733342D02*
Y1731120D01*
X650040Y1730655D01*
X650347Y1730345D01*
X650730Y1730242D01*
X651113Y1730345D01*
X651420Y1730655D01*
X651573Y1731120D01*
Y1733342D01*
G01X653102Y1732825D02*
X653332Y1733135D01*
X653600Y1733290D01*
X653907Y1733342D01*
X654290Y1733239D01*
X654558Y1732980D01*
X654635Y1732670D01*
X654597Y1732360D01*
X654443Y1732102D01*
X653677Y1731585D01*
X653332Y1731224D01*
X653102Y1730707D01*
X653025Y1730242D01*
X654635D01*
G01X656087Y1730707D02*
X656317Y1730449D01*
X656585Y1730294D01*
X656930Y1730242D01*
X657275Y1730345D01*
X657543Y1730552D01*
X657735Y1730914D01*
X657773Y1731327D01*
X657697Y1731740D01*
X657505Y1731999D01*
X657237Y1732205D01*
X656968Y1732257D01*
X656700Y1732205D01*
X656355Y1731999D01*
X656470Y1733342D01*
X657505D01*
G01X659187Y1730862D02*
X659417Y1730500D01*
X659723Y1730294D01*
X660068Y1730242D01*
X660375Y1730294D01*
X660682Y1730552D01*
X660873Y1730862D01*
X660912Y1731172D01*
X660835Y1731534D01*
X660567Y1731792D01*
X660298Y1731895D01*
X659953D01*
G01X660298D02*
X660528Y1732050D01*
X660720Y1732309D01*
X660797Y1732619D01*
X660720Y1732929D01*
X660528Y1733187D01*
X660183Y1733342D01*
X659838Y1733290D01*
X659493Y1733084D01*
G01X660520Y1724693D02*
Y1716031D01*
G01D02*
X649920D01*
G01D02*
Y1724693D01*
G01D02*
X652582D01*
G01D02*
X655220Y1721862D01*
G01D02*
X657858Y1724693D01*
G01D02*
X660520D01*
G01X662120Y1721962D02*
X668320D01*
G01Y1718762D02*
X662120D01*
G01D02*
Y1721962D01*
G01X677350Y101152D02*
Y103652D01*
X677030Y103152D01*
G01Y101152D02*
X677670D01*
G01X679550D02*
Y103652D01*
X679230Y103152D01*
G01Y101152D02*
X679870D01*
G01X664287Y116554D02*
Y104073D01*
G01X666010Y115012D02*
X669210D01*
G01X666010Y108812D02*
Y115012D01*
G01X669210Y108812D02*
X666010D01*
G01X669210Y115012D02*
Y108812D01*
G01X678243Y107285D02*
X675043D01*
G01X678243Y113485D02*
Y107285D01*
G01X675043Y113485D02*
X678243D01*
G01X675043Y107285D02*
Y113485D01*
G01X682223Y107285D02*
X679023D01*
G01Y113485D02*
X682223D01*
G01X679023Y107285D02*
Y113485D01*
G01X685053Y117968D02*
X678853D01*
G01D02*
Y121168D01*
G01Y117468D02*
X685053D01*
G01Y114268D02*
X678853D01*
G01D02*
Y117468D01*
G01Y121168D02*
X685053D01*
G01Y121820D02*
X678853D01*
Y125020D01*
X685053D01*
Y121820D01*
G01X674212Y141929D02*
X665484D01*
G01X679312Y142224D02*
X688225D01*
G01X668437D02*
X673712D01*
G01X668437Y148753D02*
Y142224D01*
G01X688212Y141929D02*
X678812D01*
G01X665484D02*
Y148753D01*
G01Y156758D02*
Y164501D01*
G01X668437D02*
Y156758D01*
G01X678462Y168772D02*
X676212Y170836D01*
G01X678462Y160266D02*
Y168772D01*
G01X670062Y160266D02*
X678462D01*
G01X670062Y157666D02*
Y160266D01*
G01X665962D02*
X670062Y157666D01*
G01X670162Y162666D02*
X665962Y160266D01*
G01X670162Y160166D02*
Y162666D01*
G01X670062Y160266D02*
X670162Y160166D01*
G01X665962Y160266D02*
X670062D01*
G01X665484Y228543D02*
X688225D01*
G01X665484Y221719D02*
Y228543D01*
G01X668437Y228248D02*
Y221719D01*
G01X688225Y228248D02*
X668437D01*
G01X679000Y365162D02*
Y371362D01*
X682200D01*
Y365162D01*
X679000D01*
G01Y368312D02*
Y374512D01*
X682200D01*
Y368312D01*
X679000D01*
G01X668530Y393202D02*
X674730D01*
G01D02*
Y390002D01*
G01D02*
X668530D01*
G01D02*
Y393202D01*
G01X665573Y408958D02*
X740377D01*
G01X665573Y483762D02*
Y408958D01*
G01X740377Y483762D02*
X665573D01*
G01X676820Y509762D02*
X673620D01*
G01X676820Y515962D02*
Y509762D01*
G01X673620D02*
Y515962D01*
G01X671820Y496762D02*
X668620D01*
G01X671820Y502962D02*
Y496762D01*
G01X668620Y502962D02*
X671820D01*
G01X668620Y496762D02*
Y502962D01*
G01X676820Y496762D02*
X673620D01*
G01X676820Y502962D02*
Y496762D01*
G01X673620Y502962D02*
X676820D01*
G01X673620Y496762D02*
Y502962D01*
G01X681820Y496762D02*
X678620D01*
G01Y502962D02*
X681820D01*
G01X678620Y496762D02*
Y502962D01*
G01Y509762D02*
Y515962D01*
G01X681820Y509762D02*
X678620D01*
G01X673620Y523262D02*
Y529462D01*
G01X676820Y523262D02*
X673620D01*
G01X676820Y529462D02*
Y523262D01*
G01X673620Y515962D02*
X676820D01*
G01X678620Y523262D02*
Y529462D01*
G01X681820Y523262D02*
X678620D01*
G01Y515962D02*
X681820D01*
G01X673620Y529462D02*
X676820D01*
G01X678620D02*
X681820D01*
G01X667418Y1380135D02*
Y1382735D01*
G01X668211Y1380135D02*
X667418D01*
G01X664787Y1394295D02*
Y1388095D01*
G01X667418Y1403757D02*
X668426D01*
G01X667418Y1401903D02*
Y1403757D01*
G01Y1389346D02*
Y1391044D01*
G01X664787Y1404795D02*
Y1398595D01*
G01X668803Y1415265D02*
Y1418365D01*
X669723D01*
X670030Y1418210D01*
X670260Y1417848D01*
X670337Y1417435D01*
X670260Y1417022D01*
X670068Y1416712D01*
X669723Y1416557D01*
X668803D01*
G01X671827Y1418365D02*
Y1416143D01*
X671980Y1415678D01*
X672287Y1415368D01*
X672670Y1415265D01*
X673053Y1415368D01*
X673360Y1415678D01*
X673513Y1416143D01*
Y1418365D01*
G01X675693Y1415265D02*
X675770Y1415937D01*
X675885Y1416505D01*
X676038Y1417022D01*
X676230Y1417590D01*
X676537Y1418365D01*
X675003D01*
G01X678027Y1415730D02*
X678257Y1415472D01*
X678525Y1415317D01*
X678870Y1415265D01*
X679215Y1415368D01*
X679483Y1415575D01*
X679675Y1415937D01*
X679713Y1416350D01*
X679637Y1416763D01*
X679445Y1417022D01*
X679177Y1417228D01*
X678908Y1417280D01*
X678640Y1417228D01*
X678295Y1417022D01*
X678410Y1418365D01*
X679445D01*
G01X680820Y1414232D02*
X683120D01*
G01X684303Y1415265D02*
Y1418365D01*
X685223D01*
X685530Y1418210D01*
X685760Y1417848D01*
X685837Y1417435D01*
X685760Y1417022D01*
X685568Y1416712D01*
X685223Y1416557D01*
X684303D01*
G01X688170Y1415265D02*
Y1418365D01*
X687710Y1417745D01*
G01Y1415265D02*
X688630D01*
G01X690120Y1414232D02*
X692420D01*
G01X694370Y1415265D02*
Y1418365D01*
X693910Y1417745D01*
G01Y1415265D02*
X694830D01*
G01X676626Y1421260D02*
Y1424668D01*
G01X694342Y1421260D02*
X676626D01*
G01X664825Y1413084D02*
X668025D01*
G01X664825Y1406884D02*
Y1413084D01*
G01X668025Y1406884D02*
X664825D01*
G01X668025Y1413084D02*
Y1406884D01*
G01X681850Y1406970D02*
X678650D01*
G01Y1413170D02*
X681850D01*
G01X678650Y1406970D02*
Y1413170D01*
G01X669077Y1410598D02*
Y1413798D01*
G01X675277Y1410598D02*
X669077D01*
G01X675277Y1413798D02*
Y1410598D01*
G01X669077Y1413798D02*
X675277D01*
G01X676626Y1435568D02*
Y1438976D01*
G01D02*
X694342D01*
G01X675313Y1549692D02*
X675003Y1549922D01*
X674848Y1550190D01*
X674796Y1550497D01*
X674899Y1550880D01*
X675158Y1551148D01*
X675468Y1551225D01*
X675778Y1551187D01*
X676036Y1551033D01*
X676553Y1550267D01*
X676914Y1549922D01*
X677431Y1549692D01*
X677896Y1549615D01*
Y1551225D01*
G01X676863Y1556122D02*
Y1557118D01*
G01X677276Y1561977D02*
X677638Y1562207D01*
X677844Y1562513D01*
X677896Y1562858D01*
X677844Y1563165D01*
X677586Y1563472D01*
X677276Y1563663D01*
X676966Y1563702D01*
X676604Y1563625D01*
X676346Y1563357D01*
X676243Y1563088D01*
Y1562743D01*
G01Y1563088D02*
X676088Y1563318D01*
X675829Y1563510D01*
X675519Y1563587D01*
X675209Y1563510D01*
X674951Y1563318D01*
X674796Y1562973D01*
X674848Y1562628D01*
X675054Y1562283D01*
G01X674796Y1569710D02*
X677896D01*
G01X677431D02*
X677689Y1569557D01*
X677844Y1569327D01*
X677896Y1569058D01*
X677793Y1568752D01*
X677534Y1568522D01*
X677224Y1568368D01*
X676863Y1568330D01*
X676501Y1568368D01*
X676191Y1568522D01*
X675933Y1568752D01*
X675829Y1569058D01*
X675881Y1569327D01*
X675984Y1569518D01*
X676191Y1569710D01*
G01X675829Y1572120D02*
X677896D01*
G01X675003D02*
X674951Y1572043D01*
X674848D01*
X674796Y1572120D01*
X674848Y1572197D01*
X674951D01*
X675003Y1572120D01*
G01X677534Y1574645D02*
X677741Y1574837D01*
X677896Y1575105D01*
Y1575335D01*
X677793Y1575565D01*
X677638Y1575718D01*
X677431Y1575795D01*
X677121Y1575757D01*
X676966Y1575603D01*
X676656Y1574913D01*
X676294Y1574760D01*
X676036Y1574837D01*
X675881Y1574990D01*
X675829Y1575220D01*
X675881Y1575450D01*
X676036Y1575680D01*
G01X677896Y1579010D02*
X675829D01*
G01X676191D02*
X675984Y1578857D01*
X675881Y1578627D01*
X675829Y1578358D01*
X675933Y1578090D01*
X676139Y1577860D01*
X676449Y1577707D01*
X676863Y1577630D01*
X677276Y1577707D01*
X677586Y1577860D01*
X677793Y1578090D01*
X677896Y1578358D01*
X677844Y1578627D01*
X677689Y1578857D01*
X677483Y1579010D01*
G01X677896Y1580730D02*
X674796D01*
G01X676346D02*
X676036Y1580922D01*
X675881Y1581152D01*
X675829Y1581382D01*
X675933Y1581727D01*
X676139Y1581957D01*
X676501Y1582110D01*
X676914D01*
X677328Y1582033D01*
X677638Y1581880D01*
X677844Y1581612D01*
X677896Y1581382D01*
X677844Y1581152D01*
X677689Y1580922D01*
X677431Y1580730D01*
G01X677896Y1584520D02*
X674796D01*
G01X676501Y1587045D02*
Y1588272D01*
X676139Y1588157D01*
X675933Y1587965D01*
X675829Y1587697D01*
X675881Y1587428D01*
X676036Y1587198D01*
X676398Y1587045D01*
X676708Y1586968D01*
X677018D01*
X677328Y1587045D01*
X677638Y1587237D01*
X677844Y1587467D01*
X677896Y1587735D01*
X677793Y1588003D01*
X677483Y1588272D01*
G01X673996Y1550420D02*
X670896D01*
X671516Y1549960D01*
G01X673996D02*
Y1550880D01*
G01X672963Y1556122D02*
Y1557118D01*
G01X671413Y1562092D02*
X671103Y1562322D01*
X670948Y1562590D01*
X670896Y1562897D01*
X670999Y1563280D01*
X671258Y1563548D01*
X671568Y1563625D01*
X671878Y1563587D01*
X672136Y1563433D01*
X672653Y1562667D01*
X673014Y1562322D01*
X673531Y1562092D01*
X673996Y1562015D01*
Y1563625D01*
G01Y1569787D02*
Y1568253D01*
X670896D01*
Y1569787D01*
G01X672394Y1569173D02*
Y1568253D01*
G01X673996Y1571468D02*
X671929D01*
G01X672446D02*
X672188Y1571622D01*
X671981Y1571852D01*
X671929Y1572158D01*
X671981Y1572427D01*
X672188Y1572657D01*
X672549Y1572772D01*
X673996D01*
G01Y1575910D02*
X671929D01*
G01X672291D02*
X672084Y1575757D01*
X671981Y1575527D01*
X671929Y1575258D01*
X672033Y1574990D01*
X672239Y1574760D01*
X672549Y1574607D01*
X672963Y1574530D01*
X673376Y1574607D01*
X673686Y1574760D01*
X673893Y1574990D01*
X673996Y1575258D01*
X673944Y1575527D01*
X673789Y1575757D01*
X673583Y1575910D01*
G01X673996Y1577630D02*
X670896D01*
G01X672446D02*
X672136Y1577822D01*
X671981Y1578052D01*
X671929Y1578282D01*
X672033Y1578627D01*
X672239Y1578857D01*
X672601Y1579010D01*
X673014D01*
X673428Y1578933D01*
X673738Y1578780D01*
X673944Y1578512D01*
X673996Y1578282D01*
X673944Y1578052D01*
X673789Y1577822D01*
X673531Y1577630D01*
G01X673996Y1581420D02*
X670896D01*
G01X672601Y1583945D02*
Y1585172D01*
X672239Y1585057D01*
X672033Y1584865D01*
X671929Y1584597D01*
X671981Y1584328D01*
X672136Y1584098D01*
X672498Y1583945D01*
X672808Y1583868D01*
X673118D01*
X673428Y1583945D01*
X673738Y1584137D01*
X673944Y1584367D01*
X673996Y1584635D01*
X673893Y1584903D01*
X673583Y1585172D01*
G01X675029Y1587428D02*
X674513Y1587045D01*
X673996Y1586853D01*
X671929D01*
X671413Y1587045D01*
X670896Y1587428D01*
G01X673996Y1589877D02*
X670896D01*
Y1590643D01*
X671051Y1590950D01*
X671258Y1591180D01*
X671568Y1591372D01*
X671929Y1591525D01*
X672446Y1591563D01*
X672963Y1591525D01*
X673324Y1591372D01*
X673634Y1591180D01*
X673841Y1590950D01*
X673996Y1590643D01*
Y1589877D01*
G01Y1594587D02*
Y1593053D01*
X670896D01*
Y1594587D01*
G01X672394Y1593973D02*
Y1593053D01*
G01X673996Y1596192D02*
X670896D01*
Y1597648D01*
G01X672394Y1597112D02*
Y1596192D01*
G01X673996Y1599062D02*
X670896Y1600020D01*
X673996Y1600978D01*
G01X672911Y1600633D02*
Y1599407D01*
G01X670896Y1602277D02*
X673118D01*
X673583Y1602430D01*
X673893Y1602737D01*
X673996Y1603120D01*
X673893Y1603503D01*
X673583Y1603810D01*
X673118Y1603963D01*
X670896D01*
G01Y1605453D02*
X673996D01*
Y1606987D01*
G01X670896Y1609320D02*
X673996D01*
G01X670896Y1608438D02*
Y1610202D01*
G01X675029Y1612612D02*
X674513Y1612995D01*
X673996Y1613187D01*
X671929D01*
X671413Y1612995D01*
X670896Y1612612D01*
G01X669109Y1550275D02*
X666009D01*
G01Y1551885D02*
X669109D01*
G01X667559D02*
Y1550275D01*
G01X668696Y1553375D02*
X668954Y1553682D01*
X669109Y1554027D01*
Y1554333D01*
X668954Y1554640D01*
X668696Y1554870D01*
X668334Y1554985D01*
X667972Y1554908D01*
X667662Y1554717D01*
X667456Y1554372D01*
X667352Y1553912D01*
X667146Y1553643D01*
X666784Y1553528D01*
X666422Y1553605D01*
X666164Y1553797D01*
X666009Y1554065D01*
Y1554333D01*
X666112Y1554602D01*
X666371Y1554832D01*
G01X666267Y1558123D02*
X666112Y1557893D01*
X666009Y1557625D01*
Y1557318D01*
X666164Y1556973D01*
X666422Y1556705D01*
X666732Y1556513D01*
X667249Y1556360D01*
X667714Y1556322D01*
X668179Y1556398D01*
X668489Y1556513D01*
X668799Y1556743D01*
X669006Y1557012D01*
X669109Y1557280D01*
Y1557548D01*
X669006Y1557817D01*
X668851Y1558047D01*
X668644Y1558238D01*
G01X666009Y1564170D02*
X669109D01*
G01X668644D02*
X668902Y1564017D01*
X669057Y1563787D01*
X669109Y1563518D01*
X669006Y1563212D01*
X668747Y1562982D01*
X668437Y1562828D01*
X668076Y1562790D01*
X667714Y1562828D01*
X667404Y1562982D01*
X667146Y1563212D01*
X667042Y1563518D01*
X667094Y1563787D01*
X667197Y1563978D01*
X667404Y1564170D01*
G01X667042Y1566580D02*
X669109D01*
G01X666216D02*
X666164Y1566503D01*
X666061D01*
X666009Y1566580D01*
X666061Y1566657D01*
X666164D01*
X666216Y1566580D01*
G01X668747Y1569105D02*
X668954Y1569297D01*
X669109Y1569565D01*
Y1569795D01*
X669006Y1570025D01*
X668851Y1570178D01*
X668644Y1570255D01*
X668334Y1570217D01*
X668179Y1570063D01*
X667869Y1569373D01*
X667507Y1569220D01*
X667249Y1569297D01*
X667094Y1569450D01*
X667042Y1569680D01*
X667094Y1569910D01*
X667249Y1570140D01*
G01X669109Y1573470D02*
X667042D01*
G01X667404D02*
X667197Y1573317D01*
X667094Y1573087D01*
X667042Y1572818D01*
X667146Y1572550D01*
X667352Y1572320D01*
X667662Y1572167D01*
X668076Y1572090D01*
X668489Y1572167D01*
X668799Y1572320D01*
X669006Y1572550D01*
X669109Y1572818D01*
X669057Y1573087D01*
X668902Y1573317D01*
X668696Y1573470D01*
G01X669109Y1575190D02*
X666009D01*
G01X667559D02*
X667249Y1575382D01*
X667094Y1575612D01*
X667042Y1575842D01*
X667146Y1576187D01*
X667352Y1576417D01*
X667714Y1576570D01*
X668127D01*
X668541Y1576493D01*
X668851Y1576340D01*
X669057Y1576072D01*
X669109Y1575842D01*
X669057Y1575612D01*
X668902Y1575382D01*
X668644Y1575190D01*
G01X669109Y1578980D02*
X666009D01*
G01X667714Y1581505D02*
Y1582732D01*
X667352Y1582617D01*
X667146Y1582425D01*
X667042Y1582157D01*
X667094Y1581888D01*
X667249Y1581658D01*
X667611Y1581505D01*
X667921Y1581428D01*
X668231D01*
X668541Y1581505D01*
X668851Y1581697D01*
X669057Y1581927D01*
X669109Y1582195D01*
X669006Y1582463D01*
X668696Y1582732D01*
G01X674478Y1643358D02*
X674171Y1643410D01*
X673903Y1643616D01*
X673673Y1643926D01*
X673520Y1644288D01*
X673443Y1644701D01*
Y1645115D01*
X673520Y1645528D01*
X673673Y1645890D01*
X673903Y1646200D01*
X674171Y1646406D01*
X674478Y1646458D01*
X674785Y1646406D01*
X675053Y1646200D01*
X675283Y1645890D01*
X675436Y1645528D01*
X675513Y1645115D01*
Y1644701D01*
X675436Y1644288D01*
X675283Y1643926D01*
X675053Y1643616D01*
X674785Y1643410D01*
X674478Y1643358D01*
G01X674785Y1644185D02*
X675245Y1643358D01*
G01X677578D02*
Y1646458D01*
X677118Y1645838D01*
G01Y1643358D02*
X678038D01*
G01X680678Y1646458D02*
X680371Y1646355D01*
X680141Y1646096D01*
X679988Y1645786D01*
X679873Y1645373D01*
X679835Y1644908D01*
X679873Y1644443D01*
X679988Y1644030D01*
X680141Y1643720D01*
X680371Y1643461D01*
X680678Y1643358D01*
X680985Y1643461D01*
X681215Y1643720D01*
X681368Y1644030D01*
X681483Y1644443D01*
X681521Y1644908D01*
X681483Y1645373D01*
X681368Y1645786D01*
X681215Y1646096D01*
X680985Y1646355D01*
X680678Y1646458D01*
G01X682935Y1643978D02*
X683165Y1643616D01*
X683471Y1643410D01*
X683816Y1643358D01*
X684123Y1643410D01*
X684430Y1643668D01*
X684621Y1643978D01*
X684660Y1644288D01*
X684583Y1644650D01*
X684315Y1644908D01*
X684046Y1645011D01*
X683701D01*
G01X684046D02*
X684276Y1645166D01*
X684468Y1645425D01*
X684545Y1645735D01*
X684468Y1646045D01*
X684276Y1646303D01*
X683931Y1646458D01*
X683586Y1646406D01*
X683241Y1646200D01*
G01X682599Y1633072D02*
X679252D01*
G01D02*
X677352Y1635272D01*
G01D02*
X675452Y1633072D01*
G01D02*
X672105D01*
G01D02*
Y1641734D01*
G01D02*
X682599D01*
G01X670118Y1645957D02*
X663918D01*
G01D02*
Y1649157D01*
G01X670118D02*
Y1645957D01*
G01X663972Y1644267D02*
X670172D01*
G01D02*
Y1641067D01*
G01D02*
X663972D01*
G01D02*
Y1644267D01*
G01X678018Y1660318D02*
X677711Y1660370D01*
X677443Y1660576D01*
X677213Y1660886D01*
X677060Y1661248D01*
X676983Y1661661D01*
Y1662075D01*
X677060Y1662488D01*
X677213Y1662850D01*
X677443Y1663160D01*
X677711Y1663366D01*
X678018Y1663418D01*
X678325Y1663366D01*
X678593Y1663160D01*
X678823Y1662850D01*
X678976Y1662488D01*
X679053Y1662075D01*
Y1661661D01*
X678976Y1661248D01*
X678823Y1660886D01*
X678593Y1660576D01*
X678325Y1660370D01*
X678018Y1660318D01*
G01X678325Y1661145D02*
X678785Y1660318D01*
G01X681118D02*
Y1663418D01*
X680658Y1662798D01*
G01Y1660318D02*
X681578D01*
G01X684218Y1663418D02*
X683911Y1663315D01*
X683681Y1663056D01*
X683528Y1662746D01*
X683413Y1662333D01*
X683375Y1661868D01*
X683413Y1661403D01*
X683528Y1660990D01*
X683681Y1660680D01*
X683911Y1660421D01*
X684218Y1660318D01*
X684525Y1660421D01*
X684755Y1660680D01*
X684908Y1660990D01*
X685023Y1661403D01*
X685061Y1661868D01*
X685023Y1662333D01*
X684908Y1662746D01*
X684755Y1663056D01*
X684525Y1663315D01*
X684218Y1663418D01*
G01X686590Y1662901D02*
X686820Y1663211D01*
X687088Y1663366D01*
X687395Y1663418D01*
X687778Y1663315D01*
X688046Y1663056D01*
X688123Y1662746D01*
X688085Y1662436D01*
X687931Y1662178D01*
X687165Y1661661D01*
X686820Y1661300D01*
X686590Y1660783D01*
X686513Y1660318D01*
X688123D01*
G01X677641Y1659152D02*
X680988D01*
G01X688135Y1650490D02*
X677641D01*
G01D02*
Y1659152D01*
G01X663918Y1649157D02*
X670118D01*
G01X670193Y1657957D02*
X663993D01*
G01D02*
Y1661157D01*
G01D02*
X670193D01*
G01D02*
Y1657957D01*
G01X663993Y1657157D02*
X670193D01*
G01D02*
Y1653957D01*
G01D02*
X663993D01*
G01D02*
Y1657157D01*
G01X663918Y1653157D02*
X670118D01*
G01D02*
Y1649957D01*
G01D02*
X663918D01*
G01D02*
Y1653157D01*
G01X670220Y1663262D02*
X664020D01*
G01D02*
Y1666462D01*
G01X670220D02*
Y1663262D01*
G01X673357Y1683852D02*
Y1681630D01*
X673510Y1681165D01*
X673817Y1680855D01*
X674200Y1680752D01*
X674583Y1680855D01*
X674890Y1681165D01*
X675043Y1681630D01*
Y1683852D01*
G01X677300Y1680752D02*
Y1683852D01*
X676840Y1683232D01*
G01Y1680752D02*
X677760D01*
G01X679748Y1681114D02*
X680017Y1680855D01*
X680323Y1680752D01*
X680630Y1680855D01*
X680898Y1681165D01*
X681090Y1681630D01*
X681167Y1682095D01*
Y1682664D01*
X681090Y1683129D01*
X680898Y1683542D01*
X680668Y1683749D01*
X680400Y1683852D01*
X680093Y1683749D01*
X679863Y1683542D01*
X679710Y1683232D01*
X679633Y1682819D01*
X679710Y1682457D01*
X679902Y1682095D01*
X680132Y1681889D01*
X680400Y1681837D01*
X680707Y1681940D01*
X680937Y1682199D01*
X681167Y1682664D01*
G01X682657Y1681217D02*
X682887Y1680959D01*
X683155Y1680804D01*
X683500Y1680752D01*
X683845Y1680855D01*
X684113Y1681062D01*
X684305Y1681424D01*
X684343Y1681837D01*
X684267Y1682250D01*
X684075Y1682509D01*
X683807Y1682715D01*
X683538Y1682767D01*
X683270Y1682715D01*
X682925Y1682509D01*
X683040Y1683852D01*
X684075D01*
G01X683920Y1666531D02*
X673320D01*
G01D02*
Y1675193D01*
G01D02*
X675982D01*
G01D02*
X678620Y1672362D01*
G01D02*
X681258Y1675193D01*
G01X664020Y1666462D02*
X670220D01*
G01Y1675262D02*
X664020D01*
G01D02*
Y1678462D01*
G01D02*
X670220D01*
G01D02*
Y1675262D01*
G01X664020Y1674462D02*
X670220D01*
G01Y1671262D02*
X664020D01*
G01D02*
Y1674462D01*
G01X670220D02*
Y1671262D01*
G01Y1667262D02*
X664020D01*
G01D02*
Y1670462D01*
G01D02*
X670220D01*
G01D02*
Y1667262D01*
G01X667120Y1709962D02*
X673320D01*
G01D02*
Y1706762D01*
G01D02*
X667120D01*
G01D02*
Y1709962D01*
G01X673320Y1710762D02*
X667120D01*
G01D02*
Y1713962D01*
G01D02*
X673320D01*
G01D02*
Y1710762D01*
G01X668320Y1721962D02*
Y1718762D01*
G01X673320Y1726762D02*
X667120D01*
G01D02*
Y1729962D01*
G01D02*
X673320D01*
G01D02*
Y1726762D01*
G01X667120Y1725962D02*
X673320D01*
G01D02*
Y1722762D01*
G01D02*
X667120D01*
G01D02*
Y1725962D01*
G01Y1717962D02*
X673320D01*
G01D02*
Y1714762D01*
G01D02*
X667120D01*
G01D02*
Y1717962D01*
G01Y1733962D02*
X673320D01*
G01D02*
Y1730762D01*
G01D02*
X667120D01*
G01D02*
Y1733962D01*
G01X695220Y80362D02*
X683220D01*
G01X695220Y86362D02*
Y80362D01*
G01X683220Y86362D02*
X695220D01*
G01X683220Y80362D02*
Y86362D01*
G01X695320Y78562D02*
Y75362D01*
G01X689120Y78562D02*
X695320D01*
G01X689120Y75362D02*
Y78562D01*
G01X695320Y75362D02*
X689120D01*
G01X682443Y94558D02*
Y99158D01*
G01X692643Y94558D02*
X682443D01*
G01X692643Y99158D02*
Y94558D01*
G01X682443Y99158D02*
X692643D01*
G01X687543Y99458D02*
Y104058D01*
G01X692643D02*
Y99458D01*
G01X682443D02*
Y104058D01*
G01X692643Y99458D02*
X682443D01*
G01X695080Y98182D02*
Y100682D01*
X694760Y100182D01*
G01Y98182D02*
X695400D01*
G01X696773Y100265D02*
X696933Y100515D01*
X697120Y100640D01*
X697333Y100682D01*
X697600Y100599D01*
X697787Y100390D01*
X697840Y100140D01*
X697813Y99890D01*
X697707Y99682D01*
X697173Y99265D01*
X696933Y98974D01*
X696773Y98557D01*
X696720Y98182D01*
X697840D01*
G01X695553Y93268D02*
Y90068D01*
G01X689353Y93268D02*
X695553D01*
G01X689353Y90068D02*
Y93268D01*
G01X695553Y90068D02*
X689353D01*
G01X682443Y104058D02*
X692643D01*
G01X689544Y120030D02*
Y116896D01*
G01Y114896D02*
Y112960D01*
G01Y107826D02*
X690709D01*
G01X689544Y110960D02*
Y107826D01*
G01X683043Y113485D02*
X686243D01*
G01X683043Y107285D02*
Y113485D01*
G01X686243Y107285D02*
X683043D01*
G01X686243Y113485D02*
Y107285D01*
G01X682223Y113485D02*
Y107285D01*
G01X685053Y121168D02*
Y117968D01*
G01Y117468D02*
Y114268D01*
G01X687210Y121022D02*
Y123522D01*
X686890Y123022D01*
G01Y121022D02*
X687530D01*
G01X689410Y123522D02*
X689197Y123439D01*
X689037Y123230D01*
X688930Y122980D01*
X688850Y122647D01*
X688823Y122272D01*
X688850Y121897D01*
X688930Y121564D01*
X689037Y121314D01*
X689197Y121105D01*
X689410Y121022D01*
X689623Y121105D01*
X689783Y121314D01*
X689890Y121564D01*
X689970Y121897D01*
X689997Y122272D01*
X689970Y122647D01*
X689890Y122980D01*
X689783Y123230D01*
X689623Y123439D01*
X689410Y123522D01*
G01X694733Y124520D02*
X694547Y124729D01*
X694333Y124812D01*
X694120Y124729D01*
X693933Y124479D01*
X693800Y124104D01*
X693747Y123729D01*
Y123270D01*
X693800Y122895D01*
X693933Y122562D01*
X694093Y122395D01*
X694280Y122312D01*
X694493Y122395D01*
X694653Y122562D01*
X694760Y122812D01*
X694813Y123145D01*
X694760Y123437D01*
X694627Y123729D01*
X694467Y123895D01*
X694280Y123937D01*
X694067Y123854D01*
X693907Y123645D01*
X693747Y123270D01*
G01X690709Y120030D02*
X689544D01*
G01X696053Y126568D02*
X692853D01*
G01X696053Y132768D02*
Y126568D01*
G01X692853Y132768D02*
X696053D01*
G01X692853Y126568D02*
Y132768D01*
G01X685853Y126568D02*
Y132768D01*
G01D02*
X689053D01*
G01D02*
Y126568D01*
G01D02*
X685853D01*
G01X681853D02*
Y132768D01*
G01D02*
X685053D01*
G01D02*
Y126568D01*
G01D02*
X681853D01*
G01X694000Y365162D02*
Y371362D01*
X697200D01*
Y365162D01*
X694000D01*
G01Y368312D02*
Y374512D01*
X697200D01*
Y368312D01*
X694000D01*
G01X689000Y365162D02*
Y371362D01*
X692200D01*
Y365162D01*
X689000D01*
G01Y368312D02*
Y374512D01*
X692200D01*
Y368312D01*
X689000D01*
G01X684000Y365162D02*
Y371362D01*
X687200D01*
Y365162D01*
X684000D01*
G01Y368312D02*
Y374512D01*
X687200D01*
Y368312D01*
X684000D01*
G01X689890Y380822D02*
X686690D01*
G01X689890Y387022D02*
Y380822D01*
G01X686690Y387022D02*
X689890D01*
G01X686690Y380822D02*
Y387022D01*
G01X686870Y396262D02*
X690070D01*
G01X686870Y390062D02*
Y396262D01*
G01X690070Y390062D02*
X686870D01*
G01X690070Y396262D02*
Y390062D01*
G01X691820Y509762D02*
X688620D01*
G01X691820Y515962D02*
Y509762D01*
G01X688620D02*
Y515962D01*
G01X681820Y502962D02*
Y496762D01*
G01X683620Y502962D02*
X686820D01*
G01X683620Y496762D02*
Y502962D01*
G01X686820Y496762D02*
X683620D01*
G01X686820Y502962D02*
Y496762D01*
G01Y509762D02*
X683620D01*
G01X686820Y515962D02*
Y509762D01*
G01X683620D02*
Y515962D01*
G01X681820D02*
Y509762D01*
G01X693620D02*
Y515962D01*
G01X696820Y509762D02*
X693620D01*
G01X688620Y515962D02*
X691820D01*
G01X693620Y523262D02*
Y529462D01*
G01X696820Y523262D02*
X693620D01*
G01X681820Y529462D02*
Y523262D01*
G01X683620Y515962D02*
X686820D01*
G01X693620D02*
X696820D01*
G01X693620Y529462D02*
X696820D01*
G01X679925Y697211D02*
X705515D01*
G01X679925Y1312420D02*
Y697211D01*
G01X705515Y732644D02*
X679925D01*
G01X705515Y1299574D02*
X679925D01*
G01X708293Y1324740D02*
G03I-10827J0D01*
G01X692060Y1337715D02*
X686146D01*
G01X692060Y1377085D02*
Y1337715D01*
G01X692043Y1336912D02*
X692235Y1336602D01*
X692465Y1336395D01*
X692733Y1336292D01*
X693040Y1336395D01*
X693270Y1336602D01*
X693500Y1336912D01*
X693577Y1337325D01*
Y1339392D01*
G01X695182Y1338875D02*
X695412Y1339185D01*
X695680Y1339340D01*
X695987Y1339392D01*
X696370Y1339289D01*
X696638Y1339030D01*
X696715Y1338720D01*
X696677Y1338410D01*
X696523Y1338152D01*
X695757Y1337635D01*
X695412Y1337274D01*
X695182Y1336757D01*
X695105Y1336292D01*
X696715D01*
G01X699010D02*
X699278Y1336344D01*
X699585Y1336499D01*
X699777Y1336757D01*
X699853Y1337119D01*
X699777Y1337480D01*
X699547Y1337790D01*
X699202Y1337945D01*
X698818D01*
X698588Y1338049D01*
X698397Y1338307D01*
X698320Y1338669D01*
X698435Y1339030D01*
X698703Y1339289D01*
X699010Y1339392D01*
X699317Y1339289D01*
X699585Y1339030D01*
X699700Y1338669D01*
X699623Y1338307D01*
X699432Y1338049D01*
X699202Y1337945D01*
X698818D01*
X698473Y1337790D01*
X698243Y1337480D01*
X698167Y1337119D01*
X698243Y1336757D01*
X698435Y1336499D01*
X698742Y1336344D01*
X699010Y1336292D01*
G01X679925Y1335007D02*
Y1333970D01*
G01X690080Y1335007D02*
X679925D01*
G01X708293Y1324740D02*
X686639D01*
G01X698000Y1364745D02*
X694900D01*
Y1365665D01*
X695055Y1365972D01*
X695417Y1366202D01*
X695830Y1366279D01*
X696243Y1366202D01*
X696553Y1366010D01*
X696708Y1365665D01*
Y1364745D01*
G01X694900Y1367845D02*
X698000D01*
Y1369379D01*
G01Y1371712D02*
X694900D01*
X695520Y1371252D01*
G01X698000D02*
Y1372172D01*
G01Y1374812D02*
X697948Y1375080D01*
X697793Y1375387D01*
X697535Y1375579D01*
X697173Y1375655D01*
X696812Y1375579D01*
X696502Y1375349D01*
X696347Y1375004D01*
Y1374620D01*
X696243Y1374390D01*
X695985Y1374199D01*
X695623Y1374122D01*
X695262Y1374237D01*
X695003Y1374505D01*
X694900Y1374812D01*
X695003Y1375119D01*
X695262Y1375387D01*
X695623Y1375502D01*
X695985Y1375425D01*
X696243Y1375234D01*
X696347Y1375004D01*
Y1374620D01*
X696502Y1374275D01*
X696812Y1374045D01*
X697173Y1373969D01*
X697535Y1374045D01*
X697793Y1374237D01*
X697948Y1374544D01*
X698000Y1374812D01*
G01X687104Y1380135D02*
X686311D01*
G01X687104Y1382735D02*
Y1380135D01*
G01X686146Y1377085D02*
X692060D01*
G01X687104Y1403757D02*
Y1401566D01*
G01X686371Y1403757D02*
X687104D01*
G01X689721Y1395315D02*
X692921D01*
G01X689721Y1389115D02*
Y1395315D01*
G01X692921Y1389115D02*
X689721D01*
G01X692921Y1395315D02*
Y1389115D01*
G01X693825Y1395315D02*
X697025D01*
G01X693825Y1389115D02*
Y1395315D01*
G01X697025Y1389115D02*
X693825D01*
G01X688162Y1412940D02*
X700162D01*
G01X688162Y1406940D02*
Y1412940D01*
G01X700162Y1406940D02*
X688162D01*
G01X694342Y1424668D02*
Y1421260D01*
G01X682692Y1413170D02*
X685892D01*
G01X682692Y1406970D02*
Y1413170D01*
G01X685892Y1406970D02*
X682692D01*
G01X685892Y1413170D02*
Y1406970D01*
G01X681850Y1413170D02*
Y1406970D01*
G01X694342Y1438976D02*
Y1435568D01*
G01X689193Y1441065D02*
Y1444165D01*
X690113D01*
X690420Y1444010D01*
X690650Y1443648D01*
X690727Y1443235D01*
X690650Y1442822D01*
X690458Y1442512D01*
X690113Y1442357D01*
X689193D01*
G01X692293Y1444165D02*
Y1441065D01*
X693827D01*
G01X696160D02*
Y1444165D01*
X695700Y1443545D01*
G01Y1441065D02*
X696620D01*
G01X699720D02*
Y1444165D01*
X698302Y1441943D01*
X700218D01*
G01X680300Y1440645D02*
Y1443845D01*
G01X686500Y1440645D02*
X680300D01*
G01X686500Y1443845D02*
Y1440645D01*
G01X680300Y1443845D02*
X686500D01*
G01X681825Y1601800D02*
X681595Y1602162D01*
X681289Y1602368D01*
X680944Y1602420D01*
X680637Y1602368D01*
X680330Y1602110D01*
X680139Y1601800D01*
X680100Y1601490D01*
X680177Y1601128D01*
X680445Y1600870D01*
X680714Y1600767D01*
X681059D01*
G01X680714D02*
X680484Y1600612D01*
X680292Y1600353D01*
X680215Y1600043D01*
X680292Y1599733D01*
X680484Y1599475D01*
X680829Y1599320D01*
X681174Y1599372D01*
X681519Y1599578D01*
G01X693421Y1627097D02*
Y1596703D01*
G01X683579D02*
Y1627097D01*
G01X693421Y1596703D02*
X683579D01*
G01X697387Y1609477D02*
X697697Y1609669D01*
X697904Y1609899D01*
X698007Y1610167D01*
X697904Y1610474D01*
X697697Y1610704D01*
X697387Y1610934D01*
X696974Y1611011D01*
X694907D01*
G01X698007Y1612577D02*
X694907D01*
Y1613497D01*
X695062Y1613804D01*
X695424Y1614034D01*
X695837Y1614111D01*
X696250Y1614034D01*
X696560Y1613842D01*
X696715Y1613497D01*
Y1612577D01*
G01X698007Y1616904D02*
X694907D01*
X697129Y1615486D01*
Y1617402D01*
G01X694907Y1619544D02*
X695010Y1619237D01*
X695269Y1619007D01*
X695579Y1618854D01*
X695992Y1618739D01*
X696457Y1618701D01*
X696922Y1618739D01*
X697335Y1618854D01*
X697645Y1619007D01*
X697904Y1619237D01*
X698007Y1619544D01*
X697904Y1619851D01*
X697645Y1620081D01*
X697335Y1620234D01*
X696922Y1620349D01*
X696457Y1620387D01*
X695992Y1620349D01*
X695579Y1620234D01*
X695269Y1620081D01*
X695010Y1619851D01*
X694907Y1619544D01*
G01Y1622644D02*
X695010Y1622337D01*
X695269Y1622107D01*
X695579Y1621954D01*
X695992Y1621839D01*
X696457Y1621801D01*
X696922Y1621839D01*
X697335Y1621954D01*
X697645Y1622107D01*
X697904Y1622337D01*
X698007Y1622644D01*
X697904Y1622951D01*
X697645Y1623181D01*
X697335Y1623334D01*
X696922Y1623449D01*
X696457Y1623487D01*
X695992Y1623449D01*
X695579Y1623334D01*
X695269Y1623181D01*
X695010Y1622951D01*
X694907Y1622644D01*
G01X697387Y1624901D02*
X697749Y1625131D01*
X697955Y1625437D01*
X698007Y1625782D01*
X697955Y1626089D01*
X697697Y1626396D01*
X697387Y1626587D01*
X697077Y1626626D01*
X696715Y1626549D01*
X696457Y1626281D01*
X696354Y1626012D01*
Y1625667D01*
G01Y1626012D02*
X696199Y1626242D01*
X695940Y1626434D01*
X695630Y1626511D01*
X695320Y1626434D01*
X695062Y1626242D01*
X694907Y1625897D01*
X694959Y1625552D01*
X695165Y1625207D01*
G01X683579Y1627097D02*
X693421D01*
G01X696247Y1631067D02*
X690047D01*
G01D02*
Y1634267D01*
G01X682599Y1641734D02*
Y1633072D01*
G01X690122Y1646267D02*
X696322D01*
G01Y1643067D02*
X690122D01*
G01D02*
Y1646267D01*
G01X690047Y1634267D02*
X696247D01*
G01X696322Y1639067D02*
X690122D01*
G01D02*
Y1642267D01*
G01D02*
X696322D01*
G01X696247Y1635067D02*
X690047D01*
G01D02*
Y1638267D01*
G01D02*
X696247D01*
G01X696332Y1647243D02*
X690132D01*
G01D02*
Y1650443D01*
G01X680988Y1659152D02*
X682888Y1656952D01*
G01D02*
X684788Y1659152D01*
G01D02*
X688135D01*
G01D02*
Y1650490D01*
G01X690132Y1650443D02*
X696332D01*
G01X690520Y1660462D02*
X696720D01*
G01Y1657262D02*
X690520D01*
G01D02*
Y1660462D01*
G01X696720Y1665262D02*
X690520D01*
G01D02*
Y1668462D01*
G01X696720Y1661262D02*
X690520D01*
G01D02*
Y1664462D01*
G01D02*
X696720D01*
G01X683920Y1675193D02*
Y1666531D01*
G01X681258Y1675193D02*
X683920D01*
G01X685520Y1672462D02*
X691720D01*
G01D02*
Y1669262D01*
G01D02*
X685520D01*
G01D02*
Y1672462D01*
G01X690520Y1668462D02*
X696720D01*
G01X690520Y1676462D02*
X696720D01*
G01Y1673262D02*
X690520D01*
G01D02*
Y1676462D01*
G01X696720Y1677262D02*
X690520D01*
G01D02*
Y1680462D01*
G01D02*
X696720D01*
G01Y1681262D02*
X690520D01*
G01D02*
Y1684462D01*
G01D02*
X696720D01*
G01X684405Y1730450D02*
Y1733550D01*
G01X686015D02*
Y1730450D01*
G01Y1732000D02*
X684405D01*
G01X688310Y1730450D02*
X688578Y1730502D01*
X688885Y1730657D01*
X689077Y1730915D01*
X689153Y1731277D01*
X689077Y1731638D01*
X688847Y1731948D01*
X688502Y1732103D01*
X688118D01*
X687888Y1732207D01*
X687697Y1732465D01*
X687620Y1732827D01*
X687735Y1733188D01*
X688003Y1733447D01*
X688310Y1733550D01*
X688617Y1733447D01*
X688885Y1733188D01*
X689000Y1732827D01*
X688923Y1732465D01*
X688732Y1732207D01*
X688502Y1732103D01*
X688118D01*
X687773Y1731948D01*
X687543Y1731638D01*
X687467Y1731277D01*
X687543Y1730915D01*
X687735Y1730657D01*
X688042Y1730502D01*
X688310Y1730450D01*
G01X690758Y1730812D02*
X691027Y1730553D01*
X691333Y1730450D01*
X691640Y1730553D01*
X691908Y1730863D01*
X692100Y1731328D01*
X692177Y1731793D01*
Y1732362D01*
X692100Y1732827D01*
X691908Y1733240D01*
X691678Y1733447D01*
X691410Y1733550D01*
X691103Y1733447D01*
X690873Y1733240D01*
X690720Y1732930D01*
X690643Y1732517D01*
X690720Y1732155D01*
X690912Y1731793D01*
X691142Y1731587D01*
X691410Y1731535D01*
X691717Y1731638D01*
X691947Y1731897D01*
X692177Y1732362D01*
G01X700880Y-15117D02*
X701190Y-14925D01*
X701397Y-14695D01*
X701500Y-14427D01*
X701397Y-14120D01*
X701190Y-13890D01*
X700880Y-13660D01*
X700467Y-13583D01*
X698400D01*
G01X701500Y-11327D02*
X700828Y-11250D01*
X700260Y-11135D01*
X699743Y-10982D01*
X699175Y-10790D01*
X698400Y-10483D01*
Y-12017D01*
G01X701138Y-8802D02*
X701397Y-8533D01*
X701500Y-8227D01*
X701397Y-7920D01*
X701087Y-7652D01*
X700622Y-7460D01*
X700157Y-7383D01*
X699588D01*
X699123Y-7460D01*
X698710Y-7652D01*
X698503Y-7882D01*
X698400Y-8150D01*
X698503Y-8457D01*
X698710Y-8687D01*
X699020Y-8840D01*
X699433Y-8917D01*
X699795Y-8840D01*
X700157Y-8648D01*
X700363Y-8418D01*
X700415Y-8150D01*
X700312Y-7843D01*
X700053Y-7613D01*
X699588Y-7383D01*
G01X721910Y-3200D02*
Y-19800D01*
X712310D01*
Y-3200D01*
X721910D01*
G01X720254Y64567D02*
X705454D01*
G01X705600Y74762D02*
X702400D01*
G01X705600Y80962D02*
Y74762D01*
G01X702400Y80962D02*
X705600D01*
G01X702400Y74762D02*
Y80962D01*
G01X705323Y101708D02*
Y104908D01*
G01X711523Y101708D02*
X705323D01*
G01X711523Y104908D02*
Y101708D01*
G01X712213Y122315D02*
X712373Y122565D01*
X712560Y122690D01*
X712773Y122732D01*
X713040Y122649D01*
X713227Y122440D01*
X713280Y122190D01*
X713253Y121940D01*
X713147Y121732D01*
X712613Y121315D01*
X712373Y121024D01*
X712213Y120607D01*
X712160Y120232D01*
X713280D01*
G01X714920D02*
Y122732D01*
X714600Y122232D01*
G01Y120232D02*
X715240D01*
G01X716320Y119399D02*
X717920D01*
G01X718813Y122315D02*
X718973Y122565D01*
X719160Y122690D01*
X719373Y122732D01*
X719640Y122649D01*
X719827Y122440D01*
X719880Y122190D01*
X719853Y121940D01*
X719747Y121732D01*
X719213Y121315D01*
X718973Y121024D01*
X718813Y120607D01*
X718760Y120232D01*
X719880D01*
G01X721013Y122315D02*
X721173Y122565D01*
X721360Y122690D01*
X721573Y122732D01*
X721840Y122649D01*
X722027Y122440D01*
X722080Y122190D01*
X722053Y121940D01*
X721947Y121732D01*
X721413Y121315D01*
X721173Y121024D01*
X721013Y120607D01*
X720960Y120232D01*
X722080D01*
G01X709622Y107826D02*
Y110967D01*
G01Y116889D02*
Y120030D01*
G01X708457Y107826D02*
X709622D01*
G01Y112978D02*
Y114878D01*
G01X705323Y104908D02*
X711523D01*
G01X709622Y120030D02*
X708449D01*
G01X706553Y126568D02*
X703353D01*
G01X706553Y132768D02*
Y126568D01*
G01X703353Y132768D02*
X706553D01*
G01X703353Y126568D02*
Y132768D01*
G01X707353D02*
X710553D01*
G01X707353Y126568D02*
Y132768D01*
G01X710553Y126568D02*
X707353D01*
G01X710553Y132768D02*
Y126568D01*
G01X702563Y126628D02*
X699363D01*
G01X702563Y132828D02*
Y126628D01*
G01X699363Y132828D02*
X702563D01*
G01X699363Y126628D02*
Y132828D01*
G01X702333Y143572D02*
X702410Y144244D01*
X702525Y144812D01*
X702678Y145329D01*
X702870Y145897D01*
X703177Y146672D01*
X701643D01*
G01X704667Y144037D02*
X704897Y143779D01*
X705165Y143624D01*
X705510Y143572D01*
X705855Y143675D01*
X706123Y143882D01*
X706315Y144244D01*
X706353Y144657D01*
X706277Y145070D01*
X706085Y145329D01*
X705817Y145535D01*
X705548Y145587D01*
X705280Y145535D01*
X704935Y145329D01*
X705050Y146672D01*
X706085D01*
G01X701962Y154224D02*
X702230Y154585D01*
X702460Y154792D01*
X702767Y154895D01*
X703035Y154792D01*
X703227Y154585D01*
X703380Y154275D01*
X703418Y153914D01*
X703380Y153604D01*
X703227Y153294D01*
X702997Y153035D01*
X702728Y152932D01*
X702422Y153035D01*
X702153Y153345D01*
X702000Y153810D01*
X701962Y154327D01*
X702038Y154999D01*
X702153Y155360D01*
X702345Y155722D01*
X702613Y155980D01*
X702882Y156032D01*
X703150Y155929D01*
X703342Y155670D01*
G01X705713Y152932D02*
X705790Y153604D01*
X705905Y154172D01*
X706058Y154689D01*
X706250Y155257D01*
X706557Y156032D01*
X705023D01*
G01X701297Y162097D02*
X701527Y161839D01*
X701795Y161684D01*
X702140Y161632D01*
X702485Y161735D01*
X702753Y161942D01*
X702945Y162304D01*
X702983Y162717D01*
X702907Y163130D01*
X702715Y163389D01*
X702447Y163595D01*
X702178Y163647D01*
X701910Y163595D01*
X701565Y163389D01*
X701680Y164732D01*
X702715D01*
G01X705163Y161632D02*
X705240Y162304D01*
X705355Y162872D01*
X705508Y163389D01*
X705700Y163957D01*
X706007Y164732D01*
X704473D01*
G01X697768Y165485D02*
Y157743D01*
G01X696587D02*
Y165485D01*
G01X708620Y160262D02*
Y163462D01*
G01X714820Y160262D02*
X708620D01*
G01Y163462D02*
X714820D01*
G01X708620Y155762D02*
Y158962D01*
G01X714820Y155762D02*
X708620D01*
G01Y158962D02*
X714820D01*
G01X705033Y227372D02*
Y230472D01*
X706030Y227889D01*
X707027Y230472D01*
Y227372D01*
G01X709130Y227269D02*
X709053Y227320D01*
Y227424D01*
X709130Y227475D01*
X709207Y227424D01*
Y227320D01*
X709130Y227269D01*
G01X711502Y229955D02*
X711732Y230265D01*
X712000Y230420D01*
X712307Y230472D01*
X712690Y230369D01*
X712958Y230110D01*
X713035Y229800D01*
X712997Y229490D01*
X712843Y229232D01*
X712077Y228715D01*
X711732Y228354D01*
X711502Y227837D01*
X711425Y227372D01*
X713035D01*
G01X717625Y227785D02*
X717932Y227527D01*
X718277Y227372D01*
X718583D01*
X718890Y227527D01*
X719120Y227785D01*
X719235Y228147D01*
X719158Y228509D01*
X718967Y228819D01*
X718622Y229025D01*
X718162Y229129D01*
X717893Y229335D01*
X717778Y229697D01*
X717855Y230059D01*
X718047Y230317D01*
X718315Y230472D01*
X718583D01*
X718852Y230369D01*
X719082Y230110D01*
G01X720763Y230472D02*
Y227372D01*
X722297D01*
G01X724630D02*
X724323Y227424D01*
X724055Y227630D01*
X723825Y227940D01*
X723672Y228302D01*
X723595Y228715D01*
Y229129D01*
X723672Y229542D01*
X723825Y229904D01*
X724055Y230214D01*
X724323Y230420D01*
X724630Y230472D01*
X724937Y230420D01*
X725205Y230214D01*
X725435Y229904D01*
X725588Y229542D01*
X725665Y229129D01*
Y228715D01*
X725588Y228302D01*
X725435Y227940D01*
X725205Y227630D01*
X724937Y227424D01*
X724630Y227372D01*
G01X727730Y230472D02*
Y227372D01*
G01X726848Y230472D02*
X728612D01*
G01X733930D02*
X733623Y230369D01*
X733393Y230110D01*
X733240Y229800D01*
X733125Y229387D01*
X733087Y228922D01*
X733125Y228457D01*
X733240Y228044D01*
X733393Y227734D01*
X733623Y227475D01*
X733930Y227372D01*
X734237Y227475D01*
X734467Y227734D01*
X734620Y228044D01*
X734735Y228457D01*
X734773Y228922D01*
X734735Y229387D01*
X734620Y229800D01*
X734467Y230110D01*
X734237Y230369D01*
X733930Y230472D01*
G01X739938Y226339D02*
X739555Y226855D01*
X739363Y227372D01*
Y229439D01*
X739555Y229955D01*
X739938Y230472D01*
G01X742425Y227785D02*
X742732Y227527D01*
X743077Y227372D01*
X743383D01*
X743690Y227527D01*
X743920Y227785D01*
X744035Y228147D01*
X743958Y228509D01*
X743767Y228819D01*
X743422Y229025D01*
X742962Y229129D01*
X742693Y229335D01*
X742578Y229697D01*
X742655Y230059D01*
X742847Y230317D01*
X743115Y230472D01*
X743383D01*
X743652Y230369D01*
X743882Y230110D01*
G01X745372Y227372D02*
X746330Y230472D01*
X747288Y227372D01*
G01X746943Y228457D02*
X745717D01*
G01X749430Y230472D02*
Y227372D01*
G01X748548Y230472D02*
X750312D01*
G01X751572Y227372D02*
X752530Y230472D01*
X753488Y227372D01*
G01X753143Y228457D02*
X751917D01*
G01X754940Y227269D02*
X756320Y230472D01*
G01X757963Y227372D02*
Y230472D01*
X758883D01*
X759190Y230317D01*
X759420Y229955D01*
X759497Y229542D01*
X759420Y229129D01*
X759228Y228819D01*
X758883Y228664D01*
X757963D01*
G01X762673Y230214D02*
X762443Y230369D01*
X762175Y230472D01*
X761868D01*
X761523Y230317D01*
X761255Y230059D01*
X761063Y229749D01*
X760910Y229232D01*
X760872Y228767D01*
X760948Y228302D01*
X761063Y227992D01*
X761293Y227682D01*
X761562Y227475D01*
X761830Y227372D01*
X762098D01*
X762367Y227475D01*
X762597Y227630D01*
X762788Y227837D01*
G01X764470Y230472D02*
X765390D01*
G01X764930D02*
Y227372D01*
G01X764470D02*
X765390D01*
G01X767455Y228767D02*
X768682D01*
X768567Y229129D01*
X768375Y229335D01*
X768107Y229439D01*
X767838Y229387D01*
X767608Y229232D01*
X767455Y228870D01*
X767378Y228560D01*
Y228250D01*
X767455Y227940D01*
X767647Y227630D01*
X767877Y227424D01*
X768145Y227372D01*
X768413Y227475D01*
X768682Y227785D01*
G01X773655Y229439D02*
X774805Y227372D01*
G01Y229439D02*
X773655Y227372D01*
G01X777790D02*
Y230472D01*
X776372Y228250D01*
X778288D01*
G01X780622Y226339D02*
X781005Y226855D01*
X781197Y227372D01*
Y229439D01*
X781005Y229955D01*
X780622Y230472D01*
G01X704903Y232602D02*
X705095Y232292D01*
X705325Y232085D01*
X705593Y231982D01*
X705900Y232085D01*
X706130Y232292D01*
X706360Y232602D01*
X706437Y233015D01*
Y235082D01*
G01X707927Y232447D02*
X708157Y232189D01*
X708425Y232034D01*
X708770Y231982D01*
X709115Y232085D01*
X709383Y232292D01*
X709575Y232654D01*
X709613Y233067D01*
X709537Y233480D01*
X709345Y233739D01*
X709077Y233945D01*
X708808Y233997D01*
X708540Y233945D01*
X708195Y233739D01*
X708310Y235082D01*
X709345D01*
G01X711218Y232344D02*
X711487Y232085D01*
X711793Y231982D01*
X712100Y232085D01*
X712368Y232395D01*
X712560Y232860D01*
X712637Y233325D01*
Y233894D01*
X712560Y234359D01*
X712368Y234772D01*
X712138Y234979D01*
X711870Y235082D01*
X711563Y234979D01*
X711333Y234772D01*
X711180Y234462D01*
X711103Y234049D01*
X711180Y233687D01*
X711372Y233325D01*
X711602Y233119D01*
X711870Y233067D01*
X712177Y233170D01*
X712407Y233429D01*
X712637Y233894D01*
G01X708620Y223462D02*
X714820D01*
G01X708620Y220262D02*
Y223462D01*
G01X714820Y220262D02*
X708620D01*
G01X709000Y365162D02*
Y371362D01*
X712200D01*
Y365162D01*
X709000D01*
G01Y368312D02*
Y374512D01*
X712200D01*
Y368312D01*
X709000D01*
G01X704000Y365162D02*
Y371362D01*
X707200D01*
Y365162D01*
X704000D01*
G01Y368312D02*
Y374512D01*
X707200D01*
Y368312D01*
X704000D01*
G01X699000Y365162D02*
Y371362D01*
X702200D01*
Y365162D01*
X699000D01*
G01Y368312D02*
Y374512D01*
X702200D01*
Y368312D01*
X699000D01*
G01X707120Y379262D02*
Y385462D01*
G01X710320Y379262D02*
X707120D01*
G01X710320Y385462D02*
Y379262D01*
G01X714820D02*
X711620D01*
G01D02*
Y385462D01*
G01X707120D02*
X710320D01*
G01X711620Y395462D02*
X714820D01*
G01X711620Y389262D02*
Y395462D01*
G01X714820Y389262D02*
X711620D01*
G01Y385462D02*
X714820D01*
G01X712820Y509762D02*
X709620D01*
G01D02*
Y515962D01*
G01X706820Y509762D02*
X703620D01*
G01X706820Y515962D02*
Y509762D01*
G01X703620D02*
Y515962D01*
G01X696820D02*
Y509762D01*
G01X703620Y502962D02*
X706820D01*
G01X703620Y496762D02*
Y502962D01*
G01X706820Y496762D02*
X703620D01*
G01X706820Y502962D02*
Y496762D01*
G01X709620Y502962D02*
X712820D01*
G01X709620Y496762D02*
Y502962D01*
G01X712820Y496762D02*
X709620D01*
G01X696820Y529462D02*
Y523262D01*
G01X703620D02*
Y529462D01*
G01X706820Y523262D02*
X703620D01*
G01X706820Y529462D02*
Y523262D01*
G01X709620Y515962D02*
X712820D01*
G01X703620D02*
X706820D01*
G01X703620Y529462D02*
X706820D01*
G01X709625Y697211D02*
X735215D01*
G01X709625Y1335007D02*
Y697211D01*
G01X705515D02*
Y1312750D01*
G01X735215Y732644D02*
X709625D01*
G01X735215Y1299574D02*
X709625D01*
G01X732693Y1324740D02*
G03I-10827J0D01*
G01X700632Y1337715D02*
Y1357400D01*
G01X706596Y1337715D02*
X700632D01*
G01X716440Y1335007D02*
X709625D01*
G01X705515D02*
X703590D01*
G01X705515Y1333720D02*
Y1335007D01*
G01X732693Y1324740D02*
X711039D01*
G01X700632Y1357400D02*
Y1377085D01*
G01X705561Y1380135D02*
Y1382735D01*
G01X706354Y1380135D02*
X705561D01*
G01X700632Y1377085D02*
X706546D01*
G01X699730Y1388095D02*
Y1394295D01*
G01X702930Y1388095D02*
X699730D01*
G01X702930Y1394295D02*
Y1388095D01*
G01X705561Y1403757D02*
X706569D01*
G01X705561Y1401903D02*
Y1403757D01*
G01Y1389346D02*
Y1391044D01*
G01X702930Y1398595D02*
X699730D01*
G01X702930Y1404795D02*
Y1398595D01*
G01X699730Y1404795D02*
X702930D01*
G01X699730Y1398595D02*
Y1404795D01*
G01Y1394295D02*
X702930D01*
G01X697025Y1395315D02*
Y1389115D01*
G01X700162Y1412940D02*
Y1406940D01*
G01X702968Y1413084D02*
X706168D01*
G01X702968Y1406884D02*
Y1413084D01*
G01X706168Y1406884D02*
X702968D01*
G01X706168Y1413084D02*
Y1406884D01*
G01X707220Y1410598D02*
Y1413798D01*
G01X713420Y1410598D02*
X707220D01*
G01Y1413798D02*
X713420D01*
G01X727102Y1429579D02*
G03I-13386J0D01*
G01X709212Y1569283D02*
Y1566083D01*
G01X703012D02*
Y1569283D01*
G01X709212Y1566083D02*
X703012D01*
G01X709242Y1565333D02*
Y1562133D01*
G01X703042D02*
Y1565333D01*
G01X709242Y1562133D02*
X703042D01*
G01Y1565333D02*
X709242D01*
G01X703012Y1569283D02*
X709212D01*
G01Y1581283D02*
Y1578083D01*
G01X703012Y1581283D02*
X709212D01*
G01X703012Y1578083D02*
Y1581283D01*
G01X709212Y1578083D02*
X703012D01*
G01X709212Y1573283D02*
Y1570083D01*
G01X703012Y1573283D02*
X709212D01*
G01X703012Y1570083D02*
Y1573283D01*
G01X709212Y1570083D02*
X703012D01*
G01X709212Y1577283D02*
Y1574083D01*
G01X703012Y1577283D02*
X709212D01*
G01X703012Y1574083D02*
Y1577283D01*
G01X709212Y1574083D02*
X703012D01*
G01X709212Y1585283D02*
Y1582083D01*
G01X703012D02*
Y1585283D01*
G01X709212Y1582083D02*
X703012D01*
G01X709212Y1589283D02*
Y1586083D01*
G01X703012Y1589283D02*
X709212D01*
G01X703012Y1586083D02*
Y1589283D01*
G01X709212Y1586083D02*
X703012D01*
G01X709212Y1597283D02*
Y1594083D01*
G01X703012Y1597283D02*
X709212D01*
G01X703012Y1594083D02*
Y1597283D01*
G01X709212Y1594083D02*
X703012D01*
G01Y1585283D02*
X709212D01*
G01Y1593283D02*
Y1590083D01*
G01X703012Y1593283D02*
X709212D01*
G01X703012Y1590083D02*
Y1593283D01*
G01X709212Y1590083D02*
X703012D01*
G01X701980Y1608702D02*
X708180D01*
G01D02*
Y1605502D01*
G01D02*
X701980D01*
G01D02*
Y1608702D01*
G01Y1612622D02*
X708180D01*
G01D02*
Y1609422D01*
G01D02*
X701980D01*
G01D02*
Y1612622D01*
G01X709172Y1603563D02*
Y1600363D01*
G01X702972D02*
Y1603563D01*
G01X709172Y1600363D02*
X702972D01*
G01Y1603563D02*
X709172D01*
G01X710180Y1615830D02*
Y1622030D01*
X713380D01*
Y1615830D01*
X710180D01*
G01X696247Y1634267D02*
Y1631067D01*
G01X708100Y1626487D02*
X710322D01*
X710787Y1626640D01*
X711097Y1626947D01*
X711200Y1627330D01*
X711097Y1627713D01*
X710787Y1628020D01*
X710322Y1628173D01*
X708100D01*
G01X710580Y1629587D02*
X710942Y1629817D01*
X711148Y1630123D01*
X711200Y1630468D01*
X711148Y1630775D01*
X710890Y1631082D01*
X710580Y1631273D01*
X710270Y1631312D01*
X709908Y1631235D01*
X709650Y1630967D01*
X709547Y1630698D01*
Y1630353D01*
G01Y1630698D02*
X709392Y1630928D01*
X709133Y1631120D01*
X708823Y1631197D01*
X708513Y1631120D01*
X708255Y1630928D01*
X708100Y1630583D01*
X708152Y1630238D01*
X708358Y1629893D01*
G01X711200Y1633990D02*
X708100D01*
X710322Y1632572D01*
Y1634488D01*
G01X711200Y1637090D02*
X708100D01*
X710322Y1635672D01*
Y1637588D01*
G01X699298Y1634417D02*
X701520D01*
X701985Y1634570D01*
X702295Y1634877D01*
X702398Y1635260D01*
X702295Y1635643D01*
X701985Y1635950D01*
X701520Y1636103D01*
X699298D01*
G01X702398Y1638360D02*
X699298D01*
X699918Y1637900D01*
G01X702398D02*
Y1638820D01*
G01X702036Y1640808D02*
X702295Y1641077D01*
X702398Y1641383D01*
X702295Y1641690D01*
X701985Y1641958D01*
X701520Y1642150D01*
X701055Y1642227D01*
X700486D01*
X700021Y1642150D01*
X699608Y1641958D01*
X699401Y1641728D01*
X699298Y1641460D01*
X699401Y1641153D01*
X699608Y1640923D01*
X699918Y1640770D01*
X700331Y1640693D01*
X700693Y1640770D01*
X701055Y1640962D01*
X701261Y1641192D01*
X701313Y1641460D01*
X701210Y1641767D01*
X700951Y1641997D01*
X700486Y1642227D01*
G01X699815Y1643832D02*
X699505Y1644062D01*
X699350Y1644330D01*
X699298Y1644637D01*
X699401Y1645020D01*
X699660Y1645288D01*
X699970Y1645365D01*
X700280Y1645327D01*
X700538Y1645173D01*
X701055Y1644407D01*
X701416Y1644062D01*
X701933Y1643832D01*
X702398Y1643755D01*
Y1645365D01*
G01X710119Y1638251D02*
Y1644451D01*
G01D02*
X713319D01*
G01Y1638251D02*
X710119D01*
G01X696322Y1646267D02*
Y1643067D01*
G01Y1642267D02*
Y1639067D01*
G01X696247Y1638267D02*
Y1635067D01*
G01X696332Y1650443D02*
Y1647243D01*
G01X701719Y1654951D02*
Y1665751D01*
G01X713719Y1662351D02*
X711719Y1660351D01*
G01D02*
X713719Y1658351D01*
G01Y1654951D02*
X701719D01*
G01X696720Y1660462D02*
Y1657262D01*
G01Y1668462D02*
Y1665262D01*
G01Y1664462D02*
Y1661262D01*
G01X701719Y1665751D02*
X713719D01*
G01X696720Y1676462D02*
Y1673262D01*
G01Y1680462D02*
Y1677262D01*
G01Y1684462D02*
Y1681262D01*
G01X716233Y1678800D02*
X710033D01*
G01D02*
Y1682000D01*
G01D02*
X716233D01*
G01X713413Y74082D02*
Y77182D01*
X714333D01*
X714640Y77027D01*
X714870Y76665D01*
X714947Y76252D01*
X714870Y75839D01*
X714678Y75529D01*
X714333Y75374D01*
X713413D01*
G01X716437Y74082D02*
Y77182D01*
X717203D01*
X717510Y77027D01*
X717740Y76820D01*
X717932Y76510D01*
X718085Y76149D01*
X718123Y75632D01*
X718085Y75115D01*
X717932Y74754D01*
X717740Y74444D01*
X717510Y74237D01*
X717203Y74082D01*
X716437D01*
G01X720380D02*
Y77182D01*
X719920Y76562D01*
G01Y74082D02*
X720840D01*
G01X723480D02*
Y77182D01*
X723020Y76562D01*
G01Y74082D02*
X723940D01*
G01X725852Y75374D02*
X726120Y75735D01*
X726350Y75942D01*
X726657Y76045D01*
X726925Y75942D01*
X727117Y75735D01*
X727270Y75425D01*
X727308Y75064D01*
X727270Y74754D01*
X727117Y74444D01*
X726887Y74185D01*
X726618Y74082D01*
X726312Y74185D01*
X726043Y74495D01*
X725890Y74960D01*
X725852Y75477D01*
X725928Y76149D01*
X726043Y76510D01*
X726235Y76872D01*
X726503Y77130D01*
X726772Y77182D01*
X727040Y77079D01*
X727232Y76820D01*
G01X728393Y85398D02*
Y88598D01*
G01X734593Y85398D02*
X728393D01*
G01X728423Y93558D02*
Y96758D01*
G01X734623Y93558D02*
X728423D01*
G01Y96758D02*
X734623D01*
G01X728393Y88598D02*
X734593D01*
G01X728393Y89398D02*
Y92598D01*
G01X734593Y89398D02*
X728393D01*
G01Y92598D02*
X734593D01*
G01X720298Y113996D02*
Y117096D01*
X721218D01*
X721525Y116941D01*
X721755Y116579D01*
X721832Y116166D01*
X721755Y115753D01*
X721563Y115443D01*
X721218Y115288D01*
X720298D01*
G01X723322Y117096D02*
Y114874D01*
X723475Y114409D01*
X723782Y114099D01*
X724165Y113996D01*
X724548Y114099D01*
X724855Y114409D01*
X725008Y114874D01*
Y117096D01*
G01X726422Y114616D02*
X726652Y114254D01*
X726958Y114048D01*
X727303Y113996D01*
X727610Y114048D01*
X727917Y114306D01*
X728108Y114616D01*
X728147Y114926D01*
X728070Y115288D01*
X727802Y115546D01*
X727533Y115649D01*
X727188D01*
G01X727533D02*
X727763Y115804D01*
X727955Y116063D01*
X728032Y116373D01*
X727955Y116683D01*
X727763Y116941D01*
X727418Y117096D01*
X727073Y117044D01*
X726728Y116838D01*
G01X730365Y117096D02*
X730058Y116993D01*
X729828Y116734D01*
X729675Y116424D01*
X729560Y116011D01*
X729522Y115546D01*
X729560Y115081D01*
X729675Y114668D01*
X729828Y114358D01*
X730058Y114099D01*
X730365Y113996D01*
X730672Y114099D01*
X730902Y114358D01*
X731055Y114668D01*
X731170Y115081D01*
X731208Y115546D01*
X731170Y116011D01*
X731055Y116424D01*
X730902Y116734D01*
X730672Y116993D01*
X730365Y117096D01*
G01X733465D02*
X733158Y116993D01*
X732928Y116734D01*
X732775Y116424D01*
X732660Y116011D01*
X732622Y115546D01*
X732660Y115081D01*
X732775Y114668D01*
X732928Y114358D01*
X733158Y114099D01*
X733465Y113996D01*
X733772Y114099D01*
X734002Y114358D01*
X734155Y114668D01*
X734270Y115081D01*
X734308Y115546D01*
X734270Y116011D01*
X734155Y116424D01*
X734002Y116734D01*
X733772Y116993D01*
X733465Y117096D01*
G01X714373Y108425D02*
X714533Y108675D01*
X714720Y108800D01*
X714933Y108842D01*
X715200Y108759D01*
X715387Y108550D01*
X715440Y108300D01*
X715413Y108050D01*
X715307Y107842D01*
X714773Y107425D01*
X714533Y107134D01*
X714373Y106717D01*
X714320Y106342D01*
X715440D01*
G01X717080Y108842D02*
X716867Y108759D01*
X716707Y108550D01*
X716600Y108300D01*
X716520Y107967D01*
X716493Y107592D01*
X716520Y107217D01*
X716600Y106884D01*
X716707Y106634D01*
X716867Y106425D01*
X717080Y106342D01*
X717293Y106425D01*
X717453Y106634D01*
X717560Y106884D01*
X717640Y107217D01*
X717667Y107592D01*
X717640Y107967D01*
X717560Y108300D01*
X717453Y108550D01*
X717293Y108759D01*
X717080Y108842D01*
G01X717123Y127792D02*
Y130892D01*
X718043D01*
X718350Y130737D01*
X718580Y130375D01*
X718657Y129962D01*
X718580Y129549D01*
X718388Y129239D01*
X718043Y129084D01*
X717123D01*
G01X720147Y127792D02*
Y130892D01*
X720913D01*
X721220Y130737D01*
X721450Y130530D01*
X721642Y130220D01*
X721795Y129859D01*
X721833Y129342D01*
X721795Y128825D01*
X721642Y128464D01*
X721450Y128154D01*
X721220Y127947D01*
X720913Y127792D01*
X720147D01*
G01X724090D02*
Y130892D01*
X723630Y130272D01*
G01Y127792D02*
X724550D01*
G01X727190D02*
Y130892D01*
X726730Y130272D01*
G01Y127792D02*
X727650D01*
G01X729447Y128257D02*
X729677Y127999D01*
X729945Y127844D01*
X730290Y127792D01*
X730635Y127895D01*
X730903Y128102D01*
X731095Y128464D01*
X731133Y128877D01*
X731057Y129290D01*
X730865Y129549D01*
X730597Y129755D01*
X730328Y129807D01*
X730060Y129755D01*
X729715Y129549D01*
X729830Y130892D01*
X730865D01*
G01X725533Y133888D02*
X722333D01*
G01X725533Y140088D02*
Y133888D01*
G01X722333D02*
Y140088D01*
G01D02*
X725533D01*
G01X728233Y162388D02*
Y159188D01*
G01X722033Y162388D02*
X728233D01*
G01X722033Y159188D02*
Y162388D01*
G01X728233Y159188D02*
X722033D01*
G01X714820Y163462D02*
Y160262D01*
G01Y158962D02*
Y155762D01*
G01Y223462D02*
Y220262D01*
G01X714000Y365162D02*
Y371362D01*
X717200D01*
Y365162D01*
X714000D01*
G01Y368312D02*
Y374512D01*
X717200D01*
Y368312D01*
X714000D01*
G01X726620Y379262D02*
Y385462D01*
G01X729820Y379262D02*
X726620D01*
G01X714820Y385462D02*
Y379262D01*
G01X725400Y366625D02*
Y372825D01*
X728600D01*
Y366625D01*
X725400D01*
G01X720900D02*
Y372825D01*
X724100D01*
Y366625D01*
X720900D01*
G01X726620Y395462D02*
X729820D01*
G01X726620Y389262D02*
Y395462D01*
G01X729820Y389262D02*
X726620D01*
G01Y385462D02*
X729820D01*
G01X716620Y395462D02*
X719820D01*
G01X716620Y389262D02*
Y395462D01*
G01X719820Y389262D02*
X716620D01*
G01X719820Y395462D02*
Y389262D01*
G01X714820Y395462D02*
Y389262D01*
G01X715620Y509762D02*
Y515962D01*
G01X718820Y509762D02*
X715620D01*
G01X718820Y515962D02*
Y509762D01*
G01X712820Y515962D02*
Y509762D01*
G01Y502962D02*
Y496762D01*
G01X721620Y509762D02*
Y515962D01*
G01X724820Y509762D02*
X721620D01*
G01X724820Y515962D02*
Y509762D01*
G01X727620D02*
Y515962D01*
G01X730820Y509762D02*
X727620D01*
G01X715620Y502962D02*
X718820D01*
G01X715620Y496762D02*
Y502962D01*
G01X718820Y496762D02*
X715620D01*
G01X718820Y502962D02*
Y496762D01*
G01X721620Y502962D02*
X724820D01*
G01X721620Y496762D02*
Y502962D01*
G01X724820Y496762D02*
X721620D01*
G01X724820Y502962D02*
Y496762D01*
G01X727620Y502962D02*
X730820D01*
G01X727620Y496762D02*
Y502962D01*
G01X730820Y496762D02*
X727620D01*
G01X715620Y515962D02*
X718820D01*
G01X721620D02*
X724820D01*
G01X727620D02*
X730820D01*
G01X730160Y1337715D02*
X724246D01*
G01X735215Y1335007D02*
X728410D01*
G01X725247Y1380135D02*
X724454D01*
G01X725247Y1382735D02*
Y1380135D01*
G01X724246Y1377085D02*
X730160D01*
G01X725247Y1403757D02*
Y1401566D01*
G01X724514Y1403757D02*
X725247D01*
G01X728109Y1395424D02*
X731309D01*
G01X728109Y1389224D02*
Y1395424D01*
G01X731309Y1389224D02*
X728109D01*
G01X720835Y1413170D02*
X724035D01*
G01X720835Y1406970D02*
Y1413170D01*
G01X724035Y1406970D02*
X720835D01*
G01X724035Y1413170D02*
Y1406970D01*
G01X719993D02*
X716793D01*
G01X719993Y1413170D02*
Y1406970D01*
G01X716793Y1413170D02*
X719993D01*
G01X716793Y1406970D02*
Y1413170D01*
G01X713420Y1413798D02*
Y1410598D01*
G01X713716Y1416193D02*
Y1442965D01*
G01X718845Y1565688D02*
X725045D01*
G01D02*
Y1562488D01*
G01D02*
X718845D01*
G01D02*
Y1565688D01*
G01X724352Y1571093D02*
Y1567893D01*
G01X718152Y1571093D02*
X724352D01*
G01X718152Y1567893D02*
Y1571093D01*
G01X724352Y1567893D02*
X718152D01*
G01X725152Y1571093D02*
X731352D01*
G01X725152Y1567893D02*
Y1571093D01*
G01X731352Y1567893D02*
X725152D01*
G01X717899Y1575412D02*
X745991D01*
G01X717899Y1595630D02*
Y1575412D01*
G01X745991Y1595630D02*
X717899D01*
G01X726253Y1616103D02*
X732453D01*
G01X726253Y1612903D02*
Y1616103D01*
G01X732453Y1612903D02*
X726253D01*
G01X723952Y1607193D02*
X727152D01*
G01Y1600993D02*
X723952D01*
G01X727152Y1607193D02*
Y1600993D01*
G01X723952D02*
Y1607193D01*
G01X717380Y1622030D02*
Y1615830D01*
X714180D01*
Y1622030D01*
X717380D01*
G01X721370Y1622020D02*
Y1615820D01*
X718170D01*
Y1622020D01*
X721370D01*
G01X726152Y1611493D02*
X732352D01*
G01X726152Y1608293D02*
Y1611493D01*
G01X732352Y1608293D02*
X726152D01*
G01X721212Y1607283D02*
Y1601083D01*
G01X718012Y1607283D02*
X721212D01*
G01Y1601083D02*
X718012D01*
G01D02*
Y1607283D01*
G01X725420Y1622020D02*
Y1615820D01*
X722220D01*
Y1622020D01*
X725420D01*
G01X716168Y1640930D02*
X728372D01*
Y1624930D01*
X716168D01*
Y1630930D01*
X719270Y1632930D01*
X716168Y1634930D01*
Y1640930D01*
G01X713319Y1644451D02*
Y1638251D01*
G01X716670Y1646150D02*
X722870D01*
Y1642950D01*
X716670D01*
Y1646150D01*
G01X720430Y1654570D02*
Y1648370D01*
X717230D01*
Y1654570D01*
X720430D01*
G01X721030Y1648370D02*
Y1654570D01*
X724230D01*
Y1648370D01*
X721030D01*
G01X725120Y1642840D02*
Y1649040D01*
X728320D01*
Y1642840D01*
X725120D01*
G01X713719Y1665751D02*
Y1662351D01*
G01Y1658351D02*
Y1654951D01*
G01X717106Y1656374D02*
X729074D01*
Y1671086D01*
X717106D01*
Y1656374D01*
G01X723433Y1678800D02*
X717233D01*
G01D02*
Y1682000D01*
G01X723433D02*
Y1678800D01*
G01X716233Y1682000D02*
Y1678800D01*
G01X717233Y1678100D02*
X723433D01*
Y1674900D01*
X717233D01*
Y1678100D01*
G01Y1682000D02*
X723433D01*
G01X735430Y79538D02*
X737856D01*
G01X738970Y73490D02*
Y84986D01*
G01X768529Y73490D02*
X738970D01*
G01Y84986D02*
X768529D01*
G01X734593Y88598D02*
Y85398D01*
G01X735493Y86377D02*
Y92577D01*
G01X738693Y86377D02*
X735493D01*
G01X738693Y92577D02*
Y86377D01*
G01X766780Y71930D02*
X738090D01*
G01X740015Y96864D02*
X753991D01*
G01X740015Y105052D02*
Y96864D01*
G01X734623Y96758D02*
Y93558D01*
G01X735493Y92577D02*
X738693D01*
G01X734593Y92598D02*
Y89398D01*
G01X735103Y103568D02*
Y100368D01*
G01X728903Y103568D02*
X735103D01*
G01X728903Y100368D02*
Y103568D01*
G01X735103Y100368D02*
X728903D01*
G01X753991Y105052D02*
X740015D01*
G01X735740Y114135D02*
Y120335D01*
G01X738940Y114135D02*
X735740D01*
G01X738940Y120335D02*
Y114135D01*
G01X742833Y112852D02*
Y109652D01*
G01X736633Y112852D02*
X742833D01*
G01X736633Y109652D02*
Y112852D01*
G01X742833Y109652D02*
X736633D01*
G01X739670Y114059D02*
Y120259D01*
G01X742870Y114059D02*
X739670D01*
G01X742870Y120259D02*
Y114059D01*
G01X735103Y107068D02*
Y103868D01*
G01X728903Y107068D02*
X735103D01*
G01X728903Y103868D02*
Y107068D01*
G01X735103Y103868D02*
X728903D01*
G01X741039Y126419D02*
X738613D01*
G01X741867Y122482D02*
X761085D01*
G01X741867Y130356D02*
Y122482D01*
G01X761085Y130356D02*
X741867D01*
G01X735740Y120335D02*
X738940D01*
G01X739670Y120259D02*
X742870D01*
G01X744135Y140450D02*
Y143650D01*
G01X750335Y140450D02*
X744135D01*
G01Y143650D02*
X750335D01*
G01X744145Y139464D02*
X750345D01*
G01X744145Y136264D02*
Y139464D01*
G01X750345Y136264D02*
X744145D01*
G01X743013Y256899D02*
Y259999D01*
X743933D01*
X744240Y259844D01*
X744470Y259482D01*
X744547Y259069D01*
X744470Y258656D01*
X744278Y258346D01*
X743933Y258191D01*
X743013D01*
G01X746037Y259999D02*
Y257777D01*
X746190Y257312D01*
X746497Y257002D01*
X746880Y256899D01*
X747263Y257002D01*
X747570Y257312D01*
X747723Y257777D01*
Y259999D01*
G01X749252Y259482D02*
X749482Y259792D01*
X749750Y259947D01*
X750057Y259999D01*
X750440Y259896D01*
X750708Y259637D01*
X750785Y259327D01*
X750747Y259017D01*
X750593Y258759D01*
X749827Y258242D01*
X749482Y257881D01*
X749252Y257364D01*
X749175Y256899D01*
X750785D01*
G01X752428Y257261D02*
X752697Y257002D01*
X753003Y256899D01*
X753310Y257002D01*
X753578Y257312D01*
X753770Y257777D01*
X753847Y258242D01*
Y258811D01*
X753770Y259276D01*
X753578Y259689D01*
X753348Y259896D01*
X753080Y259999D01*
X752773Y259896D01*
X752543Y259689D01*
X752390Y259379D01*
X752313Y258966D01*
X752390Y258604D01*
X752582Y258242D01*
X752812Y258036D01*
X753080Y257984D01*
X753387Y258087D01*
X753617Y258346D01*
X753847Y258811D01*
G01X755337Y257519D02*
X755567Y257157D01*
X755873Y256951D01*
X756218Y256899D01*
X756525Y256951D01*
X756832Y257209D01*
X757023Y257519D01*
X757062Y257829D01*
X756985Y258191D01*
X756717Y258449D01*
X756448Y258552D01*
X756103D01*
G01X756448D02*
X756678Y258707D01*
X756870Y258966D01*
X756947Y259276D01*
X756870Y259586D01*
X756678Y259844D01*
X756333Y259999D01*
X755988Y259947D01*
X755643Y259741D01*
G01X729820Y385462D02*
Y379262D01*
G01X731620D02*
Y385462D01*
G01X734820Y379262D02*
X731620D01*
G01X734820Y385462D02*
Y379262D01*
G01X741800Y372825D02*
Y366625D01*
G01X738600Y372825D02*
X741800D01*
G01X738600Y366625D02*
Y372825D01*
G01X741800Y366625D02*
X738600D01*
G01X734200D02*
Y372825D01*
X737400D01*
Y366625D01*
X734200D01*
G01X729800D02*
Y372825D01*
X733000D01*
Y366625D01*
X729800D01*
G01X736620Y395462D02*
X739820D01*
G01X736620Y389262D02*
Y395462D01*
G01X739820Y389262D02*
X736620D01*
G01X739820Y395462D02*
Y389262D01*
G01X729820Y395462D02*
Y389262D01*
G01X731620Y395462D02*
X734820D01*
G01X731620Y389262D02*
Y395462D01*
G01X734820Y389262D02*
X731620D01*
G01X734820Y395462D02*
Y389262D01*
G01X731620Y385462D02*
X734820D01*
G01X740377Y408958D02*
Y483762D01*
G01X743620Y509762D02*
Y515962D01*
G01X746820Y509762D02*
X743620D01*
G01X733620D02*
Y515962D01*
G01X736820Y509762D02*
X733620D01*
G01X736820Y515962D02*
Y509762D01*
G01X730820Y515962D02*
Y509762D01*
G01Y502962D02*
Y496762D01*
G01X746820D02*
X743620D01*
G01Y502962D02*
X746820D01*
G01X743620Y496762D02*
Y502962D01*
G01X733573Y523237D02*
Y529437D01*
G01X736773Y523237D02*
X733573D01*
G01X736773Y529437D02*
Y523237D01*
G01X743620Y515962D02*
X746820D01*
G01X733620D02*
X736820D01*
G01X746820Y523262D02*
X743620D01*
G01D02*
Y529462D01*
G01X733573Y529437D02*
X736773D01*
G01X743620Y529462D02*
X746820D01*
G01X786501Y605413D02*
G03I-22900J0D01*
G01X739325Y697211D02*
X752050D01*
G01X739325Y1335007D02*
Y697211D01*
G01X735215D02*
Y1335007D01*
G01X764915Y732644D02*
X739325D01*
G01X764915Y1299574D02*
X739325D01*
G01X730160Y1377085D02*
Y1337715D01*
G01X740763Y1337146D02*
X740955Y1336836D01*
X741185Y1336629D01*
X741453Y1336526D01*
X741760Y1336629D01*
X741990Y1336836D01*
X742220Y1337146D01*
X742297Y1337559D01*
Y1339626D01*
G01X743787Y1337146D02*
X744017Y1336784D01*
X744323Y1336578D01*
X744668Y1336526D01*
X744975Y1336578D01*
X745282Y1336836D01*
X745473Y1337146D01*
X745512Y1337456D01*
X745435Y1337818D01*
X745167Y1338076D01*
X744898Y1338179D01*
X744553D01*
G01X744898D02*
X745128Y1338334D01*
X745320Y1338593D01*
X745397Y1338903D01*
X745320Y1339213D01*
X745128Y1339471D01*
X744783Y1339626D01*
X744438Y1339574D01*
X744093Y1339368D01*
G01X747730Y1339626D02*
X747423Y1339523D01*
X747193Y1339264D01*
X747040Y1338954D01*
X746925Y1338541D01*
X746887Y1338076D01*
X746925Y1337611D01*
X747040Y1337198D01*
X747193Y1336888D01*
X747423Y1336629D01*
X747730Y1336526D01*
X748037Y1336629D01*
X748267Y1336888D01*
X748420Y1337198D01*
X748535Y1337611D01*
X748573Y1338076D01*
X748535Y1338541D01*
X748420Y1338954D01*
X748267Y1339264D01*
X748037Y1339523D01*
X747730Y1339626D01*
G01X764915Y1335007D02*
X739325D01*
G01X731443Y1337206D02*
X731635Y1336896D01*
X731865Y1336689D01*
X732133Y1336586D01*
X732440Y1336689D01*
X732670Y1336896D01*
X732900Y1337206D01*
X732977Y1337619D01*
Y1339686D01*
G01X734582Y1339169D02*
X734812Y1339479D01*
X735080Y1339634D01*
X735387Y1339686D01*
X735770Y1339583D01*
X736038Y1339324D01*
X736115Y1339014D01*
X736077Y1338704D01*
X735923Y1338446D01*
X735157Y1337929D01*
X734812Y1337568D01*
X734582Y1337051D01*
X734505Y1336586D01*
X736115D01*
G01X738333D02*
X738410Y1337258D01*
X738525Y1337826D01*
X738678Y1338343D01*
X738870Y1338911D01*
X739177Y1339686D01*
X737643D01*
G01X732303Y1368662D02*
Y1371762D01*
X733223D01*
X733530Y1371607D01*
X733760Y1371245D01*
X733837Y1370832D01*
X733760Y1370419D01*
X733568Y1370109D01*
X733223Y1369954D01*
X732303D01*
G01X735403Y1371762D02*
Y1368662D01*
X736937D01*
G01X739270D02*
Y1371762D01*
X738810Y1371142D01*
G01Y1368662D02*
X739730D01*
G01X741642Y1371245D02*
X741872Y1371555D01*
X742140Y1371710D01*
X742447Y1371762D01*
X742830Y1371659D01*
X743098Y1371400D01*
X743175Y1371090D01*
X743137Y1370780D01*
X742983Y1370522D01*
X742217Y1370005D01*
X741872Y1369644D01*
X741642Y1369127D01*
X741565Y1368662D01*
X743175D01*
G01X731360Y1404205D02*
X743360D01*
G01X731360Y1398205D02*
Y1404205D01*
G01X743360Y1398205D02*
X731360D01*
G01X743360Y1404205D02*
Y1398205D01*
G01X732406Y1395424D02*
X735606D01*
G01X732406Y1389224D02*
Y1395424D01*
G01X735606Y1389224D02*
X732406D01*
G01X735606Y1395424D02*
Y1389224D01*
G01X731309Y1395424D02*
Y1389224D01*
G01X729710Y1421365D02*
X741710D01*
G01X729710Y1415365D02*
Y1421365D01*
G01X741710Y1415365D02*
X729710D01*
G01X741710Y1421365D02*
Y1415365D01*
G01X729700Y1413025D02*
X741700D01*
G01X729700Y1407025D02*
Y1413025D01*
G01X741700Y1407025D02*
X729700D01*
G01X741700Y1413025D02*
Y1407025D01*
G01X730423Y1430592D02*
Y1433692D01*
X731343D01*
X731650Y1433537D01*
X731880Y1433175D01*
X731957Y1432762D01*
X731880Y1432349D01*
X731688Y1432039D01*
X731343Y1431884D01*
X730423D01*
G01X733447Y1433692D02*
Y1431470D01*
X733600Y1431005D01*
X733907Y1430695D01*
X734290Y1430592D01*
X734673Y1430695D01*
X734980Y1431005D01*
X735133Y1431470D01*
Y1433692D01*
G01X737313Y1430592D02*
X737390Y1431264D01*
X737505Y1431832D01*
X737658Y1432349D01*
X737850Y1432917D01*
X738157Y1433692D01*
X736623D01*
G01X740413Y1430592D02*
X740490Y1431264D01*
X740605Y1431832D01*
X740758Y1432349D01*
X740950Y1432917D01*
X741257Y1433692D01*
X739723D01*
G01X742440Y1429559D02*
X744740D01*
G01X745923Y1430592D02*
Y1433692D01*
X746843D01*
X747150Y1433537D01*
X747380Y1433175D01*
X747457Y1432762D01*
X747380Y1432349D01*
X747188Y1432039D01*
X746843Y1431884D01*
X745923D01*
G01X749790Y1430592D02*
Y1433692D01*
X749330Y1433072D01*
G01Y1430592D02*
X750250D01*
G01X751740Y1429559D02*
X754040D01*
G01X755147Y1431212D02*
X755377Y1430850D01*
X755683Y1430644D01*
X756028Y1430592D01*
X756335Y1430644D01*
X756642Y1430902D01*
X756833Y1431212D01*
X756872Y1431522D01*
X756795Y1431884D01*
X756527Y1432142D01*
X756258Y1432245D01*
X755913D01*
G01X756258D02*
X756488Y1432400D01*
X756680Y1432659D01*
X756757Y1432969D01*
X756680Y1433279D01*
X756488Y1433537D01*
X756143Y1433692D01*
X755798Y1433640D01*
X755453Y1433434D01*
G01X731352Y1571093D02*
Y1567893D01*
G01X732453Y1616103D02*
Y1612903D01*
G01X732352Y1611493D02*
Y1608293D01*
G01X740947Y1616433D02*
Y1619533D01*
X741867D01*
X742174Y1619378D01*
X742404Y1619016D01*
X742481Y1618603D01*
X742404Y1618190D01*
X742212Y1617880D01*
X741867Y1617725D01*
X740947D01*
G01X743971Y1619533D02*
Y1617311D01*
X744124Y1616846D01*
X744431Y1616536D01*
X744814Y1616433D01*
X745197Y1616536D01*
X745504Y1616846D01*
X745657Y1617311D01*
Y1619533D01*
G01X747186Y1619016D02*
X747416Y1619326D01*
X747684Y1619481D01*
X747991Y1619533D01*
X748374Y1619430D01*
X748642Y1619171D01*
X748719Y1618861D01*
X748681Y1618551D01*
X748527Y1618293D01*
X747761Y1617776D01*
X747416Y1617415D01*
X747186Y1616898D01*
X747109Y1616433D01*
X748719D01*
G01X751014D02*
X751282Y1616485D01*
X751589Y1616640D01*
X751781Y1616898D01*
X751857Y1617260D01*
X751781Y1617621D01*
X751551Y1617931D01*
X751206Y1618086D01*
X750822D01*
X750592Y1618190D01*
X750401Y1618448D01*
X750324Y1618810D01*
X750439Y1619171D01*
X750707Y1619430D01*
X751014Y1619533D01*
X751321Y1619430D01*
X751589Y1619171D01*
X751704Y1618810D01*
X751627Y1618448D01*
X751436Y1618190D01*
X751206Y1618086D01*
X750822D01*
X750477Y1617931D01*
X750247Y1617621D01*
X750171Y1617260D01*
X750247Y1616898D01*
X750439Y1616640D01*
X750746Y1616485D01*
X751014Y1616433D01*
G01X753462Y1616795D02*
X753731Y1616536D01*
X754037Y1616433D01*
X754344Y1616536D01*
X754612Y1616846D01*
X754804Y1617311D01*
X754881Y1617776D01*
Y1618345D01*
X754804Y1618810D01*
X754612Y1619223D01*
X754382Y1619430D01*
X754114Y1619533D01*
X753807Y1619430D01*
X753577Y1619223D01*
X753424Y1618913D01*
X753347Y1618500D01*
X753424Y1618138D01*
X753616Y1617776D01*
X753846Y1617570D01*
X754114Y1617518D01*
X754421Y1617621D01*
X754651Y1617880D01*
X754881Y1618345D01*
G01X729080Y1642840D02*
Y1649040D01*
X732280D01*
Y1642840D01*
X729080D01*
G01X730620Y1655727D02*
X732842D01*
X733307Y1655880D01*
X733617Y1656187D01*
X733720Y1656570D01*
X733617Y1656953D01*
X733307Y1657260D01*
X732842Y1657413D01*
X730620D01*
G01X733100Y1658827D02*
X733462Y1659057D01*
X733668Y1659363D01*
X733720Y1659708D01*
X733668Y1660015D01*
X733410Y1660322D01*
X733100Y1660513D01*
X732790Y1660552D01*
X732428Y1660475D01*
X732170Y1660207D01*
X732067Y1659938D01*
Y1659593D01*
G01Y1659938D02*
X731912Y1660168D01*
X731653Y1660360D01*
X731343Y1660437D01*
X731033Y1660360D01*
X730775Y1660168D01*
X730620Y1659823D01*
X730672Y1659478D01*
X730878Y1659133D01*
G01X733720Y1663230D02*
X730620D01*
X732842Y1661812D01*
Y1663728D01*
G01X733100Y1665027D02*
X733462Y1665257D01*
X733668Y1665563D01*
X733720Y1665908D01*
X733668Y1666215D01*
X733410Y1666522D01*
X733100Y1666713D01*
X732790Y1666752D01*
X732428Y1666675D01*
X732170Y1666407D01*
X732067Y1666138D01*
Y1665793D01*
G01Y1666138D02*
X731912Y1666368D01*
X731653Y1666560D01*
X731343Y1666637D01*
X731033Y1666560D01*
X730775Y1666368D01*
X730620Y1666023D01*
X730672Y1665678D01*
X730878Y1665333D01*
G01X749755Y1680762D02*
X743555D01*
G01D02*
Y1683962D01*
G01X749755Y1676762D02*
X743555D01*
G01D02*
Y1679962D01*
G01D02*
X749755D01*
G01X743555Y1675962D02*
X749755D01*
G01Y1672762D02*
X743555D01*
G01D02*
Y1675962D01*
G01X741862Y1665645D02*
Y1671845D01*
G01D02*
X745062D01*
G01Y1665645D02*
X741862D01*
G01X741138Y1675855D02*
Y1669655D01*
G01D02*
X737938D01*
G01D02*
Y1675855D01*
G01D02*
X741138D01*
G01X743555Y1683962D02*
X749755D01*
G01X764654Y64567D02*
X753504D01*
G01X753991Y96864D02*
Y105052D01*
G01X755518Y87748D02*
Y90948D01*
G01X761718Y87748D02*
X755518D01*
G01Y90948D02*
X761718D01*
G01X758593Y97948D02*
X761793D01*
G01X758593Y91748D02*
Y97948D01*
G01X761793Y91748D02*
X758593D01*
G01X761793Y99128D02*
X758593D01*
G01D02*
Y105328D01*
G01X756233Y116888D02*
Y113688D01*
G01X750033Y116888D02*
X756233D01*
G01X750033Y113688D02*
Y116888D01*
G01X756233Y113688D02*
X750033D01*
G01Y109688D02*
Y112888D01*
G01X756233Y109688D02*
X750033D01*
G01X756233Y112888D02*
Y109688D01*
G01X750033Y112888D02*
X756233D01*
G01X756235Y120772D02*
Y117572D01*
G01X750035D02*
Y120772D01*
G01X756235Y117572D02*
X750035D01*
G01X758593Y105328D02*
X761793D01*
G01X757452Y136867D02*
X757145Y136919D01*
X756877Y137125D01*
X756647Y137435D01*
X756494Y137797D01*
X756417Y138210D01*
Y138624D01*
X756494Y139037D01*
X756647Y139399D01*
X756877Y139709D01*
X757145Y139915D01*
X757452Y139967D01*
X757759Y139915D01*
X758027Y139709D01*
X758257Y139399D01*
X758410Y139037D01*
X758487Y138624D01*
Y138210D01*
X758410Y137797D01*
X758257Y137435D01*
X758027Y137125D01*
X757759Y136919D01*
X757452Y136867D01*
G01X757759Y137694D02*
X758219Y136867D01*
G01X759709Y137487D02*
X759939Y137125D01*
X760245Y136919D01*
X760590Y136867D01*
X760897Y136919D01*
X761204Y137177D01*
X761395Y137487D01*
X761434Y137797D01*
X761357Y138159D01*
X761089Y138417D01*
X760820Y138520D01*
X760475D01*
G01X760820D02*
X761050Y138675D01*
X761242Y138934D01*
X761319Y139244D01*
X761242Y139554D01*
X761050Y139812D01*
X760705Y139967D01*
X760360Y139915D01*
X760015Y139709D01*
G01X763000Y137229D02*
X763269Y136970D01*
X763575Y136867D01*
X763882Y136970D01*
X764150Y137280D01*
X764342Y137745D01*
X764419Y138210D01*
Y138779D01*
X764342Y139244D01*
X764150Y139657D01*
X763920Y139864D01*
X763652Y139967D01*
X763345Y139864D01*
X763115Y139657D01*
X762962Y139347D01*
X762885Y138934D01*
X762962Y138572D01*
X763154Y138210D01*
X763384Y138004D01*
X763652Y137952D01*
X763959Y138055D01*
X764189Y138314D01*
X764419Y138779D01*
G01X761085Y122482D02*
Y130356D01*
G01X753726Y126219D02*
X754826D01*
G01X750726D02*
X749726D01*
G01X753726Y124719D02*
X750726Y126219D01*
G01X753726Y127719D02*
Y124719D01*
G01X750726Y126219D02*
X753726Y127719D01*
G01X750726Y124719D02*
Y127719D01*
G01X750035Y120772D02*
X756235D01*
G01X757123Y141063D02*
Y153687D01*
G01X768935Y141063D02*
X757123D01*
G01X750335Y143650D02*
Y140450D01*
G01X750345Y139464D02*
Y136264D01*
G01X759738Y165746D02*
Y174408D01*
G01X763085Y165746D02*
X759738D01*
G01X757123Y153687D02*
X768935D01*
G01X746600Y165937D02*
Y169137D01*
G01X752800Y165937D02*
X746600D01*
G01X752800Y169137D02*
Y165937D01*
G01X746245Y174904D02*
X745938Y174956D01*
X745670Y175162D01*
X745440Y175472D01*
X745287Y175834D01*
X745210Y176247D01*
Y176661D01*
X745287Y177074D01*
X745440Y177436D01*
X745670Y177746D01*
X745938Y177952D01*
X746245Y178004D01*
X746552Y177952D01*
X746820Y177746D01*
X747050Y177436D01*
X747203Y177074D01*
X747280Y176661D01*
Y176247D01*
X747203Y175834D01*
X747050Y175472D01*
X746820Y175162D01*
X746552Y174956D01*
X746245Y174904D01*
G01X746552Y175731D02*
X747012Y174904D01*
G01X749345D02*
Y178004D01*
X748885Y177384D01*
G01Y174904D02*
X749805D01*
G01X751717Y177487D02*
X751947Y177797D01*
X752215Y177952D01*
X752522Y178004D01*
X752905Y177901D01*
X753173Y177642D01*
X753250Y177332D01*
X753212Y177022D01*
X753058Y176764D01*
X752292Y176247D01*
X751947Y175886D01*
X751717Y175369D01*
X751640Y174904D01*
X753250D01*
G01X754702Y175369D02*
X754932Y175111D01*
X755200Y174956D01*
X755545Y174904D01*
X755890Y175007D01*
X756158Y175214D01*
X756350Y175576D01*
X756388Y175989D01*
X756312Y176402D01*
X756120Y176661D01*
X755852Y176867D01*
X755583Y176919D01*
X755315Y176867D01*
X754970Y176661D01*
X755085Y178004D01*
X756120D01*
G01X759738Y174408D02*
X770232D01*
G01X746600Y169137D02*
X752800D01*
G01X752760Y266922D02*
Y263722D01*
G01X746560D02*
Y266922D01*
G01X752760Y263722D02*
X746560D01*
G01X752760Y270922D02*
Y267722D01*
G01X746560Y270922D02*
X752760D01*
G01X746560Y267722D02*
Y270922D01*
G01X752760Y267722D02*
X746560D01*
G01X759273Y278203D02*
X771047D01*
G01X759273Y268441D02*
Y278203D01*
G01X771047Y268441D02*
X759273D01*
G01X746560Y266922D02*
X752760D01*
G01X746560Y274722D02*
Y277922D01*
G01X752760Y274722D02*
X746560D01*
G01X752760Y277922D02*
Y274722D01*
G01X746560Y277922D02*
X752760D01*
G01X759120Y391612D02*
Y394812D01*
G01X765320Y391612D02*
X759120D01*
G01Y394812D02*
X765320D01*
G01X759120Y411612D02*
Y414812D01*
G01X765320Y411612D02*
X759120D01*
G01Y404812D02*
X765320D01*
G01X759120Y401612D02*
Y404812D01*
G01X765320Y401612D02*
X759120D01*
G01Y409812D02*
X765320D01*
G01X759120Y406612D02*
Y409812D01*
G01X765320Y406612D02*
X759120D01*
G01Y399812D02*
X765320D01*
G01X759120Y396612D02*
Y399812D01*
G01X765320Y396612D02*
X759120D01*
G01Y414812D02*
X765320D01*
G01X759120Y416612D02*
Y419812D01*
G01X765320Y416612D02*
X759120D01*
G01Y419812D02*
X765320D01*
G01X759120Y421612D02*
Y424812D01*
G01X765320Y421612D02*
X759120D01*
G01Y424812D02*
X765320D01*
G01X759120Y426612D02*
Y429812D01*
G01X765320Y426612D02*
X759120D01*
G01X759907Y433472D02*
X759600Y433524D01*
X759332Y433730D01*
X759102Y434040D01*
X758949Y434402D01*
X758872Y434815D01*
Y435229D01*
X758949Y435642D01*
X759102Y436004D01*
X759332Y436314D01*
X759600Y436520D01*
X759907Y436572D01*
X760214Y436520D01*
X760482Y436314D01*
X760712Y436004D01*
X760865Y435642D01*
X760942Y435229D01*
Y434815D01*
X760865Y434402D01*
X760712Y434040D01*
X760482Y433730D01*
X760214Y433524D01*
X759907Y433472D01*
G01X762202Y433885D02*
X762509Y433627D01*
X762854Y433472D01*
X763160D01*
X763467Y433627D01*
X763697Y433885D01*
X763812Y434247D01*
X763735Y434609D01*
X763544Y434919D01*
X763199Y435125D01*
X762739Y435229D01*
X762470Y435435D01*
X762355Y435797D01*
X762432Y436159D01*
X762624Y436417D01*
X762892Y436572D01*
X763160D01*
X763429Y436469D01*
X763659Y436210D01*
G01X766950Y436314D02*
X766720Y436469D01*
X766452Y436572D01*
X766145D01*
X765800Y436417D01*
X765532Y436159D01*
X765340Y435849D01*
X765187Y435332D01*
X765149Y434867D01*
X765225Y434402D01*
X765340Y434092D01*
X765570Y433782D01*
X765839Y433575D01*
X766107Y433472D01*
X766375D01*
X766644Y433575D01*
X766874Y433730D01*
X767065Y433937D01*
G01X768479Y436055D02*
X768709Y436365D01*
X768977Y436520D01*
X769284Y436572D01*
X769667Y436469D01*
X769935Y436210D01*
X770012Y435900D01*
X769974Y435590D01*
X769820Y435332D01*
X769054Y434815D01*
X768709Y434454D01*
X768479Y433937D01*
X768402Y433472D01*
X770012D01*
G01X759820Y440262D02*
X756620D01*
G01X759820Y446462D02*
Y440262D01*
G01X756620D02*
Y446462D01*
G01X759120Y429812D02*
X765320D01*
G01X756620Y446462D02*
X759820D01*
G01X758240Y461462D02*
X764440D01*
G01X758240Y458262D02*
Y461462D01*
G01X764440Y458262D02*
X758240D01*
G01Y456462D02*
X764440D01*
G01X758240Y453262D02*
Y456462D01*
G01X764440Y453262D02*
X758240D01*
G01Y463262D02*
Y466462D01*
G01X764440Y463262D02*
X758240D01*
G01Y466462D02*
X764440D01*
G01X758240Y468262D02*
Y471462D01*
G01X764440Y468262D02*
X758240D01*
G01Y471462D02*
X764440D01*
G01X758240Y476462D02*
X764440D01*
G01X758240Y473262D02*
Y476462D01*
G01X764440Y473262D02*
X758240D01*
G01Y487262D02*
Y490462D01*
G01X764440Y487262D02*
X758240D01*
G01Y490462D02*
X764440D01*
G01X758300Y491852D02*
Y495052D01*
G01X764500Y491852D02*
X758300D01*
G01X758240Y482262D02*
Y485462D01*
G01X764440Y482262D02*
X758240D01*
G01Y485462D02*
X764440D01*
G01X758240Y478262D02*
Y481462D01*
G01X764440Y478262D02*
X758240D01*
G01Y481462D02*
X764440D01*
G01X758250Y496059D02*
Y499259D01*
G01X764450Y496059D02*
X758250D01*
G01Y499259D02*
X764450D01*
G01X758300Y495052D02*
X764500D01*
G01X746820Y515962D02*
Y509762D01*
G01Y502962D02*
Y496762D01*
G01X754689Y502977D02*
Y496777D01*
X751489D01*
Y502977D01*
X754689D01*
G01X750779Y502957D02*
Y496757D01*
X747579D01*
Y502957D01*
X750779D01*
G01X760100Y510362D02*
Y516562D01*
X763300D01*
Y510362D01*
X760100D01*
G01X746820Y529462D02*
Y523262D01*
G01X752820D02*
X749620D01*
G01X752820Y529462D02*
Y523262D01*
G01X749620D02*
Y529462D01*
G01D02*
X752820D01*
G01X759510Y697211D02*
X764915D01*
G01X760520Y1381562D02*
X766720D01*
G01X760520Y1378362D02*
Y1381562D01*
G01X766720Y1378362D02*
X760520D01*
G01Y1377062D02*
X766720D01*
G01X760520Y1373862D02*
Y1377062D01*
G01X766720Y1373862D02*
X760520D01*
G01X760420Y1386962D02*
Y1390162D01*
G01X766620Y1386962D02*
X760420D01*
G01Y1385662D02*
X766620D01*
G01X760420Y1382462D02*
Y1385662D01*
G01X766620Y1382462D02*
X760420D01*
G01Y1404462D02*
Y1407662D01*
G01X766620Y1404462D02*
X760420D01*
G01Y1403162D02*
X766620D01*
G01X760420Y1399962D02*
Y1403162D01*
G01X766620Y1399962D02*
X760420D01*
G01Y1391162D02*
Y1394362D01*
G01X766620Y1391162D02*
X760420D01*
G01Y1394362D02*
X766620D01*
G01X760420Y1398862D02*
X766620D01*
G01X760420Y1395662D02*
Y1398862D01*
G01X766620Y1395662D02*
X760420D01*
G01Y1390162D02*
X766620D01*
G01X760420Y1407662D02*
X766620D01*
G01X760320Y1408662D02*
Y1411862D01*
G01X766520Y1408662D02*
X760320D01*
G01Y1411862D02*
X766520D01*
G01X760320Y1416362D02*
X766520D01*
G01X760320Y1413162D02*
Y1416362D01*
G01X766520Y1413162D02*
X760320D01*
G01X753012Y1577583D02*
Y1580783D01*
G01X759212Y1577583D02*
X753012D01*
G01X759212Y1580783D02*
Y1577583D01*
G01X753012Y1580783D02*
X759212D01*
G01Y1584783D02*
Y1581583D01*
G01X753012D02*
Y1584783D01*
G01X759212Y1581583D02*
X753012D01*
G01X745991Y1575412D02*
Y1595630D01*
G01X753012Y1588783D02*
X759212D01*
G01X753012Y1585583D02*
Y1588783D01*
G01X759212Y1585583D02*
X753012D01*
G01X759212Y1588783D02*
Y1585583D01*
G01X753012Y1584783D02*
X759212D01*
G01X753012Y1590583D02*
Y1593783D01*
G01X759212Y1590583D02*
X753012D01*
G01X759212Y1593783D02*
Y1590583D01*
G01X753012Y1593783D02*
X759212D01*
G01X753747Y1669355D02*
Y1667133D01*
X753900Y1666668D01*
X754207Y1666358D01*
X754590Y1666255D01*
X754973Y1666358D01*
X755280Y1666668D01*
X755433Y1667133D01*
Y1669355D01*
G01X756962Y1668838D02*
X757192Y1669148D01*
X757460Y1669303D01*
X757767Y1669355D01*
X758150Y1669252D01*
X758418Y1668993D01*
X758495Y1668683D01*
X758457Y1668373D01*
X758303Y1668115D01*
X757537Y1667598D01*
X757192Y1667237D01*
X756962Y1666720D01*
X756885Y1666255D01*
X758495D01*
G01X760138Y1666617D02*
X760407Y1666358D01*
X760713Y1666255D01*
X761020Y1666358D01*
X761288Y1666668D01*
X761480Y1667133D01*
X761557Y1667598D01*
Y1668167D01*
X761480Y1668632D01*
X761288Y1669045D01*
X761058Y1669252D01*
X760790Y1669355D01*
X760483Y1669252D01*
X760253Y1669045D01*
X760100Y1668735D01*
X760023Y1668322D01*
X760100Y1667960D01*
X760292Y1667598D01*
X760522Y1667392D01*
X760790Y1667340D01*
X761097Y1667443D01*
X761327Y1667702D01*
X761557Y1668167D01*
G01X763890Y1669355D02*
X763583Y1669252D01*
X763353Y1668993D01*
X763200Y1668683D01*
X763085Y1668270D01*
X763047Y1667805D01*
X763085Y1667340D01*
X763200Y1666927D01*
X763353Y1666617D01*
X763583Y1666358D01*
X763890Y1666255D01*
X764197Y1666358D01*
X764427Y1666617D01*
X764580Y1666927D01*
X764695Y1667340D01*
X764733Y1667805D01*
X764695Y1668270D01*
X764580Y1668683D01*
X764427Y1668993D01*
X764197Y1669252D01*
X763890Y1669355D01*
G01X753130Y1672657D02*
Y1684469D01*
G01X765754Y1672657D02*
X753130D01*
G01X749755Y1683962D02*
Y1680762D01*
G01Y1679962D02*
Y1676762D01*
G01Y1675962D02*
Y1672762D01*
G01X745062Y1671845D02*
Y1665645D01*
G01X753130Y1684469D02*
X765754D01*
G01X765315Y1696921D02*
X759115D01*
G01D02*
Y1700121D01*
G01X757459Y1693695D02*
Y1687495D01*
G01D02*
X754259D01*
G01D02*
Y1693695D01*
G01D02*
X757459D01*
G01X758259D02*
X761459D01*
G01Y1687495D02*
X758259D01*
G01D02*
Y1693695D01*
G01X752171Y1715364D02*
Y1701716D01*
G01D02*
X764375D01*
G01X759115Y1700121D02*
X765315D01*
G01X764375Y1715364D02*
X752171D01*
G01X760959Y1728195D02*
Y1721995D01*
G01D02*
X757759D01*
G01D02*
Y1728195D01*
G01D02*
X760959D01*
G01X756959D02*
Y1721995D01*
G01D02*
X753759D01*
G01D02*
Y1728195D01*
G01D02*
X756959D01*
G01X772170Y79638D02*
X769930D01*
G01X771143Y78013D02*
Y81263D01*
G01X768529Y84986D02*
Y73490D01*
G01X761718Y90948D02*
Y87748D01*
G01X761793Y97948D02*
Y91748D01*
G01Y105328D02*
Y99128D01*
G01X765730Y117780D02*
Y111580D01*
X762530D01*
Y117780D01*
X765730D01*
G01X766287Y125602D02*
X764047D01*
G01X765260Y123977D02*
Y127227D01*
G01X768935Y153687D02*
Y141063D01*
G01X773203Y152128D02*
Y155328D01*
G01X779403Y152128D02*
X773203D01*
G01X770232Y174408D02*
Y165746D01*
G01X764985Y167946D02*
X763085Y165746D01*
G01X766885D02*
X764985Y167946D01*
G01X770232Y165746D02*
X766885D01*
G01X773189Y156426D02*
Y159626D01*
G01X779389Y156426D02*
X773189D01*
G01Y159626D02*
X779389D01*
G01X773203Y155328D02*
X779403D01*
G01X773320Y164854D02*
X779520D01*
G01X773320Y161654D02*
Y164854D01*
G01X779520Y161654D02*
X773320D01*
G01X767850Y262792D02*
Y250792D01*
G01X761850Y262792D02*
X767850D01*
G01X761850Y250792D02*
Y262792D01*
G01X767850Y250792D02*
X761850D01*
G01X766760Y279722D02*
X763560D01*
G01X766760Y285922D02*
Y279722D01*
G01X763560D02*
Y285922D01*
G01X771047Y278203D02*
Y268441D01*
G01X763560Y285922D02*
X766760D01*
G01X775942Y297679D02*
Y300879D01*
G01X782142Y297679D02*
X775942D01*
G01X762142D02*
Y300879D01*
G01X768342Y297679D02*
X762142D01*
G01X768342Y300879D02*
Y297679D01*
G01X762043Y309649D02*
Y312849D01*
G01X768243Y309649D02*
X762043D01*
G01X768243Y312849D02*
Y309649D01*
G01X762043Y312849D02*
X768243D01*
G01X775942Y300879D02*
X782142D01*
G01X762142D02*
X768342D01*
G01X771341Y310355D02*
X777541D01*
G01X771341Y307155D02*
Y310355D01*
G01X777541Y307155D02*
X771341D01*
G01X771426Y305010D02*
X777626D01*
G01X771426Y301810D02*
Y305010D01*
G01X777626Y301810D02*
X771426D01*
G01X761570Y315832D02*
Y319032D01*
G01X767770Y315832D02*
X761570D01*
G01X767770Y319032D02*
Y315832D01*
G01X761570Y319032D02*
X767770D01*
G01X764703Y321392D02*
X766943D01*
G01X765730Y323017D02*
Y319767D01*
G01X769137Y320892D02*
Y323992D01*
X769903D01*
X770210Y323837D01*
X770440Y323630D01*
X770632Y323320D01*
X770785Y322959D01*
X770823Y322442D01*
X770785Y321925D01*
X770632Y321564D01*
X770440Y321254D01*
X770210Y321047D01*
X769903Y320892D01*
X769137D01*
G01X772352Y322184D02*
X772620Y322545D01*
X772850Y322752D01*
X773157Y322855D01*
X773425Y322752D01*
X773617Y322545D01*
X773770Y322235D01*
X773808Y321874D01*
X773770Y321564D01*
X773617Y321254D01*
X773387Y320995D01*
X773118Y320892D01*
X772812Y320995D01*
X772543Y321305D01*
X772390Y321770D01*
X772352Y322287D01*
X772428Y322959D01*
X772543Y323320D01*
X772735Y323682D01*
X773003Y323940D01*
X773272Y323992D01*
X773540Y323889D01*
X773732Y323630D01*
G01X769130Y319592D02*
X779530D01*
Y315192D01*
X769130D01*
Y319592D01*
G01X774400Y362262D02*
Y368462D01*
X777600D01*
Y362262D01*
X774400D01*
G01X762400D02*
Y368462D01*
X765600D01*
Y362262D01*
X762400D01*
G01X770360Y362382D02*
Y368582D01*
X773560D01*
Y362382D01*
X770360D01*
G01X766360D02*
Y368582D01*
X769560D01*
Y362382D01*
X766360D01*
G01X774120Y394812D02*
X780320D01*
G01X774120Y391612D02*
Y394812D01*
G01X780320Y391612D02*
X774120D01*
G01X765320Y394812D02*
Y391612D01*
G01X774120Y411612D02*
Y414812D01*
G01X780320Y411612D02*
X774120D01*
G01Y406612D02*
Y409812D01*
G01X780320Y406612D02*
X774120D01*
G01Y409812D02*
X780320D01*
G01X774120Y401612D02*
Y404812D01*
G01X780320Y401612D02*
X774120D01*
G01Y404812D02*
X780320D01*
G01X765320Y414812D02*
Y411612D01*
G01Y404812D02*
Y401612D01*
G01Y409812D02*
Y406612D01*
G01X774120Y396612D02*
Y399812D01*
G01X780320Y396612D02*
X774120D01*
G01Y399812D02*
X780320D01*
G01X765320D02*
Y396612D01*
G01X774120Y414812D02*
X780320D01*
G01X774120Y416612D02*
Y419812D01*
G01X780320Y416612D02*
X774120D01*
G01Y419812D02*
X780320D01*
G01X774120Y421612D02*
Y424812D01*
G01X780320Y421612D02*
X774120D01*
G01Y424812D02*
X780320D01*
G01X765320Y419812D02*
Y416612D01*
G01Y424812D02*
Y421612D01*
G01Y429812D02*
Y426612D01*
G01X775620Y442962D02*
X778820D01*
G01X775620Y436762D02*
Y442962D01*
G01X778820Y436762D02*
X775620D01*
G01X761421Y438244D02*
Y448480D01*
G01X774019Y438244D02*
X761421D01*
G01X774019Y448480D02*
Y438244D01*
G01X778820Y443762D02*
X775620D01*
G01D02*
Y449962D01*
G01X761421Y448480D02*
X774019D01*
G01X775620Y449962D02*
X778820D01*
G01X773240Y456462D02*
X779440D01*
G01X773240Y453262D02*
Y456462D01*
G01X779440Y453262D02*
X773240D01*
G01Y461462D02*
X779440D01*
G01X773240Y458262D02*
Y461462D01*
G01X779440Y458262D02*
X773240D01*
G01X764440Y461462D02*
Y458262D01*
G01Y456462D02*
Y453262D01*
G01X773240Y463262D02*
Y466462D01*
G01X779440Y463262D02*
X773240D01*
G01Y466462D02*
X779440D01*
G01X773240Y468262D02*
Y471462D01*
G01X779440Y468262D02*
X773240D01*
G01Y471462D02*
X779440D01*
G01X764440Y466462D02*
Y463262D01*
G01Y471462D02*
Y468262D01*
G01Y476462D02*
Y473262D01*
G01Y490462D02*
Y487262D01*
G01X764500Y495052D02*
Y491852D01*
G01X764440Y485462D02*
Y482262D01*
G01Y481462D02*
Y478262D01*
G01X773240Y487262D02*
Y490462D01*
G01X779440Y487262D02*
X773240D01*
G01Y490462D02*
X779440D01*
G01X764450Y499259D02*
Y496059D01*
G01X769306Y577473D02*
Y580573D01*
G01X770916D02*
Y577473D01*
G01Y579023D02*
X769306D01*
G01X773211Y577473D02*
Y580573D01*
X772751Y579953D01*
G01Y577473D02*
X773671D01*
G01X775583Y580056D02*
X775813Y580366D01*
X776081Y580521D01*
X776388Y580573D01*
X776771Y580470D01*
X777039Y580211D01*
X777116Y579901D01*
X777078Y579591D01*
X776924Y579333D01*
X776158Y578816D01*
X775813Y578455D01*
X775583Y577938D01*
X775506Y577473D01*
X777116D01*
G01X779871D02*
Y580573D01*
X778453Y578351D01*
X780369D01*
G01X769025Y699872D02*
Y697211D01*
G01Y1335007D02*
Y705172D01*
G01Y697211D02*
X794615D01*
G01X764915Y703192D02*
Y1335007D01*
G01Y697211D02*
Y698982D01*
G01X794615Y732644D02*
X769025D01*
G01X794615Y1299574D02*
X769025D01*
G01X767703Y1336996D02*
X767895Y1336686D01*
X768125Y1336479D01*
X768393Y1336376D01*
X768700Y1336479D01*
X768930Y1336686D01*
X769160Y1336996D01*
X769237Y1337409D01*
Y1339476D01*
G01X770842Y1338959D02*
X771072Y1339269D01*
X771340Y1339424D01*
X771647Y1339476D01*
X772030Y1339373D01*
X772298Y1339114D01*
X772375Y1338804D01*
X772337Y1338494D01*
X772183Y1338236D01*
X771417Y1337719D01*
X771072Y1337358D01*
X770842Y1336841D01*
X770765Y1336376D01*
X772375D01*
G01X774018Y1336738D02*
X774287Y1336479D01*
X774593Y1336376D01*
X774900Y1336479D01*
X775168Y1336789D01*
X775360Y1337254D01*
X775437Y1337719D01*
Y1338288D01*
X775360Y1338753D01*
X775168Y1339166D01*
X774938Y1339373D01*
X774670Y1339476D01*
X774363Y1339373D01*
X774133Y1339166D01*
X773980Y1338856D01*
X773903Y1338443D01*
X773980Y1338081D01*
X774172Y1337719D01*
X774402Y1337513D01*
X774670Y1337461D01*
X774977Y1337564D01*
X775207Y1337823D01*
X775437Y1338288D01*
G01X794615Y1335007D02*
X769025D01*
G01X766720Y1381562D02*
Y1378362D01*
G01Y1377062D02*
Y1373862D01*
G01X766620Y1390162D02*
Y1386962D01*
G01Y1385662D02*
Y1382462D01*
G01Y1407662D02*
Y1404462D01*
G01Y1403162D02*
Y1399962D01*
G01Y1394362D02*
Y1391162D01*
G01Y1398862D02*
Y1395662D01*
G01X766520Y1411862D02*
Y1408662D01*
G01Y1416362D02*
Y1413162D01*
G01X774552Y1582593D02*
X771352D01*
G01X774552Y1588793D02*
Y1582593D01*
G01X771352D02*
Y1588793D01*
G01X770239Y1572193D02*
X764039D01*
Y1575393D01*
X770239D01*
Y1572193D01*
G01X770252Y1583493D02*
Y1580293D01*
G01X764052Y1583493D02*
X770252D01*
G01X764052Y1580293D02*
Y1583493D01*
G01X770252Y1580293D02*
X764052D01*
G01X770252Y1579493D02*
Y1576293D01*
G01X764052Y1579493D02*
X770252D01*
G01X764052Y1576293D02*
Y1579493D01*
G01X770252Y1576293D02*
X764052D01*
G01X771352Y1588793D02*
X774552D01*
G01X770252Y1592493D02*
Y1589293D01*
G01X764052Y1592493D02*
X770252D01*
G01X764052Y1589293D02*
Y1592493D01*
G01X770252Y1589293D02*
X764052D01*
G01X770252Y1596493D02*
Y1593293D01*
G01X764052D02*
Y1596493D01*
G01X770252Y1593293D02*
X764052D01*
G01Y1596493D02*
X770252D01*
G01X765754Y1684469D02*
Y1672657D01*
G01X1086083Y1787213D02*
Y1668906D01*
X771477D01*
Y1787213D01*
X1086083D01*
G01X765315Y1700121D02*
Y1696921D01*
G01X765459Y1693695D02*
Y1687495D01*
G01D02*
X762259D01*
G01D02*
Y1693695D01*
G01D02*
X765459D01*
G01X761459D02*
Y1687495D01*
G01X766826Y1704067D02*
X769048D01*
X769513Y1704220D01*
X769823Y1704527D01*
X769926Y1704910D01*
X769823Y1705293D01*
X769513Y1705600D01*
X769048Y1705753D01*
X766826D01*
G01X767343Y1707282D02*
X767033Y1707512D01*
X766878Y1707780D01*
X766826Y1708087D01*
X766929Y1708470D01*
X767188Y1708738D01*
X767498Y1708815D01*
X767808Y1708777D01*
X768066Y1708623D01*
X768583Y1707857D01*
X768944Y1707512D01*
X769461Y1707282D01*
X769926Y1707205D01*
Y1708815D01*
G01Y1711033D02*
X769254Y1711110D01*
X768686Y1711225D01*
X768169Y1711378D01*
X767601Y1711570D01*
X766826Y1711877D01*
Y1710343D01*
G01X769926Y1714210D02*
X769874Y1714478D01*
X769719Y1714785D01*
X769461Y1714977D01*
X769099Y1715053D01*
X768738Y1714977D01*
X768428Y1714747D01*
X768273Y1714402D01*
Y1714018D01*
X768169Y1713788D01*
X767911Y1713597D01*
X767549Y1713520D01*
X767188Y1713635D01*
X766929Y1713903D01*
X766826Y1714210D01*
X766929Y1714517D01*
X767188Y1714785D01*
X767549Y1714900D01*
X767911Y1714823D01*
X768169Y1714632D01*
X768273Y1714402D01*
Y1714018D01*
X768428Y1713673D01*
X768738Y1713443D01*
X769099Y1713367D01*
X769461Y1713443D01*
X769719Y1713635D01*
X769874Y1713942D01*
X769926Y1714210D01*
G01X761773Y1708540D02*
X764375Y1711142D01*
G01D02*
Y1715364D01*
G01Y1701716D02*
Y1705938D01*
G01D02*
X761773Y1708540D01*
G01X764959Y1728195D02*
Y1721995D01*
G01D02*
X761759D01*
G01D02*
Y1728195D01*
G01D02*
X764959D01*
G01X783002Y108372D02*
Y111472D01*
G01X784612D02*
Y108372D01*
G01Y109922D02*
X783002D01*
G01X786907Y108372D02*
Y111472D01*
X786447Y110852D01*
G01Y108372D02*
X787367D01*
G01X790007Y111472D02*
X789700Y111369D01*
X789470Y111110D01*
X789317Y110800D01*
X789202Y110387D01*
X789164Y109922D01*
X789202Y109457D01*
X789317Y109044D01*
X789470Y108734D01*
X789700Y108475D01*
X790007Y108372D01*
X790314Y108475D01*
X790544Y108734D01*
X790697Y109044D01*
X790812Y109457D01*
X790850Y109922D01*
X790812Y110387D01*
X790697Y110800D01*
X790544Y111110D01*
X790314Y111369D01*
X790007Y111472D01*
G01X792264Y108992D02*
X792494Y108630D01*
X792800Y108424D01*
X793145Y108372D01*
X793452Y108424D01*
X793759Y108682D01*
X793950Y108992D01*
X793989Y109302D01*
X793912Y109664D01*
X793644Y109922D01*
X793375Y110025D01*
X793030D01*
G01X793375D02*
X793605Y110180D01*
X793797Y110439D01*
X793874Y110749D01*
X793797Y111059D01*
X793605Y111317D01*
X793260Y111472D01*
X792915Y111420D01*
X792570Y111214D01*
G01X784626Y121997D02*
Y153797D01*
X798426D01*
Y121997D01*
X784626D01*
G01X779403Y155328D02*
Y152128D01*
G01X779389Y159626D02*
Y156426D01*
G01X779520Y164854D02*
Y161654D01*
G01X783553Y182320D02*
G03X837186Y204724I22137J22404D01*
G01D02*
G03X783571Y227146I-31496J0D01*
G01X798500Y250500D02*
X793500D01*
Y258500D01*
X797000Y262000D01*
X794500D01*
X797000Y259500D01*
Y262000D01*
G01X778060Y266222D02*
Y269422D01*
G01X784260Y266222D02*
X778060D01*
G01X784260Y269422D02*
Y266222D01*
G01X778060Y269422D02*
X784260D01*
G01X778060Y280222D02*
Y283422D01*
G01X784260Y280222D02*
X778060D01*
G01X784260Y283422D02*
Y280222D01*
G01Y276422D02*
Y273222D01*
G01X778060Y276422D02*
X784260D01*
G01X778060Y273222D02*
Y276422D01*
G01X784260Y273222D02*
X778060D01*
G01Y283422D02*
X784260D01*
G01X782142Y300879D02*
Y297679D01*
G01X790726Y305010D02*
Y301810D01*
G01X784526Y305010D02*
X790726D01*
G01X784526Y301810D02*
Y305010D01*
G01X790726Y301810D02*
X784526D01*
G01X790641Y310355D02*
Y307155D01*
G01X784441Y310355D02*
X790641D01*
G01X784441Y307155D02*
Y310355D01*
G01X790641Y307155D02*
X784441D01*
G01X777541Y310355D02*
Y307155D01*
G01X777626Y305010D02*
Y301810D01*
G01X782417Y317392D02*
X784843D01*
G01X781330Y319592D02*
X779530D01*
G01X781330Y315192D02*
X779530D01*
G01X781330Y319592D02*
Y315192D01*
G01X780730D02*
Y319592D01*
G01X780130D02*
Y315192D01*
G01X796200Y367800D02*
Y361600D01*
X793000D01*
Y367800D01*
X796200D01*
G01X791384Y377356D02*
X779416D01*
Y362644D01*
X791384D01*
Y377356D01*
G01X780933Y378807D02*
X783155D01*
X783620Y378960D01*
X783930Y379267D01*
X784033Y379650D01*
X783930Y380033D01*
X783620Y380340D01*
X783155Y380493D01*
X780933D01*
G01X783413Y381907D02*
X783775Y382137D01*
X783981Y382443D01*
X784033Y382788D01*
X783981Y383095D01*
X783723Y383402D01*
X783413Y383593D01*
X783103Y383632D01*
X782741Y383555D01*
X782483Y383287D01*
X782380Y383018D01*
Y382673D01*
G01Y383018D02*
X782225Y383248D01*
X781966Y383440D01*
X781656Y383517D01*
X781346Y383440D01*
X781088Y383248D01*
X780933Y382903D01*
X780985Y382558D01*
X781191Y382213D01*
G01X783413Y385007D02*
X783775Y385237D01*
X783981Y385543D01*
X784033Y385888D01*
X783981Y386195D01*
X783723Y386502D01*
X783413Y386693D01*
X783103Y386732D01*
X782741Y386655D01*
X782483Y386387D01*
X782380Y386118D01*
Y385773D01*
G01Y386118D02*
X782225Y386348D01*
X781966Y386540D01*
X781656Y386617D01*
X781346Y386540D01*
X781088Y386348D01*
X780933Y386003D01*
X780985Y385658D01*
X781191Y385313D01*
G01X784033Y388873D02*
X783361Y388950D01*
X782793Y389065D01*
X782276Y389218D01*
X781708Y389410D01*
X780933Y389717D01*
Y388183D01*
G01X793698Y385630D02*
X805902D01*
Y369630D01*
X793698D01*
Y375630D01*
X796800Y377630D01*
X793698Y379630D01*
Y385630D01*
G01X792600Y383700D02*
X786400D01*
Y386900D01*
X792600D01*
Y383700D01*
G01X788320Y391862D02*
Y395062D01*
G01X794520Y391862D02*
X788320D01*
G01Y395062D02*
X794520D01*
G01X780320Y394812D02*
Y391612D01*
G01Y414812D02*
Y411612D01*
G01Y409812D02*
Y406612D01*
G01Y404812D02*
Y401612D01*
G01X788320Y399812D02*
X794520D01*
G01X788320Y396612D02*
Y399812D01*
G01X794520Y396612D02*
X788320D01*
G01X780320Y399812D02*
Y396612D01*
G01X788320Y404100D02*
X794520D01*
Y400900D01*
X788320D01*
Y404100D01*
G01X780320Y419812D02*
Y416612D01*
G01Y424812D02*
Y421612D01*
G01X791320Y423762D02*
X788120D01*
G01X791320Y429962D02*
Y423762D01*
G01X788120D02*
Y429962D01*
G01X792620Y423762D02*
Y429962D01*
G01X795820Y423762D02*
X792620D01*
G01X793580Y432282D02*
X793273Y432334D01*
X793005Y432540D01*
X792775Y432850D01*
X792622Y433212D01*
X792545Y433625D01*
Y434039D01*
X792622Y434452D01*
X792775Y434814D01*
X793005Y435124D01*
X793273Y435330D01*
X793580Y435382D01*
X793887Y435330D01*
X794155Y435124D01*
X794385Y434814D01*
X794538Y434452D01*
X794615Y434039D01*
Y433625D01*
X794538Y433212D01*
X794385Y432850D01*
X794155Y432540D01*
X793887Y432334D01*
X793580Y432282D01*
G01X793887Y433109D02*
X794347Y432282D01*
G01X795837Y432902D02*
X796067Y432540D01*
X796373Y432334D01*
X796718Y432282D01*
X797025Y432334D01*
X797332Y432592D01*
X797523Y432902D01*
X797562Y433212D01*
X797485Y433574D01*
X797217Y433832D01*
X796948Y433935D01*
X796603D01*
G01X796948D02*
X797178Y434090D01*
X797370Y434349D01*
X797447Y434659D01*
X797370Y434969D01*
X797178Y435227D01*
X796833Y435382D01*
X796488Y435330D01*
X796143Y435124D01*
G01X798937Y432902D02*
X799167Y432540D01*
X799473Y432334D01*
X799818Y432282D01*
X800125Y432334D01*
X800432Y432592D01*
X800623Y432902D01*
X800662Y433212D01*
X800585Y433574D01*
X800317Y433832D01*
X800048Y433935D01*
X799703D01*
G01X800048D02*
X800278Y434090D01*
X800470Y434349D01*
X800547Y434659D01*
X800470Y434969D01*
X800278Y435227D01*
X799933Y435382D01*
X799588Y435330D01*
X799243Y435124D01*
G01X778820Y442962D02*
Y436762D01*
G01X788240Y443262D02*
Y446462D01*
G01X794440Y443262D02*
X788240D01*
G01Y441462D02*
X794440D01*
G01X788240Y438262D02*
Y441462D01*
G01X794440Y438262D02*
X788240D01*
G01X778820Y449962D02*
Y443762D01*
G01X788120Y429962D02*
X791320D01*
G01X792620D02*
X795820D01*
G01X788240Y451462D02*
X794440D01*
G01X788240Y448262D02*
Y451462D01*
G01X794440Y448262D02*
X788240D01*
G01Y446462D02*
X794440D01*
G01X788240Y456462D02*
X794440D01*
G01X788240Y453262D02*
Y456462D01*
G01X794440Y453262D02*
X788240D01*
G01Y461462D02*
X794440D01*
G01X788240Y458262D02*
Y461462D01*
G01X794440Y458262D02*
X788240D01*
G01X779440Y456462D02*
Y453262D01*
G01Y461462D02*
Y458262D01*
G01Y466462D02*
Y463262D01*
G01Y471462D02*
Y468262D01*
G01X788240Y463262D02*
Y466462D01*
G01X794440Y463262D02*
X788240D01*
G01Y466462D02*
X794440D01*
G01X788240Y473262D02*
Y476462D01*
G01X794440Y473262D02*
X788240D01*
G01Y476462D02*
X794440D01*
G01X788240Y471462D02*
X794440D01*
G01X788240Y468262D02*
Y471462D01*
G01X794440Y468262D02*
X788240D01*
G01X791307Y496962D02*
Y494740D01*
X791460Y494275D01*
X791767Y493965D01*
X792150Y493862D01*
X792533Y493965D01*
X792840Y494275D01*
X792993Y494740D01*
Y496962D01*
G01X795250Y493862D02*
Y496962D01*
X794790Y496342D01*
G01Y493862D02*
X795710D01*
G01X797507Y494327D02*
X797737Y494069D01*
X798005Y493914D01*
X798350Y493862D01*
X798695Y493965D01*
X798963Y494172D01*
X799155Y494534D01*
X799193Y494947D01*
X799117Y495360D01*
X798925Y495619D01*
X798657Y495825D01*
X798388Y495877D01*
X798120Y495825D01*
X797775Y495619D01*
X797890Y496962D01*
X798925D01*
G01X801450Y493862D02*
X801718Y493914D01*
X802025Y494069D01*
X802217Y494327D01*
X802293Y494689D01*
X802217Y495050D01*
X801987Y495360D01*
X801642Y495515D01*
X801258D01*
X801028Y495619D01*
X800837Y495877D01*
X800760Y496239D01*
X800875Y496600D01*
X801143Y496859D01*
X801450Y496962D01*
X801757Y496859D01*
X802025Y496600D01*
X802140Y496239D01*
X802063Y495877D01*
X801872Y495619D01*
X801642Y495515D01*
X801258D01*
X800913Y495360D01*
X800683Y495050D01*
X800607Y494689D01*
X800683Y494327D01*
X800875Y494069D01*
X801182Y493914D01*
X801450Y493862D01*
G01X779440Y490462D02*
Y487262D01*
G01X786800Y484862D02*
X793000D01*
Y481662D01*
X786800D01*
Y484862D01*
G01X791318Y500066D02*
Y511878D01*
G01X803942Y500066D02*
X791318D01*
G01X784400Y510162D02*
Y503962D01*
X781200D01*
Y510162D01*
X784400D01*
G01X791318Y511878D02*
X803942D01*
G01X792260Y527382D02*
X791953Y527434D01*
X791685Y527640D01*
X791455Y527950D01*
X791302Y528312D01*
X791225Y528725D01*
Y529139D01*
X791302Y529552D01*
X791455Y529914D01*
X791685Y530224D01*
X791953Y530430D01*
X792260Y530482D01*
X792567Y530430D01*
X792835Y530224D01*
X793065Y529914D01*
X793218Y529552D01*
X793295Y529139D01*
Y528725D01*
X793218Y528312D01*
X793065Y527950D01*
X792835Y527640D01*
X792567Y527434D01*
X792260Y527382D01*
G01X792567Y528209D02*
X793027Y527382D01*
G01X794517Y527847D02*
X794747Y527589D01*
X795015Y527434D01*
X795360Y527382D01*
X795705Y527485D01*
X795973Y527692D01*
X796165Y528054D01*
X796203Y528467D01*
X796127Y528880D01*
X795935Y529139D01*
X795667Y529345D01*
X795398Y529397D01*
X795130Y529345D01*
X794785Y529139D01*
X794900Y530482D01*
X795935D01*
G01X798920Y527382D02*
Y530482D01*
X797502Y528260D01*
X799418D01*
G01X803922Y513976D02*
X791298D01*
G01D02*
Y525788D01*
G01D02*
X803922D01*
G01X789120Y515382D02*
X785920D01*
G01X789120Y521582D02*
Y515382D01*
G01X785920Y521582D02*
X789120D01*
G01X785920Y515382D02*
Y521582D01*
G01X781850D02*
X785050D01*
G01X781850Y515382D02*
Y521582D01*
G01X785050Y515382D02*
X781850D01*
G01X785050Y521582D02*
Y515382D01*
G01X777970Y1595632D02*
Y1575414D01*
G01D02*
X798188D01*
G01Y1595632D02*
X777970D01*
G01X779268Y1614870D02*
Y1617970D01*
X780188D01*
X780495Y1617815D01*
X780725Y1617453D01*
X780802Y1617040D01*
X780725Y1616627D01*
X780533Y1616317D01*
X780188Y1616162D01*
X779268D01*
G01X782292Y1617970D02*
Y1615748D01*
X782445Y1615283D01*
X782752Y1614973D01*
X783135Y1614870D01*
X783518Y1614973D01*
X783825Y1615283D01*
X783978Y1615748D01*
Y1617970D01*
G01X785507Y1617453D02*
X785737Y1617763D01*
X786005Y1617918D01*
X786312Y1617970D01*
X786695Y1617867D01*
X786963Y1617608D01*
X787040Y1617298D01*
X787002Y1616988D01*
X786848Y1616730D01*
X786082Y1616213D01*
X785737Y1615852D01*
X785507Y1615335D01*
X785430Y1614870D01*
X787040D01*
G01X789335D02*
X789603Y1614922D01*
X789910Y1615077D01*
X790102Y1615335D01*
X790178Y1615697D01*
X790102Y1616058D01*
X789872Y1616368D01*
X789527Y1616523D01*
X789143D01*
X788913Y1616627D01*
X788722Y1616885D01*
X788645Y1617247D01*
X788760Y1617608D01*
X789028Y1617867D01*
X789335Y1617970D01*
X789642Y1617867D01*
X789910Y1617608D01*
X790025Y1617247D01*
X789948Y1616885D01*
X789757Y1616627D01*
X789527Y1616523D01*
X789143D01*
X788798Y1616368D01*
X788568Y1616058D01*
X788492Y1615697D01*
X788568Y1615335D01*
X788760Y1615077D01*
X789067Y1614922D01*
X789335Y1614870D01*
G01X792358D02*
X792435Y1615542D01*
X792550Y1616110D01*
X792703Y1616627D01*
X792895Y1617195D01*
X793202Y1617970D01*
X791668D01*
G01X815872Y1682410D02*
X783288D01*
G01D02*
Y1692083D01*
G01Y1717697D02*
Y1775402D01*
G01X1074272Y1734890D02*
X783288D01*
G01Y1775402D02*
X1074272D01*
G01X802957Y151492D02*
Y149270D01*
X803110Y148805D01*
X803417Y148495D01*
X803800Y148392D01*
X804183Y148495D01*
X804490Y148805D01*
X804643Y149270D01*
Y151492D01*
G01X806172Y150975D02*
X806402Y151285D01*
X806670Y151440D01*
X806977Y151492D01*
X807360Y151389D01*
X807628Y151130D01*
X807705Y150820D01*
X807667Y150510D01*
X807513Y150252D01*
X806747Y149735D01*
X806402Y149374D01*
X806172Y148857D01*
X806095Y148392D01*
X807705D01*
G01X809272Y149684D02*
X809540Y150045D01*
X809770Y150252D01*
X810077Y150355D01*
X810345Y150252D01*
X810537Y150045D01*
X810690Y149735D01*
X810728Y149374D01*
X810690Y149064D01*
X810537Y148754D01*
X810307Y148495D01*
X810038Y148392D01*
X809732Y148495D01*
X809463Y148805D01*
X809310Y149270D01*
X809272Y149787D01*
X809348Y150459D01*
X809463Y150820D01*
X809655Y151182D01*
X809923Y151440D01*
X810192Y151492D01*
X810460Y151389D01*
X810652Y151130D01*
G01X812257Y148857D02*
X812487Y148599D01*
X812755Y148444D01*
X813100Y148392D01*
X813445Y148495D01*
X813713Y148702D01*
X813905Y149064D01*
X813943Y149477D01*
X813867Y149890D01*
X813675Y150149D01*
X813407Y150355D01*
X813138Y150407D01*
X812870Y150355D01*
X812525Y150149D01*
X812640Y151492D01*
X813675D01*
G01X800883Y247000D02*
Y250100D01*
X801803D01*
X802110Y249945D01*
X802340Y249583D01*
X802417Y249170D01*
X802340Y248757D01*
X802148Y248447D01*
X801803Y248292D01*
X800883D01*
G01X804750Y247000D02*
Y250100D01*
X804290Y249480D01*
G01Y247000D02*
X805210D01*
G01X807122Y249583D02*
X807352Y249893D01*
X807620Y250048D01*
X807927Y250100D01*
X808310Y249997D01*
X808578Y249738D01*
X808655Y249428D01*
X808617Y249118D01*
X808463Y248860D01*
X807697Y248343D01*
X807352Y247982D01*
X807122Y247465D01*
X807045Y247000D01*
X808655D01*
G01X809992Y250100D02*
X810950Y247000D01*
X811908Y250100D01*
G01X812900Y245967D02*
X815200D01*
G01X816345Y247413D02*
X816652Y247155D01*
X816997Y247000D01*
X817303D01*
X817610Y247155D01*
X817840Y247413D01*
X817955Y247775D01*
X817878Y248137D01*
X817687Y248447D01*
X817342Y248653D01*
X816882Y248757D01*
X816613Y248963D01*
X816498Y249325D01*
X816575Y249687D01*
X816767Y249945D01*
X817035Y250100D01*
X817303D01*
X817572Y249997D01*
X817802Y249738D01*
G01X821093Y249842D02*
X820863Y249997D01*
X820595Y250100D01*
X820288D01*
X819943Y249945D01*
X819675Y249687D01*
X819483Y249377D01*
X819330Y248860D01*
X819292Y248395D01*
X819368Y247930D01*
X819483Y247620D01*
X819713Y247310D01*
X819982Y247103D01*
X820250Y247000D01*
X820518D01*
X820787Y247103D01*
X821017Y247258D01*
X821208Y247465D01*
G01X822353Y247000D02*
Y250100D01*
X823350Y247517D01*
X824347Y250100D01*
Y247000D01*
G01X825300Y245967D02*
X827600D01*
G01X828822Y247000D02*
Y250100D01*
X830278D01*
G01X829742Y248602D02*
X828822D01*
G01X831692Y247000D02*
X832650Y250100D01*
X833608Y247000D01*
G01X833263Y248085D02*
X832037D01*
G01X834907Y250100D02*
Y247878D01*
X835060Y247413D01*
X835367Y247103D01*
X835750Y247000D01*
X836133Y247103D01*
X836440Y247413D01*
X836593Y247878D01*
Y250100D01*
G01X838083D02*
Y247000D01*
X839617D01*
G01X841950Y250100D02*
Y247000D01*
G01X841068Y250100D02*
X842832D01*
G01X799500Y256500D02*
X844500D01*
Y244500D01*
X798500D01*
Y256500D01*
X799500D01*
G01X803515Y238084D02*
Y241184D01*
G01X805125D02*
Y238084D01*
G01Y239634D02*
X803515D01*
G01X807420Y238084D02*
Y241184D01*
X806960Y240564D01*
G01Y238084D02*
X807880D01*
G01X810520D02*
Y241184D01*
X810060Y240564D01*
G01Y238084D02*
X810980D01*
G01X812892Y240667D02*
X813122Y240977D01*
X813390Y241132D01*
X813697Y241184D01*
X814080Y241081D01*
X814348Y240822D01*
X814425Y240512D01*
X814387Y240202D01*
X814233Y239944D01*
X813467Y239427D01*
X813122Y239066D01*
X812892Y238549D01*
X812815Y238084D01*
X814425D01*
G01X801273Y259800D02*
X803513D01*
G01X802300Y261425D02*
Y258175D01*
G01X800647Y252080D02*
Y255180D01*
X801413D01*
X801720Y255025D01*
X801950Y254818D01*
X802142Y254508D01*
X802295Y254147D01*
X802333Y253630D01*
X802295Y253113D01*
X802142Y252752D01*
X801950Y252442D01*
X801720Y252235D01*
X801413Y252080D01*
X800647D01*
G01X804590D02*
Y255180D01*
X804130Y254560D01*
G01Y252080D02*
X805050D01*
G01X808150D02*
Y255180D01*
X806732Y252958D01*
X808648D01*
G01X811250Y252080D02*
Y255180D01*
X809832Y252958D01*
X811748D01*
G01X807987Y259700D02*
X810413D01*
G01X800640Y266780D02*
X811040D01*
Y262380D01*
X800640D01*
Y266780D01*
G01X801362Y271400D02*
X807562D01*
Y268200D01*
X801362D01*
Y271400D01*
G01X797525Y320269D02*
X797295Y320424D01*
X797027Y320527D01*
X796720D01*
X796375Y320372D01*
X796107Y320114D01*
X795915Y319804D01*
X795762Y319287D01*
X795724Y318822D01*
X795800Y318357D01*
X795915Y318047D01*
X796145Y317737D01*
X796414Y317530D01*
X796682Y317427D01*
X796950D01*
X797219Y317530D01*
X797449Y317685D01*
X797640Y317892D01*
G01X798824Y317427D02*
X799782Y320527D01*
X800740Y317427D01*
G01X800395Y318512D02*
X799169D01*
G01X802882Y320527D02*
Y317427D01*
G01X802000Y320527D02*
X803764D01*
G01X806749Y317427D02*
X805215D01*
Y320527D01*
X806749D01*
G01X806135Y319029D02*
X805215D01*
G01X808315Y317427D02*
Y320527D01*
X809274D01*
X809580Y320372D01*
X809772Y320165D01*
X809849Y319752D01*
X809772Y319339D01*
X809542Y319080D01*
X809274Y318925D01*
X808315D01*
G01X809274D02*
X809849Y317427D01*
G01X811415D02*
Y320527D01*
X812374D01*
X812680Y320372D01*
X812872Y320165D01*
X812949Y319752D01*
X812872Y319339D01*
X812642Y319080D01*
X812374Y318925D01*
X811415D01*
G01X812374D02*
X812949Y317427D01*
G01X817615Y320527D02*
Y317427D01*
X819149D01*
G01X822249D02*
X820715D01*
Y320527D01*
X822249D01*
G01X821635Y319029D02*
X820715D01*
G01X823739Y317427D02*
Y320527D01*
X824505D01*
X824812Y320372D01*
X825042Y320165D01*
X825234Y319855D01*
X825387Y319494D01*
X825425Y318977D01*
X825387Y318460D01*
X825234Y318099D01*
X825042Y317789D01*
X824812Y317582D01*
X824505Y317427D01*
X823739D01*
G01X803800Y367800D02*
Y361600D01*
X800600D01*
Y367800D01*
X803800D01*
G01X796800Y361600D02*
Y367800D01*
X800000D01*
Y361600D01*
X796800D01*
G01X804400D02*
Y367800D01*
X807600D01*
Y361600D01*
X804400D01*
G01X811400Y367800D02*
Y361600D01*
X808200D01*
Y367800D01*
X811400D01*
G01X806500Y368837D02*
X808722D01*
X809187Y368990D01*
X809497Y369297D01*
X809600Y369680D01*
X809497Y370063D01*
X809187Y370370D01*
X808722Y370523D01*
X806500D01*
G01X808980Y371937D02*
X809342Y372167D01*
X809548Y372473D01*
X809600Y372818D01*
X809548Y373125D01*
X809290Y373432D01*
X808980Y373623D01*
X808670Y373662D01*
X808308Y373585D01*
X808050Y373317D01*
X807947Y373048D01*
Y372703D01*
G01Y373048D02*
X807792Y373278D01*
X807533Y373470D01*
X807223Y373547D01*
X806913Y373470D01*
X806655Y373278D01*
X806500Y372933D01*
X806552Y372588D01*
X806758Y372243D01*
G01X808980Y375037D02*
X809342Y375267D01*
X809548Y375573D01*
X809600Y375918D01*
X809548Y376225D01*
X809290Y376532D01*
X808980Y376723D01*
X808670Y376762D01*
X808308Y376685D01*
X808050Y376417D01*
X807947Y376148D01*
Y375803D01*
G01Y376148D02*
X807792Y376378D01*
X807533Y376570D01*
X807223Y376647D01*
X806913Y376570D01*
X806655Y376378D01*
X806500Y376033D01*
X806552Y375688D01*
X806758Y375343D01*
G01X809238Y378328D02*
X809497Y378597D01*
X809600Y378903D01*
X809497Y379210D01*
X809187Y379478D01*
X808722Y379670D01*
X808257Y379747D01*
X807688D01*
X807223Y379670D01*
X806810Y379478D01*
X806603Y379248D01*
X806500Y378980D01*
X806603Y378673D01*
X806810Y378443D01*
X807120Y378290D01*
X807533Y378213D01*
X807895Y378290D01*
X808257Y378482D01*
X808463Y378712D01*
X808515Y378980D01*
X808412Y379287D01*
X808153Y379517D01*
X807688Y379747D01*
G01X817210Y403570D02*
Y391758D01*
X804586D01*
Y403570D01*
X817210D01*
G01X794520Y395062D02*
Y391862D01*
G01X811200Y387700D02*
Y381500D01*
X808000D01*
Y387700D01*
X811200D01*
G01X817210Y418170D02*
Y406358D01*
X804586D01*
Y418170D01*
X817210D01*
G01X796548Y403864D02*
X796241Y403916D01*
X795973Y404122D01*
X795743Y404432D01*
X795590Y404794D01*
X795513Y405207D01*
Y405621D01*
X795590Y406034D01*
X795743Y406396D01*
X795973Y406706D01*
X796241Y406912D01*
X796548Y406964D01*
X796855Y406912D01*
X797123Y406706D01*
X797353Y406396D01*
X797506Y406034D01*
X797583Y405621D01*
Y405207D01*
X797506Y404794D01*
X797353Y404432D01*
X797123Y404122D01*
X796855Y403916D01*
X796548Y403864D01*
G01X796855Y404691D02*
X797315Y403864D01*
G01X798805Y404484D02*
X799035Y404122D01*
X799341Y403916D01*
X799686Y403864D01*
X799993Y403916D01*
X800300Y404174D01*
X800491Y404484D01*
X800530Y404794D01*
X800453Y405156D01*
X800185Y405414D01*
X799916Y405517D01*
X799571D01*
G01X799916D02*
X800146Y405672D01*
X800338Y405931D01*
X800415Y406241D01*
X800338Y406551D01*
X800146Y406809D01*
X799801Y406964D01*
X799456Y406912D01*
X799111Y406706D01*
G01X803208Y403864D02*
Y406964D01*
X801790Y404742D01*
X803706D01*
G01X798898Y411526D02*
Y417726D01*
G01X802098Y411526D02*
X798898D01*
G01X802098Y417726D02*
Y411526D01*
G01X798898Y403126D02*
X802098D01*
G01X798898Y396926D02*
Y403126D01*
G01X802098Y396926D02*
X798898D01*
G01X802098Y403126D02*
Y396926D01*
G01X794520Y399812D02*
Y396612D01*
G01X794946Y411526D02*
Y417726D01*
X798146D01*
Y411526D01*
X794946D01*
G01X815126Y423050D02*
X803314D01*
G01D02*
Y435674D01*
G01X805548Y419764D02*
X805241Y419816D01*
X804973Y420022D01*
X804743Y420332D01*
X804590Y420694D01*
X804513Y421107D01*
Y421521D01*
X804590Y421934D01*
X804743Y422296D01*
X804973Y422606D01*
X805241Y422812D01*
X805548Y422864D01*
X805855Y422812D01*
X806123Y422606D01*
X806353Y422296D01*
X806506Y421934D01*
X806583Y421521D01*
Y421107D01*
X806506Y420694D01*
X806353Y420332D01*
X806123Y420022D01*
X805855Y419816D01*
X805548Y419764D01*
G01X805855Y420591D02*
X806315Y419764D01*
G01X807805Y420384D02*
X808035Y420022D01*
X808341Y419816D01*
X808686Y419764D01*
X808993Y419816D01*
X809300Y420074D01*
X809491Y420384D01*
X809530Y420694D01*
X809453Y421056D01*
X809185Y421314D01*
X808916Y421417D01*
X808571D01*
G01X808916D02*
X809146Y421572D01*
X809338Y421831D01*
X809415Y422141D01*
X809338Y422451D01*
X809146Y422709D01*
X808801Y422864D01*
X808456Y422812D01*
X808111Y422606D01*
G01X810905Y420229D02*
X811135Y419971D01*
X811403Y419816D01*
X811748Y419764D01*
X812093Y419867D01*
X812361Y420074D01*
X812553Y420436D01*
X812591Y420849D01*
X812515Y421262D01*
X812323Y421521D01*
X812055Y421727D01*
X811786Y421779D01*
X811518Y421727D01*
X811173Y421521D01*
X811288Y422864D01*
X812323D01*
G01X795820Y429962D02*
Y423762D01*
G01X798898Y417726D02*
X802098D01*
G01X803314Y435674D02*
X815126D01*
G01X794440Y446462D02*
Y443262D01*
G01Y441462D02*
Y438262D01*
G01X810170Y439460D02*
X803970D01*
Y442660D01*
X810170D01*
Y439460D01*
G01Y443500D02*
X803970D01*
Y446700D01*
X810170D01*
Y443500D01*
G01X794440Y451462D02*
Y448262D01*
G01Y456462D02*
Y453262D01*
G01X809940Y456462D02*
Y453262D01*
G01X803740Y456462D02*
X809940D01*
G01X803740Y453262D02*
Y456462D01*
G01X809940Y453262D02*
X803740D01*
G01X809940Y461462D02*
Y458262D01*
G01X803740Y461462D02*
X809940D01*
G01X803740Y458262D02*
Y461462D01*
G01X809940Y458262D02*
X803740D01*
G01X794440Y461462D02*
Y458262D01*
G01X809940Y451462D02*
Y448262D01*
G01X803740Y451462D02*
X809940D01*
G01X803740Y448262D02*
Y451462D01*
G01X809940Y448262D02*
X803740D01*
G01Y468262D02*
Y471462D01*
G01X809940Y468262D02*
X803740D01*
G01X809940Y471462D02*
Y468262D01*
G01X803740Y471462D02*
X809940D01*
G01X803740Y473262D02*
Y476462D01*
G01X809940Y473262D02*
X803740D01*
G01X809940Y476462D02*
Y473262D01*
G01X803740Y476462D02*
X809940D01*
G01Y466462D02*
Y463262D01*
G01X803740Y466462D02*
X809940D01*
G01X803740Y463262D02*
Y466462D01*
G01X809940Y463262D02*
X803740D01*
G01X794440Y466462D02*
Y463262D01*
G01Y476462D02*
Y473262D01*
G01Y471462D02*
Y468262D01*
G01X803942Y511878D02*
Y500066D01*
G01X803922Y525788D02*
Y513976D01*
G01X798725Y711102D02*
Y697211D01*
G01D02*
X824315D01*
G01X794615D02*
Y710592D01*
G01X798725Y1335007D02*
Y717232D01*
G01X794615Y715952D02*
Y1335007D01*
G01X824315Y732644D02*
X798725D01*
G01X824315Y1299574D02*
X798725D01*
G01X824315Y1335007D02*
X798725D01*
G01X872736Y1420330D02*
G03I-31496J0D01*
G01X811752Y1572193D02*
X805552D01*
Y1575393D01*
X811752D01*
Y1572193D01*
G01X805552Y1583393D02*
X811752D01*
G01X805552Y1580193D02*
Y1583393D01*
G01X811752Y1580193D02*
X805552D01*
G01Y1576193D02*
Y1579393D01*
G01X811752Y1576193D02*
X805552D01*
G01Y1579393D02*
X811752D01*
G01X798188Y1575414D02*
Y1595632D01*
G01X805552Y1599393D02*
X811752D01*
G01X805552Y1596193D02*
Y1599393D01*
G01X811752Y1596193D02*
X805552D01*
G01Y1592193D02*
Y1595393D01*
G01X811752Y1592193D02*
X805552D01*
G01Y1595393D02*
X811752D01*
G01X805552Y1587393D02*
X811752D01*
G01X805552Y1584193D02*
Y1587393D01*
G01X811752Y1584193D02*
X805552D01*
G01Y1600193D02*
Y1603393D01*
G01X811752Y1600193D02*
X805552D01*
G01Y1603393D02*
X811752D01*
G01X805552Y1607393D02*
X811752D01*
G01X805552Y1604193D02*
Y1607393D01*
G01X811752Y1604193D02*
X805552D01*
G01Y1608193D02*
Y1611393D01*
G01X811752Y1608193D02*
X805552D01*
G01Y1611393D02*
X811752D01*
G01X818380Y14883D02*
X818690Y15075D01*
X818897Y15305D01*
X819000Y15573D01*
X818897Y15880D01*
X818690Y16110D01*
X818380Y16340D01*
X817967Y16417D01*
X815900D01*
G01X819000Y18673D02*
X818328Y18750D01*
X817760Y18865D01*
X817243Y19018D01*
X816675Y19210D01*
X815900Y19517D01*
Y17983D01*
G01X818380Y21007D02*
X818742Y21237D01*
X818948Y21543D01*
X819000Y21888D01*
X818948Y22195D01*
X818690Y22502D01*
X818380Y22693D01*
X818070Y22732D01*
X817708Y22655D01*
X817450Y22387D01*
X817347Y22118D01*
Y21773D01*
G01Y22118D02*
X817192Y22348D01*
X816933Y22540D01*
X816623Y22617D01*
X816313Y22540D01*
X816055Y22348D01*
X815900Y22003D01*
X815952Y21658D01*
X816158Y21313D01*
G01X820714Y116098D02*
X817514D01*
G01X820714Y122298D02*
Y116098D01*
G01X817514D02*
Y122298D01*
G01X828714Y116098D02*
X825514D01*
G01D02*
Y122298D01*
G01X824714Y116098D02*
X821514D01*
G01X824714Y122298D02*
Y116098D01*
G01X821514D02*
Y122298D01*
G01X817608Y130992D02*
Y132945D01*
G01X819561Y130992D02*
X817608D01*
G01X817514Y122298D02*
X820714D01*
G01X825514D02*
X828714D01*
G01X821514D02*
X824714D01*
G01X817608Y142804D02*
X819561D01*
G01X817608Y140851D02*
Y142804D01*
G01X828214Y145598D02*
X825014D01*
G01Y151798D02*
X828214D01*
G01X825014Y145598D02*
Y151798D01*
G01X818874Y257806D02*
X818567Y257858D01*
X818299Y258064D01*
X818069Y258374D01*
X817916Y258736D01*
X817839Y259149D01*
Y259563D01*
X817916Y259976D01*
X818069Y260338D01*
X818299Y260648D01*
X818567Y260854D01*
X818874Y260906D01*
X819181Y260854D01*
X819449Y260648D01*
X819679Y260338D01*
X819832Y259976D01*
X819909Y259563D01*
Y259149D01*
X819832Y258736D01*
X819679Y258374D01*
X819449Y258064D01*
X819181Y257858D01*
X818874Y257806D01*
G01X819181Y258633D02*
X819641Y257806D01*
G01X821974D02*
Y260906D01*
X821514Y260286D01*
G01Y257806D02*
X822434D01*
G01X824231Y258271D02*
X824461Y258013D01*
X824729Y257858D01*
X825074Y257806D01*
X825419Y257909D01*
X825687Y258116D01*
X825879Y258478D01*
X825917Y258891D01*
X825841Y259304D01*
X825649Y259563D01*
X825381Y259769D01*
X825112Y259821D01*
X824844Y259769D01*
X824499Y259563D01*
X824614Y260906D01*
X825649D01*
G01X828174D02*
X827867Y260803D01*
X827637Y260544D01*
X827484Y260234D01*
X827369Y259821D01*
X827331Y259356D01*
X827369Y258891D01*
X827484Y258478D01*
X827637Y258168D01*
X827867Y257909D01*
X828174Y257806D01*
X828481Y257909D01*
X828711Y258168D01*
X828864Y258478D01*
X828979Y258891D01*
X829017Y259356D01*
X828979Y259821D01*
X828864Y260234D01*
X828711Y260544D01*
X828481Y260803D01*
X828174Y260906D01*
G01X818177Y271470D02*
X821524D01*
X823424Y269270D01*
X825324Y271470D01*
X828671D01*
Y262808D01*
X818177D01*
Y271470D01*
G01X812840Y262380D02*
X811040D01*
G01X812840Y266780D02*
Y262380D01*
G01X812240D02*
Y266780D01*
G01X811640D02*
Y262380D01*
G01X820008Y273285D02*
Y276485D01*
G01X826208Y273285D02*
X820008D01*
G01X826208Y276485D02*
Y273285D01*
G01X820008Y276485D02*
X826208D01*
G01X820008Y278285D02*
Y281485D01*
G01X826208Y278285D02*
X820008D01*
G01X826208Y281485D02*
Y278285D01*
G01X820008Y281485D02*
X826208D01*
G01X812840Y266780D02*
X811040D01*
G01X822507Y375962D02*
Y373740D01*
X822660Y373275D01*
X822967Y372965D01*
X823350Y372862D01*
X823733Y372965D01*
X824040Y373275D01*
X824193Y373740D01*
Y375962D01*
G01X825607Y373482D02*
X825837Y373120D01*
X826143Y372914D01*
X826488Y372862D01*
X826795Y372914D01*
X827102Y373172D01*
X827293Y373482D01*
X827332Y373792D01*
X827255Y374154D01*
X826987Y374412D01*
X826718Y374515D01*
X826373D01*
G01X826718D02*
X826948Y374670D01*
X827140Y374929D01*
X827217Y375239D01*
X827140Y375549D01*
X826948Y375807D01*
X826603Y375962D01*
X826258Y375910D01*
X825913Y375704D01*
G01X828822Y375445D02*
X829052Y375755D01*
X829320Y375910D01*
X829627Y375962D01*
X830010Y375859D01*
X830278Y375600D01*
X830355Y375290D01*
X830317Y374980D01*
X830163Y374722D01*
X829397Y374205D01*
X829052Y373844D01*
X828822Y373327D01*
X828745Y372862D01*
X830355D01*
G01X831807Y373327D02*
X832037Y373069D01*
X832305Y372914D01*
X832650Y372862D01*
X832995Y372965D01*
X833263Y373172D01*
X833455Y373534D01*
X833493Y373947D01*
X833417Y374360D01*
X833225Y374619D01*
X832957Y374825D01*
X832688Y374877D01*
X832420Y374825D01*
X832075Y374619D01*
X832190Y375962D01*
X833225D01*
G01X825878Y387412D02*
Y390612D01*
G01X832078Y387412D02*
X825878D01*
G01Y390612D02*
X832078D01*
G01X825878Y395676D02*
Y398876D01*
G01X832078Y395676D02*
X825878D01*
G01X825900Y382800D02*
Y386000D01*
G01X832100Y382800D02*
X825900D01*
G01Y386000D02*
X832100D01*
G01X812200Y381500D02*
Y387700D01*
X815400D01*
Y381500D01*
X812200D01*
G01X816400D02*
Y387700D01*
X819600D01*
Y381500D01*
X816400D01*
G01X825877Y410860D02*
X832077D01*
G01X825877Y407660D02*
Y410860D01*
G01X832077Y407660D02*
X825877D01*
G01X832077Y403660D02*
X825877D01*
Y406860D01*
X832077D01*
Y403660D01*
G01X825878Y398876D02*
X832078D01*
G01X825877Y414860D02*
X832077D01*
Y411660D01*
X825877D01*
Y414860D01*
G01X824082Y403207D02*
Y400985D01*
X824235Y400520D01*
X824542Y400210D01*
X824925Y400107D01*
X825308Y400210D01*
X825615Y400520D01*
X825768Y400985D01*
Y403207D01*
G01X827297Y402690D02*
X827527Y403000D01*
X827795Y403155D01*
X828102Y403207D01*
X828485Y403104D01*
X828753Y402845D01*
X828830Y402535D01*
X828792Y402225D01*
X828638Y401967D01*
X827872Y401450D01*
X827527Y401089D01*
X827297Y400572D01*
X827220Y400107D01*
X828830D01*
G01X831125Y403207D02*
X830818Y403104D01*
X830588Y402845D01*
X830435Y402535D01*
X830320Y402122D01*
X830282Y401657D01*
X830320Y401192D01*
X830435Y400779D01*
X830588Y400469D01*
X830818Y400210D01*
X831125Y400107D01*
X831432Y400210D01*
X831662Y400469D01*
X831815Y400779D01*
X831930Y401192D01*
X831968Y401657D01*
X831930Y402122D01*
X831815Y402535D01*
X831662Y402845D01*
X831432Y403104D01*
X831125Y403207D01*
G01X833382Y400572D02*
X833612Y400314D01*
X833880Y400159D01*
X834225Y400107D01*
X834570Y400210D01*
X834838Y400417D01*
X835030Y400779D01*
X835068Y401192D01*
X834992Y401605D01*
X834800Y401864D01*
X834532Y402070D01*
X834263Y402122D01*
X833995Y402070D01*
X833650Y401864D01*
X833765Y403207D01*
X834800D01*
G01X815126Y435674D02*
Y423050D01*
G01X825820Y423762D02*
X822620D01*
G01X825820Y429962D02*
Y423762D01*
G01X822620D02*
Y429962D01*
G01D02*
X825820D01*
G01X830784Y446056D02*
X818816D01*
Y431344D01*
X830784D01*
Y446056D01*
G01X822400Y447600D02*
X816200D01*
Y450800D01*
X822400D01*
Y447600D01*
G01X829600D02*
X823400D01*
Y450800D01*
X829600D01*
Y447600D01*
G01X817807Y457100D02*
Y454878D01*
X817960Y454413D01*
X818267Y454103D01*
X818650Y454000D01*
X819033Y454103D01*
X819340Y454413D01*
X819493Y454878D01*
Y457100D01*
G01X820907Y454620D02*
X821137Y454258D01*
X821443Y454052D01*
X821788Y454000D01*
X822095Y454052D01*
X822402Y454310D01*
X822593Y454620D01*
X822632Y454930D01*
X822555Y455292D01*
X822287Y455550D01*
X822018Y455653D01*
X821673D01*
G01X822018D02*
X822248Y455808D01*
X822440Y456067D01*
X822517Y456377D01*
X822440Y456687D01*
X822248Y456945D01*
X821903Y457100D01*
X821558Y457048D01*
X821213Y456842D01*
G01X824007Y454620D02*
X824237Y454258D01*
X824543Y454052D01*
X824888Y454000D01*
X825195Y454052D01*
X825502Y454310D01*
X825693Y454620D01*
X825732Y454930D01*
X825655Y455292D01*
X825387Y455550D01*
X825118Y455653D01*
X824773D01*
G01X825118D02*
X825348Y455808D01*
X825540Y456067D01*
X825617Y456377D01*
X825540Y456687D01*
X825348Y456945D01*
X825003Y457100D01*
X824658Y457048D01*
X824313Y456842D01*
G01X827950Y454000D02*
X828218Y454052D01*
X828525Y454207D01*
X828717Y454465D01*
X828793Y454827D01*
X828717Y455188D01*
X828487Y455498D01*
X828142Y455653D01*
X827758D01*
X827528Y455757D01*
X827337Y456015D01*
X827260Y456377D01*
X827375Y456738D01*
X827643Y456997D01*
X827950Y457100D01*
X828257Y456997D01*
X828525Y456738D01*
X828640Y456377D01*
X828563Y456015D01*
X828372Y455757D01*
X828142Y455653D01*
X827758D01*
X827413Y455498D01*
X827183Y455188D01*
X827107Y454827D01*
X827183Y454465D01*
X827375Y454207D01*
X827682Y454052D01*
X827950Y454000D01*
G01X823940Y475200D02*
X817740D01*
Y478400D01*
X823940D01*
Y475200D01*
G01Y466462D02*
Y463262D01*
G01X817740Y466462D02*
X823940D01*
G01X817740Y463262D02*
Y466462D01*
G01X823940Y463262D02*
X817740D01*
G01X823940Y467300D02*
X817740D01*
Y470500D01*
X823940D01*
Y467300D01*
G01Y471300D02*
X817740D01*
Y474500D01*
X823940D01*
Y471300D01*
G01X822663Y495600D02*
X828863D01*
Y492400D01*
X822663D01*
Y495600D01*
G01X822670Y496482D02*
Y499682D01*
G01X828870Y496482D02*
X822670D01*
G01Y499682D02*
X828870D01*
G01X822670Y509482D02*
Y512682D01*
G01X828870Y509482D02*
X822670D01*
G01X818270Y500822D02*
X815070D01*
G01X818270Y507022D02*
Y500822D01*
G01X815070Y507022D02*
X818270D01*
G01X815070Y500822D02*
Y507022D01*
G01X822670Y507682D02*
X828870D01*
G01X822670Y504482D02*
Y507682D01*
G01X828870Y504482D02*
X822670D01*
G01Y500482D02*
Y503682D01*
G01X828870Y500482D02*
X822670D01*
G01Y503682D02*
X828870D01*
G01X822670Y525482D02*
Y528682D01*
G01X828870Y525482D02*
X822670D01*
G01Y521482D02*
Y524682D01*
G01X828870Y521482D02*
X822670D01*
G01Y524682D02*
X828870D01*
G01X822670Y520682D02*
X828870D01*
G01X822670Y517482D02*
Y520682D01*
G01X828870Y517482D02*
X822670D01*
G01Y513482D02*
Y516682D01*
G01X828870Y513482D02*
X822670D01*
G01Y516682D02*
X828870D01*
G01X822670Y512682D02*
X828870D01*
G01X814410Y515282D02*
X811210D01*
G01X814410Y521482D02*
Y515282D01*
G01X811210Y521482D02*
X814410D01*
G01X811210Y515282D02*
Y521482D01*
G01X822670Y528682D02*
X828870D01*
G01X824315Y697211D02*
Y721952D01*
G01Y728462D02*
Y1335007D01*
G01X814613Y1337486D02*
X814805Y1337176D01*
X815035Y1336969D01*
X815303Y1336866D01*
X815610Y1336969D01*
X815840Y1337176D01*
X816070Y1337486D01*
X816147Y1337899D01*
Y1339966D01*
G01X817637Y1337486D02*
X817867Y1337124D01*
X818173Y1336918D01*
X818518Y1336866D01*
X818825Y1336918D01*
X819132Y1337176D01*
X819323Y1337486D01*
X819362Y1337796D01*
X819285Y1338158D01*
X819017Y1338416D01*
X818748Y1338519D01*
X818403D01*
G01X818748D02*
X818978Y1338674D01*
X819170Y1338933D01*
X819247Y1339243D01*
X819170Y1339553D01*
X818978Y1339811D01*
X818633Y1339966D01*
X818288Y1339914D01*
X817943Y1339708D01*
G01X820852Y1339449D02*
X821082Y1339759D01*
X821350Y1339914D01*
X821657Y1339966D01*
X822040Y1339863D01*
X822308Y1339604D01*
X822385Y1339294D01*
X822347Y1338984D01*
X822193Y1338726D01*
X821427Y1338209D01*
X821082Y1337848D01*
X820852Y1337331D01*
X820775Y1336866D01*
X822385D01*
G01X817535Y1450457D02*
Y1453557D01*
G01X819145D02*
Y1450457D01*
G01Y1452007D02*
X817535D01*
G01X821440Y1450457D02*
Y1453557D01*
X820980Y1452937D01*
G01Y1450457D02*
X821900D01*
G01X824540D02*
Y1453557D01*
X824080Y1452937D01*
G01Y1450457D02*
X825000D01*
G01X828100D02*
Y1453557D01*
X826682Y1451335D01*
X828598D01*
G01X816852Y1583493D02*
X813652D01*
G01X816852Y1589693D02*
Y1583493D01*
G01X813652D02*
Y1589693D01*
G01X811752Y1583393D02*
Y1580193D01*
G01Y1579393D02*
Y1576193D01*
G01X819970Y1595632D02*
Y1575414D01*
G01D02*
X840188D01*
G01X811752Y1599393D02*
Y1596193D01*
G01Y1595393D02*
Y1592193D01*
G01X813652Y1589693D02*
X816852D01*
G01X811752Y1587393D02*
Y1584193D01*
G01Y1603393D02*
Y1600193D01*
G01X840188Y1595632D02*
X819970D01*
G01X811752Y1607393D02*
Y1604193D01*
G01Y1611393D02*
Y1608193D01*
G01X821838Y1616280D02*
Y1619380D01*
X822758D01*
X823065Y1619225D01*
X823295Y1618863D01*
X823372Y1618450D01*
X823295Y1618037D01*
X823103Y1617727D01*
X822758Y1617572D01*
X821838D01*
G01X824862Y1619380D02*
Y1617158D01*
X825015Y1616693D01*
X825322Y1616383D01*
X825705Y1616280D01*
X826088Y1616383D01*
X826395Y1616693D01*
X826548Y1617158D01*
Y1619380D01*
G01X828077Y1618863D02*
X828307Y1619173D01*
X828575Y1619328D01*
X828882Y1619380D01*
X829265Y1619277D01*
X829533Y1619018D01*
X829610Y1618708D01*
X829572Y1618398D01*
X829418Y1618140D01*
X828652Y1617623D01*
X828307Y1617262D01*
X828077Y1616745D01*
X828000Y1616280D01*
X829610D01*
G01X831905D02*
X832173Y1616332D01*
X832480Y1616487D01*
X832672Y1616745D01*
X832748Y1617107D01*
X832672Y1617468D01*
X832442Y1617778D01*
X832097Y1617933D01*
X831713D01*
X831483Y1618037D01*
X831292Y1618295D01*
X831215Y1618657D01*
X831330Y1619018D01*
X831598Y1619277D01*
X831905Y1619380D01*
X832212Y1619277D01*
X832480Y1619018D01*
X832595Y1618657D01*
X832518Y1618295D01*
X832327Y1618037D01*
X832097Y1617933D01*
X831713D01*
X831368Y1617778D01*
X831138Y1617468D01*
X831062Y1617107D01*
X831138Y1616745D01*
X831330Y1616487D01*
X831637Y1616332D01*
X831905Y1616280D01*
G01X835005D02*
X835273Y1616332D01*
X835580Y1616487D01*
X835772Y1616745D01*
X835848Y1617107D01*
X835772Y1617468D01*
X835542Y1617778D01*
X835197Y1617933D01*
X834813D01*
X834583Y1618037D01*
X834392Y1618295D01*
X834315Y1618657D01*
X834430Y1619018D01*
X834698Y1619277D01*
X835005Y1619380D01*
X835312Y1619277D01*
X835580Y1619018D01*
X835695Y1618657D01*
X835618Y1618295D01*
X835427Y1618037D01*
X835197Y1617933D01*
X834813D01*
X834468Y1617778D01*
X834238Y1617468D01*
X834162Y1617107D01*
X834238Y1616745D01*
X834430Y1616487D01*
X834737Y1616332D01*
X835005Y1616280D01*
G01X838870Y26800D02*
Y10200D01*
X829270D01*
Y26800D01*
X838870D01*
G01X837776Y61088D02*
Y78808D01*
G01X838676Y61088D02*
X837776D01*
G01X829861Y57032D02*
Y60232D01*
G01X836061Y57032D02*
X829861D01*
G01X836061Y60232D02*
Y57032D01*
G01X829861Y60232D02*
X836061D01*
G01X829939Y67443D02*
X833139D01*
G01X829939Y61243D02*
Y67443D01*
G01X833139Y61243D02*
X829939D01*
G01X833139Y67443D02*
Y61243D01*
G01X837776Y78808D02*
X838676D01*
G01X838240Y96714D02*
X853590D01*
G01X838240Y108888D02*
Y96714D01*
G01X833015Y102681D02*
Y108881D01*
G01X836215Y102681D02*
X833015D01*
G01X836215Y108881D02*
Y102681D01*
G01X841925Y92051D02*
Y88851D01*
G01X835725Y92051D02*
X841925D01*
G01X835725Y88851D02*
Y92051D01*
G01X841925Y88851D02*
X835725D01*
G01X853590Y108888D02*
X838240D01*
G01X833015Y108881D02*
X836215D01*
G01X840960Y115982D02*
X837760D01*
G01X840960Y122182D02*
Y115982D01*
G01X837760D02*
Y122182D01*
G01X828714Y122298D02*
Y116098D01*
G01X832714D02*
X829514D01*
G01X832714Y122298D02*
Y116098D01*
G01X829514D02*
Y122298D01*
G01X833514Y116098D02*
Y122298D01*
G01X836714Y116098D02*
X833514D01*
G01X836714Y122298D02*
Y116098D01*
G01X829420Y130992D02*
X827467D01*
G01X829420Y132945D02*
Y130992D01*
G01X837760Y122182D02*
X840960D01*
G01X837620Y134262D02*
Y137462D01*
G01X843820Y134262D02*
X837620D01*
G01Y130962D02*
X843820D01*
G01X837620Y127762D02*
Y130962D01*
G01X843820Y127762D02*
X837620D01*
G01X829514Y122298D02*
X832714D01*
G01X833514D02*
X836714D01*
G01X829420Y142804D02*
Y140851D01*
G01X827467Y142804D02*
X829420D01*
G01X828214Y151798D02*
Y145598D01*
G01X837620Y137462D02*
X843820D01*
G01X826620Y165262D02*
Y168462D01*
G01X832820Y165262D02*
X826620D01*
G01X832820Y168462D02*
Y165262D01*
G01X826620Y168462D02*
X832820D01*
G01X826620Y174762D02*
Y177962D01*
G01X832820Y174762D02*
X826620D01*
G01X832820Y177962D02*
Y174762D01*
G01X826620Y177962D02*
X832820D01*
G01X841820Y183262D02*
X838620D01*
G01X841820Y189462D02*
Y183262D01*
G01X838620D02*
Y189462D01*
G01X841820Y196262D02*
X838620D01*
G01X841820Y202462D02*
Y196262D01*
G01X838620D02*
Y202462D01*
G01Y189462D02*
X841820D01*
G01X841573Y208485D02*
Y210438D01*
G01X843526Y208485D02*
X841573D01*
G01X838620Y202462D02*
X841820D01*
G01X841573Y220297D02*
X843526D01*
G01X841573Y218344D02*
Y220297D01*
G01X832115Y229668D02*
X835315D01*
G01X832115Y223468D02*
Y229668D01*
G01X835315Y223468D02*
X832115D01*
G01X835315Y229668D02*
Y223468D01*
G01X834100Y271814D02*
Y265614D01*
X830900D01*
Y271814D01*
X834100D01*
G01X842147Y272649D02*
X848347D01*
G01X842147Y269449D02*
Y272649D01*
G01X848347Y269449D02*
X842147D01*
G01X831535Y273445D02*
Y276645D01*
G01X837735Y273445D02*
X831535D01*
G01X837735Y276645D02*
Y273445D01*
G01X831535Y276645D02*
X837735D01*
G01X831535Y278445D02*
Y281645D01*
G01X837735Y278445D02*
X831535D01*
G01X837735Y281645D02*
Y278445D01*
G01X831535Y281645D02*
X837735D01*
G01X855677Y384504D02*
Y372023D01*
X840323D01*
Y384701D01*
X855677D01*
G01X832078Y390612D02*
Y387412D01*
G01Y398876D02*
Y395676D01*
G01X832100Y386000D02*
Y382800D01*
G01X847841Y395880D02*
X845932Y398589D01*
X839784D01*
Y387171D01*
X855898D01*
Y398589D01*
X849750D01*
X847841Y395880D01*
G01X832077Y410860D02*
Y407660D01*
G01X847785Y408201D02*
X851030Y404756D01*
X855800D01*
Y416764D01*
X839770D01*
Y404756D01*
X844540D01*
X847785Y408201D01*
G01X839248Y403147D02*
Y400925D01*
X839401Y400460D01*
X839708Y400150D01*
X840091Y400047D01*
X840474Y400150D01*
X840781Y400460D01*
X840934Y400925D01*
Y403147D01*
G01X842463Y402630D02*
X842693Y402940D01*
X842961Y403095D01*
X843268Y403147D01*
X843651Y403044D01*
X843919Y402785D01*
X843996Y402475D01*
X843958Y402165D01*
X843804Y401907D01*
X843038Y401390D01*
X842693Y401029D01*
X842463Y400512D01*
X842386Y400047D01*
X843996D01*
G01X846291Y403147D02*
X845984Y403044D01*
X845754Y402785D01*
X845601Y402475D01*
X845486Y402062D01*
X845448Y401597D01*
X845486Y401132D01*
X845601Y400719D01*
X845754Y400409D01*
X845984Y400150D01*
X846291Y400047D01*
X846598Y400150D01*
X846828Y400409D01*
X846981Y400719D01*
X847096Y401132D01*
X847134Y401597D01*
X847096Y402062D01*
X846981Y402475D01*
X846828Y402785D01*
X846598Y403044D01*
X846291Y403147D01*
G01X848663Y401339D02*
X848931Y401700D01*
X849161Y401907D01*
X849468Y402010D01*
X849736Y401907D01*
X849928Y401700D01*
X850081Y401390D01*
X850119Y401029D01*
X850081Y400719D01*
X849928Y400409D01*
X849698Y400150D01*
X849429Y400047D01*
X849123Y400150D01*
X848854Y400460D01*
X848701Y400925D01*
X848663Y401442D01*
X848739Y402114D01*
X848854Y402475D01*
X849046Y402837D01*
X849314Y403095D01*
X849583Y403147D01*
X849851Y403044D01*
X850043Y402785D01*
G01X834000Y426000D02*
Y419800D01*
X830800D01*
Y426000D01*
X834000D01*
G01X829900D02*
Y419800D01*
X826700D01*
Y426000D01*
X829900D01*
G01X834700Y419800D02*
Y426000D01*
X837900D01*
Y419800D01*
X834700D01*
G01X841800Y426000D02*
Y419800D01*
X838600D01*
Y426000D01*
X841800D01*
G01X833098Y443500D02*
X845302D01*
Y427500D01*
X833098D01*
Y433500D01*
X836200Y435500D01*
X833098Y437500D01*
Y443500D01*
G01X833900Y448400D02*
X840100D01*
Y445200D01*
X833900D01*
Y448400D01*
G01X831507Y455100D02*
Y452878D01*
X831660Y452413D01*
X831967Y452103D01*
X832350Y452000D01*
X832733Y452103D01*
X833040Y452413D01*
X833193Y452878D01*
Y455100D01*
G01X834607Y452620D02*
X834837Y452258D01*
X835143Y452052D01*
X835488Y452000D01*
X835795Y452052D01*
X836102Y452310D01*
X836293Y452620D01*
X836332Y452930D01*
X836255Y453292D01*
X835987Y453550D01*
X835718Y453653D01*
X835373D01*
G01X835718D02*
X835948Y453808D01*
X836140Y454067D01*
X836217Y454377D01*
X836140Y454687D01*
X835948Y454945D01*
X835603Y455100D01*
X835258Y455048D01*
X834913Y454842D01*
G01X839010Y452000D02*
Y455100D01*
X837592Y452878D01*
X839508D01*
G01X841650Y455100D02*
X841343Y454997D01*
X841113Y454738D01*
X840960Y454428D01*
X840845Y454015D01*
X840807Y453550D01*
X840845Y453085D01*
X840960Y452672D01*
X841113Y452362D01*
X841343Y452103D01*
X841650Y452000D01*
X841957Y452103D01*
X842187Y452362D01*
X842340Y452672D01*
X842455Y453085D01*
X842493Y453550D01*
X842455Y454015D01*
X842340Y454428D01*
X842187Y454738D01*
X841957Y454997D01*
X841650Y455100D01*
G01X830807Y468100D02*
Y465878D01*
X830960Y465413D01*
X831267Y465103D01*
X831650Y465000D01*
X832033Y465103D01*
X832340Y465413D01*
X832493Y465878D01*
Y468100D01*
G01X833907Y465620D02*
X834137Y465258D01*
X834443Y465052D01*
X834788Y465000D01*
X835095Y465052D01*
X835402Y465310D01*
X835593Y465620D01*
X835632Y465930D01*
X835555Y466292D01*
X835287Y466550D01*
X835018Y466653D01*
X834673D01*
G01X835018D02*
X835248Y466808D01*
X835440Y467067D01*
X835517Y467377D01*
X835440Y467687D01*
X835248Y467945D01*
X834903Y468100D01*
X834558Y468048D01*
X834213Y467842D01*
G01X837007Y465620D02*
X837237Y465258D01*
X837543Y465052D01*
X837888Y465000D01*
X838195Y465052D01*
X838502Y465310D01*
X838693Y465620D01*
X838732Y465930D01*
X838655Y466292D01*
X838387Y466550D01*
X838118Y466653D01*
X837773D01*
G01X838118D02*
X838348Y466808D01*
X838540Y467067D01*
X838617Y467377D01*
X838540Y467687D01*
X838348Y467945D01*
X838003Y468100D01*
X837658Y468048D01*
X837313Y467842D01*
G01X840222Y467583D02*
X840452Y467893D01*
X840720Y468048D01*
X841027Y468100D01*
X841410Y467997D01*
X841678Y467738D01*
X841755Y467428D01*
X841717Y467118D01*
X841563Y466860D01*
X840797Y466343D01*
X840452Y465982D01*
X840222Y465465D01*
X840145Y465000D01*
X841755D01*
G01X835824Y472241D02*
X838155Y469910D01*
X841264D01*
Y478572D01*
X830384D01*
Y469910D01*
X833493D01*
X835824Y472241D01*
G01X837120Y493762D02*
Y496962D01*
G01X843320Y493762D02*
X837120D01*
G01X836758Y507413D02*
X847782D01*
G01X836758Y498751D02*
Y507413D01*
G01Y498751D02*
X847782D01*
G01X828870Y499682D02*
Y496482D01*
G01X837120Y496962D02*
X843320D01*
G01X828870Y512682D02*
Y509482D01*
G01Y507682D02*
Y504482D01*
G01Y503682D02*
Y500482D01*
G01X835802Y519778D02*
Y511116D01*
G01X848716Y519778D02*
X835802D01*
G01Y511116D02*
X848716D01*
G01X839456Y524664D02*
Y530970D01*
G01X833322Y524664D02*
X839456D01*
G01X833322Y530970D02*
Y524664D01*
G01X828870Y528682D02*
Y525482D01*
G01Y524682D02*
Y521482D01*
G01Y520682D02*
Y517482D01*
G01Y516682D02*
Y513482D01*
G01X838317Y536082D02*
Y533860D01*
X838470Y533395D01*
X838777Y533085D01*
X839160Y532982D01*
X839543Y533085D01*
X839850Y533395D01*
X840003Y533860D01*
Y536082D01*
G01X842260Y532982D02*
Y536082D01*
X841800Y535462D01*
G01Y532982D02*
X842720D01*
G01X845360D02*
Y536082D01*
X844900Y535462D01*
G01Y532982D02*
X845820D01*
G01X848383D02*
X848460Y533654D01*
X848575Y534222D01*
X848728Y534739D01*
X848920Y535307D01*
X849227Y536082D01*
X847693D01*
G01X839456Y530970D02*
X833322D01*
G01X828425Y723802D02*
Y697211D01*
G01D02*
X854015D01*
G01X836740Y732644D02*
X828425D01*
G01Y1335007D02*
Y729162D01*
G01X854015Y1299574D02*
X828425D01*
G01X827103Y1336996D02*
X827295Y1336686D01*
X827525Y1336479D01*
X827793Y1336376D01*
X828100Y1336479D01*
X828330Y1336686D01*
X828560Y1336996D01*
X828637Y1337409D01*
Y1339476D01*
G01X830127Y1336996D02*
X830357Y1336634D01*
X830663Y1336428D01*
X831008Y1336376D01*
X831315Y1336428D01*
X831622Y1336686D01*
X831813Y1336996D01*
X831852Y1337306D01*
X831775Y1337668D01*
X831507Y1337926D01*
X831238Y1338029D01*
X830893D01*
G01X831238D02*
X831468Y1338184D01*
X831660Y1338443D01*
X831737Y1338753D01*
X831660Y1339063D01*
X831468Y1339321D01*
X831123Y1339476D01*
X830778Y1339424D01*
X830433Y1339218D01*
G01X834070Y1336376D02*
Y1339476D01*
X833610Y1338856D01*
G01Y1336376D02*
X834530D01*
G01X842490Y1335007D02*
X828425D01*
G01X840188Y1575414D02*
Y1595632D01*
G01X850872Y1682410D02*
X831688D01*
G01X847676Y69948D02*
X849976Y72248D01*
G01Y67648D02*
X847676Y69948D01*
G01X849976Y61088D02*
Y67648D01*
G01X849076Y61088D02*
X849976D01*
G01Y62048D02*
Y67648D01*
G01X855029Y67593D02*
X858229D01*
G01X855029Y61393D02*
Y67593D01*
G01X858229Y61393D02*
X855029D01*
G01X858229Y67593D02*
Y61393D01*
G01X852966Y77577D02*
Y75355D01*
X853119Y74890D01*
X853426Y74580D01*
X853809Y74477D01*
X854192Y74580D01*
X854499Y74890D01*
X854652Y75355D01*
Y77577D01*
G01X856257Y74839D02*
X856526Y74580D01*
X856832Y74477D01*
X857139Y74580D01*
X857407Y74890D01*
X857599Y75355D01*
X857676Y75820D01*
Y76389D01*
X857599Y76854D01*
X857407Y77267D01*
X857177Y77474D01*
X856909Y77577D01*
X856602Y77474D01*
X856372Y77267D01*
X856219Y76957D01*
X856142Y76544D01*
X856219Y76182D01*
X856411Y75820D01*
X856641Y75614D01*
X856909Y75562D01*
X857216Y75665D01*
X857446Y75924D01*
X857676Y76389D01*
G01X860009Y77577D02*
X859702Y77474D01*
X859472Y77215D01*
X859319Y76905D01*
X859204Y76492D01*
X859166Y76027D01*
X859204Y75562D01*
X859319Y75149D01*
X859472Y74839D01*
X859702Y74580D01*
X860009Y74477D01*
X860316Y74580D01*
X860546Y74839D01*
X860699Y75149D01*
X860814Y75562D01*
X860852Y76027D01*
X860814Y76492D01*
X860699Y76905D01*
X860546Y77215D01*
X860316Y77474D01*
X860009Y77577D01*
G01X849976Y78808D02*
X849076D01*
G01X849976Y72248D02*
Y78808D01*
G01X853590Y96714D02*
Y108888D01*
G01X846535Y88651D02*
X843335D01*
G01X846535Y94851D02*
Y88651D01*
G01X843335Y94851D02*
X846535D01*
G01X843335Y88651D02*
Y94851D01*
G01X848415D02*
X851615D01*
G01X848415Y88651D02*
Y94851D01*
G01X851615Y88651D02*
X848415D01*
G01X851615Y94851D02*
Y88651D01*
G01X858459Y106484D02*
X858152Y106536D01*
X857884Y106742D01*
X857654Y107052D01*
X857501Y107414D01*
X857424Y107827D01*
Y108241D01*
X857501Y108654D01*
X857654Y109016D01*
X857884Y109326D01*
X858152Y109532D01*
X858459Y109584D01*
X858766Y109532D01*
X859034Y109326D01*
X859264Y109016D01*
X859417Y108654D01*
X859494Y108241D01*
Y107827D01*
X859417Y107414D01*
X859264Y107052D01*
X859034Y106742D01*
X858766Y106536D01*
X858459Y106484D01*
G01X860754Y106897D02*
X861061Y106639D01*
X861406Y106484D01*
X861712D01*
X862019Y106639D01*
X862249Y106897D01*
X862364Y107259D01*
X862287Y107621D01*
X862096Y107931D01*
X861751Y108137D01*
X861291Y108241D01*
X861022Y108447D01*
X860907Y108809D01*
X860984Y109171D01*
X861176Y109429D01*
X861444Y109584D01*
X861712D01*
X861981Y109481D01*
X862211Y109222D01*
G01X865502Y109326D02*
X865272Y109481D01*
X865004Y109584D01*
X864697D01*
X864352Y109429D01*
X864084Y109171D01*
X863892Y108861D01*
X863739Y108344D01*
X863701Y107879D01*
X863777Y107414D01*
X863892Y107104D01*
X864122Y106794D01*
X864391Y106587D01*
X864659Y106484D01*
X864927D01*
X865196Y106587D01*
X865426Y106742D01*
X865617Y106949D01*
G01X867759Y106484D02*
Y109584D01*
X867299Y108964D01*
G01Y106484D02*
X868219D01*
G01X843820Y137462D02*
Y134262D01*
G01Y130962D02*
Y127762D01*
G01X853320Y130962D02*
Y127762D01*
G01X847120Y130962D02*
X853320D01*
G01X847120Y127762D02*
Y130962D01*
G01X853320Y127762D02*
X847120D01*
G01X853320Y137462D02*
Y134262D01*
G01X847120D02*
Y137462D01*
G01X853320Y134262D02*
X847120D01*
G01Y137462D02*
X853320D01*
G01X854187Y160382D02*
Y158160D01*
X854340Y157695D01*
X854647Y157385D01*
X855030Y157282D01*
X855413Y157385D01*
X855720Y157695D01*
X855873Y158160D01*
Y160382D01*
G01X857402Y159865D02*
X857632Y160175D01*
X857900Y160330D01*
X858207Y160382D01*
X858590Y160279D01*
X858858Y160020D01*
X858935Y159710D01*
X858897Y159400D01*
X858743Y159142D01*
X857977Y158625D01*
X857632Y158264D01*
X857402Y157747D01*
X857325Y157282D01*
X858935D01*
G01X861153D02*
X861230Y157954D01*
X861345Y158522D01*
X861498Y159039D01*
X861690Y159607D01*
X861997Y160382D01*
X860463D01*
G01X863678Y157644D02*
X863947Y157385D01*
X864253Y157282D01*
X864560Y157385D01*
X864828Y157695D01*
X865020Y158160D01*
X865097Y158625D01*
Y159194D01*
X865020Y159659D01*
X864828Y160072D01*
X864598Y160279D01*
X864330Y160382D01*
X864023Y160279D01*
X863793Y160072D01*
X863640Y159762D01*
X863563Y159349D01*
X863640Y158987D01*
X863832Y158625D01*
X864062Y158419D01*
X864330Y158367D01*
X864637Y158470D01*
X864867Y158729D01*
X865097Y159194D01*
G01X856887Y178300D02*
Y166096D01*
G01X845363D02*
Y178300D01*
G01X848125Y166096D02*
X845363D01*
G01X851125Y169198D02*
X848125Y166096D01*
G01X854227D02*
X851125Y169198D01*
G01X856887Y166096D02*
X854227D01*
G01X847220Y161162D02*
Y164362D01*
G01X853420Y161162D02*
X847220D01*
G01X853420Y164362D02*
Y161162D01*
G01X847220Y164362D02*
X853420D01*
G01X845363Y178300D02*
X856887D01*
G01X845820Y183262D02*
X842620D01*
G01X845820Y189462D02*
Y183262D01*
G01X842620D02*
Y189462D01*
G01X846810Y184212D02*
Y187412D01*
G01X853010Y184212D02*
X846810D01*
G01X853010Y187412D02*
Y184212D01*
G01X845820Y196262D02*
X842620D01*
G01X845820Y202462D02*
Y196262D01*
G01X842620D02*
Y202462D01*
G01Y189462D02*
X845820D01*
G01X846810Y187412D02*
X853010D01*
G01X854590Y185510D02*
Y191710D01*
X857790D01*
Y185510D01*
X854590D01*
G01X856907Y210492D02*
Y208270D01*
X857060Y207805D01*
X857367Y207495D01*
X857750Y207392D01*
X858133Y207495D01*
X858440Y207805D01*
X858593Y208270D01*
Y210492D01*
G01X860122Y209975D02*
X860352Y210285D01*
X860620Y210440D01*
X860927Y210492D01*
X861310Y210389D01*
X861578Y210130D01*
X861655Y209820D01*
X861617Y209510D01*
X861463Y209252D01*
X860697Y208735D01*
X860352Y208374D01*
X860122Y207857D01*
X860045Y207392D01*
X861655D01*
G01X863873D02*
X863950Y208064D01*
X864065Y208632D01*
X864218Y209149D01*
X864410Y209717D01*
X864717Y210492D01*
X863183D01*
G01X866322Y208684D02*
X866590Y209045D01*
X866820Y209252D01*
X867127Y209355D01*
X867395Y209252D01*
X867587Y209045D01*
X867740Y208735D01*
X867778Y208374D01*
X867740Y208064D01*
X867587Y207754D01*
X867357Y207495D01*
X867088Y207392D01*
X866782Y207495D01*
X866513Y207805D01*
X866360Y208270D01*
X866322Y208787D01*
X866398Y209459D01*
X866513Y209820D01*
X866705Y210182D01*
X866973Y210440D01*
X867242Y210492D01*
X867510Y210389D01*
X867702Y210130D01*
G01X853385Y208485D02*
X851432D01*
G01X853385Y210438D02*
Y208485D01*
G01X842620Y202462D02*
X845820D01*
G01X865076Y231068D02*
X853076D01*
G01D02*
Y237068D01*
G01X853385Y220297D02*
Y218344D01*
G01X851432Y220297D02*
X853385D01*
G01X857183Y229083D02*
X860383D01*
G01X857183Y222883D02*
Y229083D01*
G01X860383Y222883D02*
X857183D01*
G01X853076Y237068D02*
X865076D01*
G01X856492Y242041D02*
X862692D01*
G01X856492Y238841D02*
Y242041D01*
G01X862692Y238841D02*
X856492D01*
G01X854703Y263457D02*
Y266657D01*
G01X860903Y263457D02*
X854703D01*
G01X854733Y271617D02*
Y274817D01*
G01X860933Y271617D02*
X854733D01*
G01Y274817D02*
X860933D01*
G01X848347Y272649D02*
Y269449D01*
G01X855213Y281927D02*
Y285127D01*
G01X861413Y281927D02*
X855213D01*
G01Y281627D02*
X861413D01*
G01X855213Y278427D02*
Y281627D01*
G01X861413Y278427D02*
X855213D01*
G01X854703Y266657D02*
X860903D01*
G01X854703Y267457D02*
Y270657D01*
G01X860903Y267457D02*
X854703D01*
G01Y270657D02*
X860903D01*
G01X855213Y285127D02*
X861413D01*
G01X847105Y282891D02*
X843905D01*
G01X847105Y289091D02*
Y282891D01*
G01X843905Y289091D02*
X847105D01*
G01X843905Y282891D02*
Y289091D01*
G01X847105Y293177D02*
X843905D01*
G01X847105Y299377D02*
Y293177D01*
G01X843905D02*
Y299377D01*
G01D02*
X847105D01*
G01X864100Y376762D02*
X857900D01*
Y379962D01*
X864100D01*
Y376762D01*
G01X861159Y418785D02*
X848481D01*
G01D02*
Y434139D01*
G01X845800Y426000D02*
Y419800D01*
X842600D01*
Y426000D01*
X845800D01*
G01X848678Y434139D02*
X861159D01*
G01X847400Y436600D02*
Y442800D01*
X850600D01*
Y436600D01*
X847400D01*
G01X854000Y471400D02*
X847800D01*
Y474600D01*
X854000D01*
Y471400D01*
G01X847800Y478500D02*
X854000D01*
Y475300D01*
X847800D01*
Y478500D01*
G01X854000Y467500D02*
X847800D01*
Y470700D01*
X854000D01*
Y467500D01*
G01X847937Y490122D02*
Y487900D01*
X848090Y487435D01*
X848397Y487125D01*
X848780Y487022D01*
X849163Y487125D01*
X849470Y487435D01*
X849623Y487900D01*
Y490122D01*
G01X851228Y487384D02*
X851497Y487125D01*
X851803Y487022D01*
X852110Y487125D01*
X852378Y487435D01*
X852570Y487900D01*
X852647Y488365D01*
Y488934D01*
X852570Y489399D01*
X852378Y489812D01*
X852148Y490019D01*
X851880Y490122D01*
X851573Y490019D01*
X851343Y489812D01*
X851190Y489502D01*
X851113Y489089D01*
X851190Y488727D01*
X851382Y488365D01*
X851612Y488159D01*
X851880Y488107D01*
X852187Y488210D01*
X852417Y488469D01*
X852647Y488934D01*
G01X854137Y487487D02*
X854367Y487229D01*
X854635Y487074D01*
X854980Y487022D01*
X855325Y487125D01*
X855593Y487332D01*
X855785Y487694D01*
X855823Y488107D01*
X855747Y488520D01*
X855555Y488779D01*
X855287Y488985D01*
X855018Y489037D01*
X854750Y488985D01*
X854405Y488779D01*
X854520Y490122D01*
X855555D01*
G01X843320Y496962D02*
Y493762D01*
G01X861720Y493700D02*
X855520D01*
Y496900D01*
X861720D01*
Y493700D01*
G01X847782Y507413D02*
Y498751D01*
G01X855520Y501562D02*
Y504762D01*
G01X861720Y501562D02*
X855520D01*
G01Y504762D02*
X861720D01*
G01X855520Y508762D02*
X861720D01*
G01X855520Y505562D02*
Y508762D01*
G01X861720Y505562D02*
X855520D01*
G01Y497462D02*
Y500662D01*
G01X861720Y497462D02*
X855520D01*
G01Y500662D02*
X861720D01*
G01X855670Y513982D02*
Y517182D01*
G01X861870Y513982D02*
X855670D01*
G01Y517182D02*
X861870D01*
G01X855670Y517982D02*
Y521182D01*
G01X861870Y517982D02*
X855670D01*
G01Y521182D02*
X861870D01*
G01X843135Y524624D02*
Y522402D01*
X843288Y521937D01*
X843595Y521627D01*
X843978Y521524D01*
X844361Y521627D01*
X844668Y521937D01*
X844821Y522402D01*
Y524624D01*
G01X846426Y521886D02*
X846695Y521627D01*
X847001Y521524D01*
X847308Y521627D01*
X847576Y521937D01*
X847768Y522402D01*
X847845Y522867D01*
Y523436D01*
X847768Y523901D01*
X847576Y524314D01*
X847346Y524521D01*
X847078Y524624D01*
X846771Y524521D01*
X846541Y524314D01*
X846388Y524004D01*
X846311Y523591D01*
X846388Y523229D01*
X846580Y522867D01*
X846810Y522661D01*
X847078Y522609D01*
X847385Y522712D01*
X847615Y522971D01*
X847845Y523436D01*
G01X850638Y521524D02*
Y524624D01*
X849220Y522402D01*
X851136D01*
G01X848716Y511116D02*
Y519778D01*
G01X854015Y697211D02*
Y735802D01*
G01Y732644D02*
X845800D01*
G01X854015Y740402D02*
Y1313342D01*
G01X858852Y1583493D02*
X855652D01*
G01D02*
Y1589693D01*
G01X853752Y1572193D02*
X847552D01*
Y1575393D01*
X853752D01*
Y1572193D01*
G01Y1583393D02*
Y1580193D01*
G01X847552Y1583393D02*
X853752D01*
G01X847552Y1580193D02*
Y1583393D01*
G01X853752Y1580193D02*
X847552D01*
G01X853752Y1579393D02*
Y1576193D01*
G01X847552D02*
Y1579393D01*
G01X853752Y1576193D02*
X847552D01*
G01Y1579393D02*
X853752D01*
G01Y1599393D02*
Y1596193D01*
G01X847552Y1599393D02*
X853752D01*
G01X847552Y1596193D02*
Y1599393D01*
G01X853752Y1596193D02*
X847552D01*
G01X853752Y1595393D02*
Y1592193D01*
G01X847552D02*
Y1595393D01*
G01X853752Y1592193D02*
X847552D01*
G01Y1595393D02*
X853752D01*
G01X855652Y1589693D02*
X858852D01*
G01X853752Y1603393D02*
Y1600193D01*
G01X847552D02*
Y1603393D01*
G01X853752Y1600193D02*
X847552D01*
G01X853752Y1587393D02*
Y1584193D01*
G01X847552Y1587393D02*
X853752D01*
G01X847552Y1584193D02*
Y1587393D01*
G01X853752Y1584193D02*
X847552D01*
G01Y1603393D02*
X853752D01*
G01Y1607393D02*
Y1604193D01*
G01X847552Y1607393D02*
X853752D01*
G01X847552Y1604193D02*
Y1607393D01*
G01X853752Y1604193D02*
X847552D01*
G01X853752Y1611393D02*
Y1608193D01*
G01X847552D02*
Y1611393D01*
G01X853752Y1608193D02*
X847552D01*
G01Y1611393D02*
X853752D01*
G01X869620Y164762D02*
Y167962D01*
G01X875820Y164762D02*
X869620D01*
G01Y167962D02*
X875820D01*
G01X873688Y193246D02*
Y181434D01*
X859832D01*
Y193246D01*
X873688D01*
G01X869620Y172962D02*
X875820D01*
G01X869620Y169762D02*
Y172962D01*
G01X875820Y169762D02*
X869620D01*
G01Y178462D02*
X875820D01*
G01X869620Y175262D02*
Y178462D01*
G01X875820Y175262D02*
X869620D01*
G01X863937Y202390D02*
Y200168D01*
X864090Y199703D01*
X864397Y199393D01*
X864780Y199290D01*
X865163Y199393D01*
X865470Y199703D01*
X865623Y200168D01*
Y202390D01*
G01X867037Y199910D02*
X867267Y199548D01*
X867573Y199342D01*
X867918Y199290D01*
X868225Y199342D01*
X868532Y199600D01*
X868723Y199910D01*
X868762Y200220D01*
X868685Y200582D01*
X868417Y200840D01*
X868148Y200943D01*
X867803D01*
G01X868148D02*
X868378Y201098D01*
X868570Y201357D01*
X868647Y201667D01*
X868570Y201977D01*
X868378Y202235D01*
X868033Y202390D01*
X867688Y202338D01*
X867343Y202132D01*
G01X870137Y199910D02*
X870367Y199548D01*
X870673Y199342D01*
X871018Y199290D01*
X871325Y199342D01*
X871632Y199600D01*
X871823Y199910D01*
X871862Y200220D01*
X871785Y200582D01*
X871517Y200840D01*
X871248Y200943D01*
X870903D01*
G01X871248D02*
X871478Y201098D01*
X871670Y201357D01*
X871747Y201667D01*
X871670Y201977D01*
X871478Y202235D01*
X871133Y202390D01*
X870788Y202338D01*
X870443Y202132D01*
G01X873352Y200582D02*
X873620Y200943D01*
X873850Y201150D01*
X874157Y201253D01*
X874425Y201150D01*
X874617Y200943D01*
X874770Y200633D01*
X874808Y200272D01*
X874770Y199962D01*
X874617Y199652D01*
X874387Y199393D01*
X874118Y199290D01*
X873812Y199393D01*
X873543Y199703D01*
X873390Y200168D01*
X873352Y200685D01*
X873428Y201357D01*
X873543Y201718D01*
X873735Y202080D01*
X874003Y202338D01*
X874272Y202390D01*
X874540Y202287D01*
X874732Y202028D01*
G01X870600Y194900D02*
X864400D01*
Y198100D01*
X870600D01*
Y194900D01*
G01X865076Y237068D02*
Y231068D01*
G01X860383Y229083D02*
Y222883D01*
G01X869993Y229363D02*
Y226163D01*
G01X863793Y229363D02*
X869993D01*
G01X863793Y226163D02*
Y229363D01*
G01X869993Y226163D02*
X863793D01*
G01X869993Y225363D02*
Y222163D01*
G01X863793Y225363D02*
X869993D01*
G01X863793Y222163D02*
Y225363D01*
G01X869993Y222163D02*
X863793D01*
G01X862692Y242041D02*
Y238841D01*
G01X860903Y266657D02*
Y263457D01*
G01X861694Y264436D02*
Y270636D01*
G01X864894Y264436D02*
X861694D01*
G01X864894Y270636D02*
Y264436D01*
G01X866325Y274923D02*
X880301D01*
G01X866325Y283111D02*
Y274923D01*
G01X860933Y274817D02*
Y271617D01*
G01X861413Y285127D02*
Y281927D01*
G01Y281627D02*
Y278427D01*
G01X861694Y270636D02*
X864894D01*
G01X860903Y270657D02*
Y267457D01*
G01X880301Y283111D02*
X866325D01*
G01X869143Y290911D02*
Y287711D01*
G01X862943Y290911D02*
X869143D01*
G01X862943Y287711D02*
Y290911D01*
G01X869143Y287711D02*
X862943D01*
G01X861971Y298485D02*
X865171D01*
G01X861971Y292285D02*
Y298485D01*
G01X865171Y292285D02*
X861971D01*
G01X865171Y298485D02*
Y292285D01*
G01X865971Y298485D02*
X869171D01*
G01X865971Y292285D02*
Y298485D01*
G01X869171Y292285D02*
X865971D01*
G01X869171Y298485D02*
Y292285D01*
G01X863386Y393020D02*
Y396220D01*
G01X869586Y393020D02*
X863386D01*
G01X869586Y396220D02*
Y393020D01*
G01X863386Y396220D02*
X869586D01*
G01X863386Y392220D02*
X869586D01*
Y389020D01*
X863386D01*
Y392220D01*
G01X869586Y388076D02*
Y384876D01*
G01X863386Y388076D02*
X869586D01*
G01X863386Y384876D02*
Y388076D01*
G01X869586Y384876D02*
X863386D01*
G01Y380815D02*
Y384015D01*
G01X869586Y380815D02*
X863386D01*
G01X869586Y384015D02*
Y380815D01*
G01X863386Y384015D02*
X869586D01*
G01Y404181D02*
Y400981D01*
G01X863386Y404181D02*
X869586D01*
G01X863386Y400981D02*
Y404181D01*
G01X869586Y400981D02*
X863386D01*
G01X863438Y405212D02*
Y408412D01*
G01X869638Y405212D02*
X863438D01*
G01X869638Y408412D02*
Y405212D01*
G01X863438Y408412D02*
X869638D01*
G01Y415876D02*
Y412676D01*
G01X863438D02*
Y415876D01*
G01X869638Y412676D02*
X863438D01*
G01X869586Y397020D02*
X863386D01*
Y400220D01*
X869586D01*
Y397020D01*
G01X863199Y427124D02*
Y424902D01*
X863352Y424437D01*
X863659Y424127D01*
X864042Y424024D01*
X864425Y424127D01*
X864732Y424437D01*
X864885Y424902D01*
Y427124D01*
G01X867142Y424024D02*
X867410Y424076D01*
X867717Y424231D01*
X867909Y424489D01*
X867985Y424851D01*
X867909Y425212D01*
X867679Y425522D01*
X867334Y425677D01*
X866950D01*
X866720Y425781D01*
X866529Y426039D01*
X866452Y426401D01*
X866567Y426762D01*
X866835Y427021D01*
X867142Y427124D01*
X867449Y427021D01*
X867717Y426762D01*
X867832Y426401D01*
X867755Y426039D01*
X867564Y425781D01*
X867334Y425677D01*
X866950D01*
X866605Y425522D01*
X866375Y425212D01*
X866299Y424851D01*
X866375Y424489D01*
X866567Y424231D01*
X866874Y424076D01*
X867142Y424024D01*
G01X869590Y424386D02*
X869859Y424127D01*
X870165Y424024D01*
X870472Y424127D01*
X870740Y424437D01*
X870932Y424902D01*
X871009Y425367D01*
Y425936D01*
X870932Y426401D01*
X870740Y426814D01*
X870510Y427021D01*
X870242Y427124D01*
X869935Y427021D01*
X869705Y426814D01*
X869552Y426504D01*
X869475Y426091D01*
X869552Y425729D01*
X869744Y425367D01*
X869974Y425161D01*
X870242Y425109D01*
X870549Y425212D01*
X870779Y425471D01*
X871009Y425936D01*
G01X861159Y434139D02*
Y418785D01*
G01X863438Y415876D02*
X869638D01*
G01X863438Y417236D02*
Y420436D01*
G01X869638Y417236D02*
X863438D01*
G01X869638Y420436D02*
Y417236D01*
G01X863438Y420436D02*
X869638D01*
G01X875027Y433779D02*
Y436879D01*
X875793D01*
X876100Y436724D01*
X876330Y436517D01*
X876522Y436207D01*
X876675Y435846D01*
X876713Y435329D01*
X876675Y434812D01*
X876522Y434451D01*
X876330Y434141D01*
X876100Y433934D01*
X875793Y433779D01*
X875027D01*
G01X878970Y436879D02*
X878663Y436776D01*
X878433Y436517D01*
X878280Y436207D01*
X878165Y435794D01*
X878127Y435329D01*
X878165Y434864D01*
X878280Y434451D01*
X878433Y434141D01*
X878663Y433882D01*
X878970Y433779D01*
X879277Y433882D01*
X879507Y434141D01*
X879660Y434451D01*
X879775Y434864D01*
X879813Y435329D01*
X879775Y435794D01*
X879660Y436207D01*
X879507Y436517D01*
X879277Y436776D01*
X878970Y436879D01*
G01X867840Y435562D02*
X860750D01*
Y439362D01*
X867840D01*
G01X868440Y435562D02*
X861250D01*
Y439362D01*
X868440D01*
G01X868840Y435562D02*
X861750D01*
Y439362D01*
X868890D01*
Y435612D01*
G01X863220Y429862D02*
Y433062D01*
G01X869420Y429862D02*
X863220D01*
G01X869420Y433062D02*
Y429862D01*
G01X863220Y433062D02*
X869420D01*
G01X861720Y504762D02*
Y501562D01*
G01Y508762D02*
Y505562D01*
G01Y500662D02*
Y497462D01*
G01X861870Y517182D02*
Y513982D01*
G01Y521182D02*
Y517982D01*
G01X869807Y899962D02*
Y897740D01*
X869960Y897275D01*
X870267Y896965D01*
X870650Y896862D01*
X871033Y896965D01*
X871340Y897275D01*
X871493Y897740D01*
Y899962D01*
G01X872907Y897482D02*
X873137Y897120D01*
X873443Y896914D01*
X873788Y896862D01*
X874095Y896914D01*
X874402Y897172D01*
X874593Y897482D01*
X874632Y897792D01*
X874555Y898154D01*
X874287Y898412D01*
X874018Y898515D01*
X873673D01*
G01X874018D02*
X874248Y898670D01*
X874440Y898929D01*
X874517Y899239D01*
X874440Y899549D01*
X874248Y899807D01*
X873903Y899962D01*
X873558Y899910D01*
X873213Y899704D01*
G01X876850Y896862D02*
Y899962D01*
X876390Y899342D01*
G01Y896862D02*
X877310D01*
G01X858852Y1589693D02*
Y1583493D01*
G01X861970Y1595632D02*
Y1575414D01*
G01D02*
X882188D01*
G01Y1595632D02*
X861970D01*
G01X865988Y1615160D02*
Y1618260D01*
X866908D01*
X867215Y1618105D01*
X867445Y1617743D01*
X867522Y1617330D01*
X867445Y1616917D01*
X867253Y1616607D01*
X866908Y1616452D01*
X865988D01*
G01X869012Y1618260D02*
Y1616038D01*
X869165Y1615573D01*
X869472Y1615263D01*
X869855Y1615160D01*
X870238Y1615263D01*
X870545Y1615573D01*
X870698Y1616038D01*
Y1618260D01*
G01X872227Y1617743D02*
X872457Y1618053D01*
X872725Y1618208D01*
X873032Y1618260D01*
X873415Y1618157D01*
X873683Y1617898D01*
X873760Y1617588D01*
X873722Y1617278D01*
X873568Y1617020D01*
X872802Y1616503D01*
X872457Y1616142D01*
X872227Y1615625D01*
X872150Y1615160D01*
X873760D01*
G01X875403Y1615522D02*
X875672Y1615263D01*
X875978Y1615160D01*
X876285Y1615263D01*
X876553Y1615573D01*
X876745Y1616038D01*
X876822Y1616503D01*
Y1617072D01*
X876745Y1617537D01*
X876553Y1617950D01*
X876323Y1618157D01*
X876055Y1618260D01*
X875748Y1618157D01*
X875518Y1617950D01*
X875365Y1617640D01*
X875288Y1617227D01*
X875365Y1616865D01*
X875557Y1616503D01*
X875787Y1616297D01*
X876055Y1616245D01*
X876362Y1616348D01*
X876592Y1616607D01*
X876822Y1617072D01*
G01X878427Y1616452D02*
X878695Y1616813D01*
X878925Y1617020D01*
X879232Y1617123D01*
X879500Y1617020D01*
X879692Y1616813D01*
X879845Y1616503D01*
X879883Y1616142D01*
X879845Y1615832D01*
X879692Y1615522D01*
X879462Y1615263D01*
X879193Y1615160D01*
X878887Y1615263D01*
X878618Y1615573D01*
X878465Y1616038D01*
X878427Y1616555D01*
X878503Y1617227D01*
X878618Y1617588D01*
X878810Y1617950D01*
X879078Y1618208D01*
X879347Y1618260D01*
X879615Y1618157D01*
X879807Y1617898D01*
G01X885872Y1682410D02*
X866688D01*
G01X875820Y167962D02*
Y164762D01*
G01Y172962D02*
Y169762D01*
G01Y178462D02*
Y175262D01*
G01X877620D02*
Y178462D01*
G01X883820Y175262D02*
X877620D01*
G01X883820Y178462D02*
Y175262D01*
G01X877620Y178462D02*
X883820D01*
G01X877620Y169762D02*
Y172962D01*
G01X883820Y169762D02*
X877620D01*
G01X883820Y172962D02*
Y169762D01*
G01X877620Y172962D02*
X883820D01*
G01X879615Y181569D02*
Y184769D01*
G01X885815Y181569D02*
X879615D01*
G01X885815Y184769D02*
Y181569D01*
G01X879615Y184769D02*
X885815D01*
G01X885900Y202750D02*
Y199550D01*
G01X879700D02*
Y202750D01*
G01X885900Y199550D02*
X879700D01*
G01X885900Y197320D02*
Y194120D01*
G01X879700Y197320D02*
X885900D01*
G01X879700Y194120D02*
Y197320D01*
G01X885900Y194120D02*
X879700D01*
G01X885825Y193655D02*
Y190455D01*
G01X879625Y193655D02*
X885825D01*
G01X879625Y190455D02*
Y193655D01*
G01X885825Y190455D02*
X879625D01*
G01Y185849D02*
Y189049D01*
G01X885825Y185849D02*
X879625D01*
G01X885825Y189049D02*
Y185849D01*
G01X879625Y189049D02*
X885825D01*
G01X875283Y210133D02*
Y241933D01*
X889083D01*
Y210133D01*
X875283D01*
G01X879700Y202750D02*
X885900D01*
G01X882280Y245451D02*
Y248551D01*
X883200D01*
X883507Y248396D01*
X883737Y248034D01*
X883814Y247621D01*
X883737Y247208D01*
X883545Y246898D01*
X883200Y246743D01*
X882280D01*
G01X885304Y245451D02*
Y248551D01*
X886070D01*
X886377Y248396D01*
X886607Y248189D01*
X886799Y247879D01*
X886952Y247518D01*
X886990Y247001D01*
X886952Y246484D01*
X886799Y246123D01*
X886607Y245813D01*
X886377Y245606D01*
X886070Y245451D01*
X885304D01*
G01X889247D02*
Y248551D01*
X888787Y247931D01*
G01Y245451D02*
X889707D01*
G01X892347D02*
Y248551D01*
X891887Y247931D01*
G01Y245451D02*
X892807D01*
G01X894604Y246071D02*
X894834Y245709D01*
X895140Y245503D01*
X895485Y245451D01*
X895792Y245503D01*
X896099Y245761D01*
X896290Y246071D01*
X896329Y246381D01*
X896252Y246743D01*
X895984Y247001D01*
X895715Y247104D01*
X895370D01*
G01X895715D02*
X895945Y247259D01*
X896137Y247518D01*
X896214Y247828D01*
X896137Y248138D01*
X895945Y248396D01*
X895600Y248551D01*
X895255Y248499D01*
X894910Y248293D01*
G01X878420Y256540D02*
X880846D01*
G01X881960Y261988D02*
X911519D01*
G01X881960Y250492D02*
Y261988D01*
G01X911519Y250492D02*
X881960D01*
G01X881828Y265807D02*
Y269007D01*
G01X888028Y265807D02*
X881828D01*
G01X888028Y269007D02*
Y265807D01*
G01X891308Y277565D02*
Y280665D01*
X892228D01*
X892535Y280510D01*
X892765Y280148D01*
X892842Y279735D01*
X892765Y279322D01*
X892573Y279012D01*
X892228Y278857D01*
X891308D01*
G01X894332Y280665D02*
Y278443D01*
X894485Y277978D01*
X894792Y277668D01*
X895175Y277565D01*
X895558Y277668D01*
X895865Y277978D01*
X896018Y278443D01*
Y280665D01*
G01X897547Y280148D02*
X897777Y280458D01*
X898045Y280613D01*
X898352Y280665D01*
X898735Y280562D01*
X899003Y280303D01*
X899080Y279993D01*
X899042Y279683D01*
X898888Y279425D01*
X898122Y278908D01*
X897777Y278547D01*
X897547Y278030D01*
X897470Y277565D01*
X899080D01*
G01X900723Y277927D02*
X900992Y277668D01*
X901298Y277565D01*
X901605Y277668D01*
X901873Y277978D01*
X902065Y278443D01*
X902142Y278908D01*
Y279477D01*
X902065Y279942D01*
X901873Y280355D01*
X901643Y280562D01*
X901375Y280665D01*
X901068Y280562D01*
X900838Y280355D01*
X900685Y280045D01*
X900608Y279632D01*
X900685Y279270D01*
X900877Y278908D01*
X901107Y278702D01*
X901375Y278650D01*
X901682Y278753D01*
X901912Y279012D01*
X902142Y279477D01*
G01X903632Y278030D02*
X903862Y277772D01*
X904130Y277617D01*
X904475Y277565D01*
X904820Y277668D01*
X905088Y277875D01*
X905280Y278237D01*
X905318Y278650D01*
X905242Y279063D01*
X905050Y279322D01*
X904782Y279528D01*
X904513Y279580D01*
X904245Y279528D01*
X903900Y279322D01*
X904015Y280665D01*
X905050D01*
G01X880301Y274923D02*
Y283111D01*
G01X881828Y269007D02*
X888028D01*
G01X884903Y276007D02*
X888103D01*
G01X884903Y269807D02*
Y276007D01*
G01X888103Y269807D02*
X884903D01*
G01X888103Y276007D02*
Y269807D01*
G01Y277187D02*
X884903D01*
G01X888103Y283387D02*
Y277187D01*
G01X884903D02*
Y283387D01*
G01X876315Y287839D02*
Y291039D01*
G01X882515Y287839D02*
X876315D01*
G01X882515Y291039D02*
Y287839D01*
G01X876315Y291039D02*
X882515D01*
G01X882543Y294947D02*
Y291747D01*
G01X876343Y294947D02*
X882543D01*
G01X876343Y291747D02*
Y294947D01*
G01X882543Y291747D02*
X876343D01*
G01X882566Y300265D02*
Y297065D01*
G01X876366D02*
Y300265D01*
G01X882566Y297065D02*
X876366D01*
G01X884903Y283387D02*
X888103D01*
G01X876366Y300265D02*
X882566D01*
G01X893347Y866254D02*
X890147D01*
G01D02*
Y872454D01*
G01X889497Y866254D02*
X886297D01*
G01X889497Y872454D02*
Y866254D01*
G01X886297D02*
Y872454D01*
G01X879172Y881435D02*
X882372D01*
G01X879172Y875235D02*
Y881435D01*
G01X882372Y875235D02*
X879172D01*
G01X882372Y881435D02*
Y875235D01*
G01X890147Y872454D02*
X893347D01*
G01X890222Y876005D02*
X896422D01*
G01X890222Y872805D02*
Y876005D01*
G01X896422Y872805D02*
X890222D01*
G01X886297Y872454D02*
X889497D01*
G01X883222Y872805D02*
Y876005D01*
G01X889422Y872805D02*
X883222D01*
G01X889422Y876005D02*
Y872805D01*
G01X883222Y876005D02*
X889422D01*
G01X879600Y891762D02*
X899400D01*
G01X879600Y895562D02*
Y891762D01*
G01X881400Y897362D02*
X879600Y895562D01*
G01Y899162D02*
X881400Y897362D01*
G01X879600Y902962D02*
Y899162D01*
G01X899400Y902962D02*
X879600D01*
G01X882972Y913355D02*
X879772D01*
G01X882972Y919555D02*
Y913355D01*
G01X879772D02*
Y919555D01*
G01D02*
X882972D01*
G01X890792Y921925D02*
X896992D01*
G01X890792Y918725D02*
Y921925D01*
G01X896992Y918725D02*
X890792D01*
G01X883792Y921925D02*
X889992D01*
G01X883792Y918725D02*
Y921925D01*
G01X889992Y918725D02*
X883792D01*
G01X889992Y921925D02*
Y918725D01*
G01X884170Y1504582D02*
X884917Y1503957D01*
X885757Y1503582D01*
X886503D01*
X887250Y1503957D01*
X887810Y1504582D01*
X888090Y1505457D01*
X887903Y1506332D01*
X887437Y1507082D01*
X886597Y1507582D01*
X885477Y1507832D01*
X884823Y1508332D01*
X884543Y1509207D01*
X884730Y1510082D01*
X885197Y1510707D01*
X885850Y1511082D01*
X886503D01*
X887157Y1510832D01*
X887717Y1510207D01*
G01X891950Y1503332D02*
X895310Y1511082D01*
G01X898983Y1503582D02*
Y1511082D01*
X903277Y1503582D01*
Y1511082D01*
G01X882530Y1494882D02*
Y1488882D01*
X888530D01*
G01X882283Y1514849D02*
Y1517949D01*
X883280Y1515366D01*
X884277Y1517949D01*
Y1514849D01*
G01X887147D02*
X885613D01*
Y1517949D01*
X887147D01*
G01X886533Y1516451D02*
X885613D01*
G01X888752Y1517432D02*
X888982Y1517742D01*
X889250Y1517897D01*
X889557Y1517949D01*
X889940Y1517846D01*
X890208Y1517587D01*
X890285Y1517277D01*
X890247Y1516967D01*
X890093Y1516709D01*
X889327Y1516192D01*
X888982Y1515831D01*
X888752Y1515314D01*
X888675Y1514849D01*
X890285D01*
G01X891852Y1517432D02*
X892082Y1517742D01*
X892350Y1517897D01*
X892657Y1517949D01*
X893040Y1517846D01*
X893308Y1517587D01*
X893385Y1517277D01*
X893347Y1516967D01*
X893193Y1516709D01*
X892427Y1516192D01*
X892082Y1515831D01*
X891852Y1515314D01*
X891775Y1514849D01*
X893385D01*
G01X888530Y1512504D02*
X882530D01*
Y1506504D01*
G01X895752Y1572193D02*
X889552D01*
Y1575393D01*
X895752D01*
Y1572193D01*
G01X889552Y1583393D02*
X895752D01*
G01X889552Y1580193D02*
Y1583393D01*
G01X895752Y1580193D02*
X889552D01*
G01Y1576193D02*
Y1579393D01*
G01X895752Y1576193D02*
X889552D01*
G01Y1579393D02*
X895752D01*
G01X882188Y1575414D02*
Y1595632D01*
G01X889552Y1599393D02*
X895752D01*
G01X889552Y1596193D02*
Y1599393D01*
G01X895752Y1596193D02*
X889552D01*
G01Y1592193D02*
Y1595393D01*
G01X895752Y1592193D02*
X889552D01*
G01Y1595393D02*
X895752D01*
G01X889552Y1587393D02*
X895752D01*
G01X889552Y1584193D02*
Y1587393D01*
G01X895752Y1584193D02*
X889552D01*
G01Y1600193D02*
Y1603393D01*
G01X895752Y1600193D02*
X889552D01*
G01Y1603393D02*
X895752D01*
G01X889552Y1608193D02*
Y1611393D01*
G01X895752Y1608193D02*
X889552D01*
G01Y1611393D02*
X895752D01*
G01X889552Y1607393D02*
X895752D01*
G01X889552Y1604193D02*
Y1607393D01*
G01X895752Y1604193D02*
X889552D01*
G01X960235Y321653D02*
G03I-31496J0D01*
G01X903953Y486513D02*
Y484960D01*
G01X897753Y486513D02*
X903953D01*
G01X897753Y484570D02*
Y486513D01*
G01X902850Y483313D02*
X898450D01*
G01X897753Y479313D02*
Y481560D01*
G01X903953Y479313D02*
X897753D01*
G01X898450Y482513D02*
X902850D01*
G01X903953Y481180D02*
Y479313D01*
G01X903748Y494899D02*
Y492970D01*
G01X897548Y493100D02*
Y494899D01*
G01X902340Y491699D02*
X898600D01*
G01X897548Y487699D02*
Y489650D01*
G01X903748Y487699D02*
X897548D01*
G01X898600Y490899D02*
X902340D01*
G01X903748Y489550D02*
Y487699D01*
G01X903733Y503173D02*
Y501410D01*
G01X897533Y503173D02*
X903733D01*
G01X902340Y499973D02*
X899330D01*
G01X897533Y501150D02*
Y503173D01*
G01Y495973D02*
Y497730D01*
G01X903733Y495973D02*
X897533D01*
G01X903733Y497690D02*
Y495973D01*
G01X899330Y499173D02*
X902340D01*
G01X897548Y494899D02*
X903748D01*
G01X893347Y872454D02*
Y866254D01*
G01X896422Y876005D02*
Y872805D01*
G01X899400Y891762D02*
Y902962D01*
G01X896992Y921925D02*
Y918725D01*
G01X903389Y976734D02*
X909589D01*
G01X903389Y973534D02*
Y976734D01*
G01X909589Y973534D02*
X903389D01*
G01Y972834D02*
X909589D01*
G01X903389Y969634D02*
Y972834D01*
G01X909589Y969634D02*
X903389D01*
G01Y994434D02*
X909589D01*
G01X903389Y991234D02*
Y994434D01*
G01X909589Y991234D02*
X903389D01*
G01Y990534D02*
X909589D01*
G01X903389Y987334D02*
Y990534D01*
G01X909589Y987334D02*
X903389D01*
G01X895782Y1126391D02*
Y1129491D01*
X896779Y1126908D01*
X897776Y1129491D01*
Y1126391D01*
G01X900646D02*
X899112D01*
Y1129491D01*
X900646D01*
G01X900032Y1127993D02*
X899112D01*
G01X902979Y1126391D02*
Y1129491D01*
X902519Y1128871D01*
G01Y1126391D02*
X903439D01*
G01X906079Y1129491D02*
X905772Y1129388D01*
X905542Y1129129D01*
X905389Y1128819D01*
X905274Y1128406D01*
X905236Y1127941D01*
X905274Y1127476D01*
X905389Y1127063D01*
X905542Y1126753D01*
X905772Y1126494D01*
X906079Y1126391D01*
X906386Y1126494D01*
X906616Y1126753D01*
X906769Y1127063D01*
X906884Y1127476D01*
X906922Y1127941D01*
X906884Y1128406D01*
X906769Y1128819D01*
X906616Y1129129D01*
X906386Y1129388D01*
X906079Y1129491D01*
G01X897652Y1583493D02*
Y1589693D01*
G01X900852Y1583493D02*
X897652D01*
G01X900852Y1589693D02*
Y1583493D01*
G01X895752Y1583393D02*
Y1580193D01*
G01Y1579393D02*
Y1576193D01*
G01X903970Y1595632D02*
Y1575414D01*
G01D02*
X924188D01*
G01X897652Y1589693D02*
X900852D01*
G01X895752Y1599393D02*
Y1596193D01*
G01Y1595393D02*
Y1592193D01*
G01Y1587393D02*
Y1584193D01*
G01Y1603393D02*
Y1600193D01*
G01X924188Y1595632D02*
X903970D01*
G01X895752Y1611393D02*
Y1608193D01*
G01Y1607393D02*
Y1604193D01*
G01X905598Y1614450D02*
Y1617550D01*
X906518D01*
X906825Y1617395D01*
X907055Y1617033D01*
X907132Y1616620D01*
X907055Y1616207D01*
X906863Y1615897D01*
X906518Y1615742D01*
X905598D01*
G01X908622Y1617550D02*
Y1615328D01*
X908775Y1614863D01*
X909082Y1614553D01*
X909465Y1614450D01*
X909848Y1614553D01*
X910155Y1614863D01*
X910308Y1615328D01*
Y1617550D01*
G01X911837Y1617033D02*
X912067Y1617343D01*
X912335Y1617498D01*
X912642Y1617550D01*
X913025Y1617447D01*
X913293Y1617188D01*
X913370Y1616878D01*
X913332Y1616568D01*
X913178Y1616310D01*
X912412Y1615793D01*
X912067Y1615432D01*
X911837Y1614915D01*
X911760Y1614450D01*
X913370D01*
G01X915013Y1614812D02*
X915282Y1614553D01*
X915588Y1614450D01*
X915895Y1614553D01*
X916163Y1614863D01*
X916355Y1615328D01*
X916432Y1615793D01*
Y1616362D01*
X916355Y1616827D01*
X916163Y1617240D01*
X915933Y1617447D01*
X915665Y1617550D01*
X915358Y1617447D01*
X915128Y1617240D01*
X914975Y1616930D01*
X914898Y1616517D01*
X914975Y1616155D01*
X915167Y1615793D01*
X915397Y1615587D01*
X915665Y1615535D01*
X915972Y1615638D01*
X916202Y1615897D01*
X916432Y1616362D01*
G01X918688Y1614450D02*
X918765Y1615122D01*
X918880Y1615690D01*
X919033Y1616207D01*
X919225Y1616775D01*
X919532Y1617550D01*
X917998D01*
G01X901523Y1671640D02*
Y1679140D01*
X903763D01*
X904510Y1678765D01*
X905070Y1677890D01*
X905257Y1676890D01*
X905070Y1675890D01*
X904603Y1675140D01*
X903763Y1674765D01*
X901523D01*
G01X909023Y1671640D02*
Y1679140D01*
X911357D01*
X912103Y1678765D01*
X912570Y1678265D01*
X912757Y1677265D01*
X912570Y1676265D01*
X912010Y1675640D01*
X911357Y1675265D01*
X909023D01*
G01X911357D02*
X912757Y1671640D01*
G01X920257D02*
X916523D01*
Y1679140D01*
X920257D01*
G01X918763Y1675515D02*
X916523D01*
G01X923930Y1672640D02*
X924677Y1672015D01*
X925517Y1671640D01*
X926263D01*
X927010Y1672015D01*
X927570Y1672640D01*
X927850Y1673515D01*
X927663Y1674390D01*
X927197Y1675140D01*
X926357Y1675640D01*
X925237Y1675890D01*
X924583Y1676390D01*
X924303Y1677265D01*
X924490Y1678140D01*
X924957Y1678765D01*
X925610Y1679140D01*
X926263D01*
X926917Y1678890D01*
X927477Y1678265D01*
G01X931430Y1672640D02*
X932177Y1672015D01*
X933017Y1671640D01*
X933763D01*
X934510Y1672015D01*
X935070Y1672640D01*
X935350Y1673515D01*
X935163Y1674390D01*
X934697Y1675140D01*
X933857Y1675640D01*
X932737Y1675890D01*
X932083Y1676390D01*
X931803Y1677265D01*
X931990Y1678140D01*
X932457Y1678765D01*
X933110Y1679140D01*
X933763D01*
X934417Y1678890D01*
X934977Y1678265D01*
G01X939677Y1674140D02*
X942103D01*
G01X946617Y1671640D02*
Y1679140D01*
X950163D01*
G01X948857Y1675515D02*
X946617D01*
G01X954770Y1679140D02*
X957010D01*
G01X955890D02*
Y1671640D01*
G01X954770D02*
X957010D01*
G01X963390Y1679140D02*
Y1671640D01*
G01X961243Y1679140D02*
X965537D01*
G01X915872Y1682410D02*
X901688D01*
G01X910039Y151358D02*
Y204968D01*
G01X910335Y151752D02*
Y204968D01*
G01X916420Y151358D02*
X910039D01*
G01X916015Y151752D02*
X910335D01*
G01X910039Y214779D02*
Y219374D01*
G01X910335Y214779D02*
Y219374D01*
G01X910039Y207904D02*
Y212417D01*
G01X910335Y207904D02*
Y212417D01*
G01X910039Y229235D02*
Y246752D01*
G01Y222119D02*
Y226522D01*
G01X910335Y229235D02*
Y246358D01*
G01Y222119D02*
Y226522D01*
G01X910039Y246752D02*
X916420D01*
G01X910335Y246358D02*
X916015D01*
G01X923437Y255642D02*
X921903D01*
Y258742D01*
X923437D01*
G01X922823Y257244D02*
X921903D01*
G01X925770Y255642D02*
Y258742D01*
X925310Y258122D01*
G01Y255642D02*
X926230D01*
G01X928870Y255539D02*
X928793Y255590D01*
Y255694D01*
X928870Y255745D01*
X928947Y255694D01*
Y255590D01*
X928870Y255539D01*
G01X931165Y256055D02*
X931472Y255797D01*
X931817Y255642D01*
X932123D01*
X932430Y255797D01*
X932660Y256055D01*
X932775Y256417D01*
X932698Y256779D01*
X932507Y257089D01*
X932162Y257295D01*
X931702Y257399D01*
X931433Y257605D01*
X931318Y257967D01*
X931395Y258329D01*
X931587Y258587D01*
X931855Y258742D01*
X932123D01*
X932392Y258639D01*
X932622Y258380D01*
G01X937365Y256055D02*
X937672Y255797D01*
X938017Y255642D01*
X938323D01*
X938630Y255797D01*
X938860Y256055D01*
X938975Y256417D01*
X938898Y256779D01*
X938707Y257089D01*
X938362Y257295D01*
X937902Y257399D01*
X937633Y257605D01*
X937518Y257967D01*
X937595Y258329D01*
X937787Y258587D01*
X938055Y258742D01*
X938323D01*
X938592Y258639D01*
X938822Y258380D01*
G01X940503Y258742D02*
Y255642D01*
X942037D01*
G01X944370D02*
X944063Y255694D01*
X943795Y255900D01*
X943565Y256210D01*
X943412Y256572D01*
X943335Y256985D01*
Y257399D01*
X943412Y257812D01*
X943565Y258174D01*
X943795Y258484D01*
X944063Y258690D01*
X944370Y258742D01*
X944677Y258690D01*
X944945Y258484D01*
X945175Y258174D01*
X945328Y257812D01*
X945405Y257399D01*
Y256985D01*
X945328Y256572D01*
X945175Y256210D01*
X944945Y255900D01*
X944677Y255694D01*
X944370Y255642D01*
G01X947470Y258742D02*
Y255642D01*
G01X946588Y258742D02*
X948352D01*
G01X953670D02*
X953363Y258639D01*
X953133Y258380D01*
X952980Y258070D01*
X952865Y257657D01*
X952827Y257192D01*
X952865Y256727D01*
X952980Y256314D01*
X953133Y256004D01*
X953363Y255745D01*
X953670Y255642D01*
X953977Y255745D01*
X954207Y256004D01*
X954360Y256314D01*
X954475Y256727D01*
X954513Y257192D01*
X954475Y257657D01*
X954360Y258070D01*
X954207Y258380D01*
X953977Y258639D01*
X953670Y258742D01*
G01X959678Y254609D02*
X959295Y255125D01*
X959103Y255642D01*
Y257709D01*
X959295Y258225D01*
X959678Y258742D01*
G01X962203Y255642D02*
Y258742D01*
X963123D01*
X963430Y258587D01*
X963660Y258225D01*
X963737Y257812D01*
X963660Y257399D01*
X963468Y257089D01*
X963123Y256934D01*
X962203D01*
G01X966913Y258484D02*
X966683Y258639D01*
X966415Y258742D01*
X966108D01*
X965763Y258587D01*
X965495Y258329D01*
X965303Y258019D01*
X965150Y257502D01*
X965112Y257037D01*
X965188Y256572D01*
X965303Y256262D01*
X965533Y255952D01*
X965802Y255745D01*
X966070Y255642D01*
X966338D01*
X966607Y255745D01*
X966837Y255900D01*
X967028Y256107D01*
G01X968710Y258742D02*
X969630D01*
G01X969170D02*
Y255642D01*
G01X968710D02*
X969630D01*
G01X971695Y257037D02*
X972922D01*
X972807Y257399D01*
X972615Y257605D01*
X972347Y257709D01*
X972078Y257657D01*
X971848Y257502D01*
X971695Y257140D01*
X971618Y256830D01*
Y256520D01*
X971695Y256210D01*
X971887Y255900D01*
X972117Y255694D01*
X972385Y255642D01*
X972653Y255745D01*
X972922Y256055D01*
G01X977895Y257709D02*
X979045Y255642D01*
G01Y257709D02*
X977895Y255642D01*
G01X982030D02*
Y258742D01*
X980612Y256520D01*
X982528D01*
G01X984862Y254609D02*
X985245Y255125D01*
X985437Y255642D01*
Y257709D01*
X985245Y258225D01*
X984862Y258742D01*
G01X915160Y256640D02*
X912920D01*
G01X914133Y255015D02*
Y258265D01*
G01X911519Y261988D02*
Y250492D01*
G01X920923Y261772D02*
X921115Y261462D01*
X921345Y261255D01*
X921613Y261152D01*
X921920Y261255D01*
X922150Y261462D01*
X922380Y261772D01*
X922457Y262185D01*
Y264252D01*
G01X924138Y261514D02*
X924407Y261255D01*
X924713Y261152D01*
X925020Y261255D01*
X925288Y261565D01*
X925480Y262030D01*
X925557Y262495D01*
Y263064D01*
X925480Y263529D01*
X925288Y263942D01*
X925058Y264149D01*
X924790Y264252D01*
X924483Y264149D01*
X924253Y263942D01*
X924100Y263632D01*
X924023Y263219D01*
X924100Y262857D01*
X924292Y262495D01*
X924522Y262289D01*
X924790Y262237D01*
X925097Y262340D01*
X925327Y262599D01*
X925557Y263064D01*
G01X927890Y264252D02*
X927583Y264149D01*
X927353Y263890D01*
X927200Y263580D01*
X927085Y263167D01*
X927047Y262702D01*
X927085Y262237D01*
X927200Y261824D01*
X927353Y261514D01*
X927583Y261255D01*
X927890Y261152D01*
X928197Y261255D01*
X928427Y261514D01*
X928580Y261824D01*
X928695Y262237D01*
X928733Y262702D01*
X928695Y263167D01*
X928580Y263580D01*
X928427Y263890D01*
X928197Y264149D01*
X927890Y264252D01*
G01X907693Y460328D02*
Y466528D01*
G01X909670Y460328D02*
X907693D01*
G01X914893D02*
X912980D01*
G01X914893Y466528D02*
Y460328D01*
G01X907693Y466528D02*
X909290D01*
G01X910893Y464900D02*
Y461780D01*
G01X911693D02*
Y464900D01*
G01X913320Y466528D02*
X914893D01*
G01X919147Y472327D02*
X921180D01*
G01X919147Y466127D02*
Y472327D01*
G01X922347Y470660D02*
Y467610D01*
G01X921100Y466127D02*
X919147D01*
G01X923147Y467610D02*
Y470660D01*
G01X913181Y487078D02*
X916010D01*
G01X918830D02*
X923720D01*
G01X913181Y491900D02*
Y490640D01*
G01Y487920D02*
Y487078D01*
G01Y511094D02*
Y508220D01*
G01Y505660D02*
Y504530D01*
G01Y501640D02*
Y500440D01*
G01Y497690D02*
Y494380D01*
G01X922040Y511094D02*
X920540D01*
G01X918150D02*
X916620D01*
G01X913800D02*
X913181D01*
G01X912857Y776651D02*
Y779751D01*
G01X914467D02*
Y776651D01*
G01Y778201D02*
X912857D01*
G01X916110Y777013D02*
X916379Y776754D01*
X916685Y776651D01*
X916992Y776754D01*
X917260Y777064D01*
X917452Y777529D01*
X917529Y777994D01*
Y778563D01*
X917452Y779028D01*
X917260Y779441D01*
X917030Y779648D01*
X916762Y779751D01*
X916455Y779648D01*
X916225Y779441D01*
X916072Y779131D01*
X915995Y778718D01*
X916072Y778356D01*
X916264Y777994D01*
X916494Y777788D01*
X916762Y777736D01*
X917069Y777839D01*
X917299Y778098D01*
X917529Y778563D01*
G01X920322Y776651D02*
Y779751D01*
X918904Y777529D01*
X920820D01*
G01X923357Y963087D02*
X920157D01*
G01X923357Y969287D02*
Y963087D01*
G01X920157D02*
Y969287D01*
G01X918574Y963087D02*
X915374D01*
G01X918574Y969287D02*
Y963087D01*
G01X915374D02*
Y969287D01*
G01X920157D02*
X923357D01*
G01X915374D02*
X918574D01*
G01X909589Y976734D02*
Y973534D01*
G01Y972834D02*
Y969634D01*
G01X918718Y980763D02*
Y978663D01*
G01D02*
X920818D01*
G01X909589Y994434D02*
Y991234D01*
G01Y990534D02*
Y987334D01*
G01X918718Y994805D02*
Y992705D01*
G01X920818Y994805D02*
X918718D01*
G01X920120Y1011462D02*
X923320D01*
G01X920120Y1005262D02*
Y1011462D01*
G01X923320Y1005262D02*
X920120D01*
G01X923320Y1011462D02*
Y1005262D01*
G01X913897Y1090951D02*
Y1094051D01*
G01X915507D02*
Y1090951D01*
G01Y1092501D02*
X913897D01*
G01X917150Y1091313D02*
X917419Y1091054D01*
X917725Y1090951D01*
X918032Y1091054D01*
X918300Y1091364D01*
X918492Y1091829D01*
X918569Y1092294D01*
Y1092863D01*
X918492Y1093328D01*
X918300Y1093741D01*
X918070Y1093948D01*
X917802Y1094051D01*
X917495Y1093948D01*
X917265Y1093741D01*
X917112Y1093431D01*
X917035Y1093018D01*
X917112Y1092656D01*
X917304Y1092294D01*
X917534Y1092088D01*
X917802Y1092036D01*
X918109Y1092139D01*
X918339Y1092398D01*
X918569Y1092863D01*
G01X920250Y1091313D02*
X920519Y1091054D01*
X920825Y1090951D01*
X921132Y1091054D01*
X921400Y1091364D01*
X921592Y1091829D01*
X921669Y1092294D01*
Y1092863D01*
X921592Y1093328D01*
X921400Y1093741D01*
X921170Y1093948D01*
X920902Y1094051D01*
X920595Y1093948D01*
X920365Y1093741D01*
X920212Y1093431D01*
X920135Y1093018D01*
X920212Y1092656D01*
X920404Y1092294D01*
X920634Y1092088D01*
X920902Y1092036D01*
X921209Y1092139D01*
X921439Y1092398D01*
X921669Y1092863D01*
G01X912207Y1406482D02*
Y1409582D01*
G01X913817D02*
Y1406482D01*
G01Y1408032D02*
X912207D01*
G01X915460Y1406844D02*
X915729Y1406585D01*
X916035Y1406482D01*
X916342Y1406585D01*
X916610Y1406895D01*
X916802Y1407360D01*
X916879Y1407825D01*
Y1408394D01*
X916802Y1408859D01*
X916610Y1409272D01*
X916380Y1409479D01*
X916112Y1409582D01*
X915805Y1409479D01*
X915575Y1409272D01*
X915422Y1408962D01*
X915345Y1408549D01*
X915422Y1408187D01*
X915614Y1407825D01*
X915844Y1407619D01*
X916112Y1407567D01*
X916419Y1407670D01*
X916649Y1407929D01*
X916879Y1408394D01*
G01X918369Y1406947D02*
X918599Y1406689D01*
X918867Y1406534D01*
X919212Y1406482D01*
X919557Y1406585D01*
X919825Y1406792D01*
X920017Y1407154D01*
X920055Y1407567D01*
X919979Y1407980D01*
X919787Y1408239D01*
X919519Y1408445D01*
X919250Y1408497D01*
X918982Y1408445D01*
X918637Y1408239D01*
X918752Y1409582D01*
X919787D01*
G01X917429Y1525849D02*
X914329D01*
Y1526769D01*
X914484Y1527076D01*
X914846Y1527306D01*
X915259Y1527383D01*
X915672Y1527306D01*
X915982Y1527114D01*
X916137Y1526769D01*
Y1525849D01*
G01X917429Y1528873D02*
X914329D01*
Y1529639D01*
X914484Y1529946D01*
X914691Y1530176D01*
X915001Y1530368D01*
X915362Y1530521D01*
X915879Y1530559D01*
X916396Y1530521D01*
X916757Y1530368D01*
X917067Y1530176D01*
X917274Y1529946D01*
X917429Y1529639D01*
Y1528873D01*
G01Y1532816D02*
X914329D01*
X914949Y1532356D01*
G01X917429D02*
Y1533276D01*
G01Y1535839D02*
X916757Y1535916D01*
X916189Y1536031D01*
X915672Y1536184D01*
X915104Y1536376D01*
X914329Y1536683D01*
Y1535149D01*
G01X939196Y1556610D02*
Y1528730D01*
X919196D01*
Y1556610D01*
X939196D01*
G01X934843Y205397D02*
Y151358D01*
G01X934547Y205397D02*
Y151752D01*
G01X934843Y151358D02*
X928462D01*
G01X934547Y151752D02*
X928867D01*
G01X934843Y212130D02*
Y207790D01*
G01X934547Y212130D02*
Y207790D01*
G01X934843Y219310D02*
Y214938D01*
G01X934547Y219310D02*
Y214938D01*
G01X934843Y226682D02*
Y222310D01*
G01X934547Y226682D02*
Y222310D01*
G01X934843Y246752D02*
Y229171D01*
G01X934547Y246358D02*
Y229171D01*
G01X928462Y246752D02*
X934843D01*
G01X928867Y246358D02*
X934547D01*
G01X926347Y472327D02*
Y466127D01*
G01D02*
X924260D01*
G01X924330Y472327D02*
X926347D01*
G01X939347Y466127D02*
X937530D01*
G01X939347Y472327D02*
Y466127D01*
G01X937270Y472327D02*
X939347D01*
G01X936147Y467500D02*
Y470360D01*
G01X932147Y472327D02*
X934000D01*
G01X932147Y466127D02*
Y472327D01*
G01X935347Y470360D02*
Y467500D01*
G01X933810Y466127D02*
X932147D01*
G01X937197Y487078D02*
Y488070D01*
G01X926610Y487078D02*
X927930D01*
G01X930370D02*
X931550D01*
G01X934260D02*
X937197D01*
G01Y490430D02*
Y499760D01*
G01Y502240D02*
Y503750D01*
G01Y506340D02*
Y507690D01*
G01Y510180D02*
Y511094D01*
G01D02*
X934090D01*
G01X932080D02*
X930460D01*
G01X927880D02*
X924540D01*
G01X928423Y963052D02*
X925223D01*
G01X928423Y969252D02*
Y963052D01*
G01X925223D02*
Y969252D01*
G01X929896Y963087D02*
Y969287D01*
G01X933096Y963087D02*
X929896D01*
G01X933096Y969287D02*
Y963087D01*
G01X925223Y969252D02*
X928423D01*
G01X929896Y969287D02*
X933096D01*
G01X937282Y973167D02*
Y975389D01*
X937129Y975854D01*
X936822Y976164D01*
X936439Y976267D01*
X936056Y976164D01*
X935749Y975854D01*
X935596Y975389D01*
Y973167D01*
G01X934067Y973684D02*
X933837Y973374D01*
X933569Y973219D01*
X933262Y973167D01*
X932879Y973270D01*
X932611Y973529D01*
X932534Y973839D01*
X932572Y974149D01*
X932726Y974407D01*
X933492Y974924D01*
X933837Y975285D01*
X934067Y975802D01*
X934144Y976267D01*
X932534D01*
G01X929779D02*
Y973167D01*
X931197Y975389D01*
X929281D01*
G01X927216Y976267D02*
X927139Y975595D01*
X927024Y975027D01*
X926871Y974510D01*
X926679Y973942D01*
X926372Y973167D01*
X927906D01*
G01X932760Y978663D02*
X934860D01*
G01D02*
Y980763D01*
G01Y994805D02*
X932760D01*
G01X934860Y992705D02*
Y994805D01*
G01X925620Y1011462D02*
X928820D01*
G01X925620Y1005262D02*
Y1011462D01*
G01X928820Y1005262D02*
X925620D01*
G01X928820Y1011462D02*
Y1005262D01*
G01X931552Y1583793D02*
Y1586993D01*
G01X937752Y1583793D02*
X931552D01*
G01X937752Y1586993D02*
Y1583793D01*
G01X931552Y1582993D02*
X937752D01*
G01X931552Y1579793D02*
Y1582993D01*
G01X937752Y1579793D02*
X931552D01*
G01X937752Y1582993D02*
Y1579793D01*
G01X924188Y1575414D02*
Y1595632D01*
G01X931552Y1586993D02*
X937752D01*
G01Y1594993D02*
Y1591793D01*
G01X931552Y1594993D02*
X937752D01*
G01X931552Y1591793D02*
Y1594993D01*
G01X937752Y1591793D02*
X931552D01*
G01Y1587793D02*
Y1590993D01*
G01X937752Y1587793D02*
X931552D01*
G01X937752Y1590993D02*
Y1587793D01*
G01X931552Y1590993D02*
X937752D01*
G01X955452Y167103D02*
X961452D01*
G01X955452Y155103D02*
Y167103D01*
G01X961452Y155103D02*
X955452D01*
G01X948015Y186512D02*
Y183312D01*
G01X941815D02*
Y186512D01*
G01X948015Y183312D02*
X941815D01*
G01X958627Y194297D02*
X955427D01*
G01Y200497D02*
X958627D01*
G01X955427Y194297D02*
Y200497D01*
G01X941735Y190452D02*
X947935D01*
G01D02*
Y187252D01*
G01X941735D02*
Y190452D01*
G01X947935Y187252D02*
X941735D01*
G01X941815Y186512D02*
X948015D01*
G01X941806Y281428D02*
Y284528D01*
G01X943416D02*
Y281428D01*
G01Y282978D02*
X941806D01*
G01X945711Y281428D02*
Y284528D01*
X945251Y283908D01*
G01Y281428D02*
X946171D01*
G01X948811D02*
Y284528D01*
X948351Y283908D01*
G01Y281428D02*
X949271D01*
G01X951068Y281893D02*
X951298Y281635D01*
X951566Y281480D01*
X951911Y281428D01*
X952256Y281531D01*
X952524Y281738D01*
X952716Y282100D01*
X952754Y282513D01*
X952678Y282926D01*
X952486Y283185D01*
X952218Y283391D01*
X951949Y283443D01*
X951681Y283391D01*
X951336Y283185D01*
X951451Y284528D01*
X952486D01*
G01X953159Y425898D02*
Y422698D01*
G01X946959Y425898D02*
X953159D01*
G01X946959Y422698D02*
Y425898D01*
G01X953159Y422698D02*
X946959D01*
G01X953082Y429724D02*
Y426524D01*
G01X946882D02*
Y429724D01*
G01X953082Y426524D02*
X946882D01*
G01X953055Y439444D02*
Y436244D01*
G01X946855Y439444D02*
X953055D01*
G01X946855Y436244D02*
Y439444D01*
G01X953055Y436244D02*
X946855D01*
G01X953132Y435618D02*
Y432418D01*
G01X946932Y435618D02*
X953132D01*
G01X946932Y432418D02*
Y435618D01*
G01X953132Y432418D02*
X946932D01*
G01X946882Y429724D02*
X953082D01*
G01X949698Y476015D02*
Y473793D01*
X949851Y473328D01*
X950158Y473018D01*
X950541Y472915D01*
X950924Y473018D01*
X951231Y473328D01*
X951384Y473793D01*
Y476015D01*
G01X952798Y473535D02*
X953028Y473173D01*
X953334Y472967D01*
X953679Y472915D01*
X953986Y472967D01*
X954293Y473225D01*
X954484Y473535D01*
X954523Y473845D01*
X954446Y474207D01*
X954178Y474465D01*
X953909Y474568D01*
X953564D01*
G01X953909D02*
X954139Y474723D01*
X954331Y474982D01*
X954408Y475292D01*
X954331Y475602D01*
X954139Y475860D01*
X953794Y476015D01*
X953449Y475963D01*
X953104Y475757D01*
G01X956741Y472915D02*
X957009Y472967D01*
X957316Y473122D01*
X957508Y473380D01*
X957584Y473742D01*
X957508Y474103D01*
X957278Y474413D01*
X956933Y474568D01*
X956549D01*
X956319Y474672D01*
X956128Y474930D01*
X956051Y475292D01*
X956166Y475653D01*
X956434Y475912D01*
X956741Y476015D01*
X957048Y475912D01*
X957316Y475653D01*
X957431Y475292D01*
X957354Y474930D01*
X957163Y474672D01*
X956933Y474568D01*
X956549D01*
X956204Y474413D01*
X955974Y474103D01*
X955898Y473742D01*
X955974Y473380D01*
X956166Y473122D01*
X956473Y472967D01*
X956741Y472915D01*
G01X940147Y472327D02*
X941470D01*
G01X940147Y466127D02*
Y472327D01*
G01X943347Y470230D02*
Y467710D01*
G01X941660Y466127D02*
X940147D01*
G01X947347D02*
X945380D01*
G01X947347Y472327D02*
Y466127D01*
G01X945570Y472327D02*
X947347D01*
G01X944147Y467710D02*
Y470230D01*
G01X953745Y485871D02*
X959945D01*
G01X953745Y484020D02*
Y485871D01*
G01X958690Y482671D02*
X955040D01*
G01X953720Y478662D02*
Y480490D01*
G01X959920Y478662D02*
X953720D01*
G01X955040Y481862D02*
X958690D01*
G01X953771Y542327D02*
X959971D01*
Y539127D01*
X953771D01*
Y542327D01*
G01X953772Y538406D02*
X959972D01*
Y535206D01*
X953772D01*
Y538406D01*
G01X962443Y973797D02*
X950327D01*
G01D02*
Y989049D01*
G01X948875Y981507D02*
Y975307D01*
G01D02*
X945675D01*
G01D02*
Y981507D01*
G01D02*
X948875D01*
G01X945350Y984752D02*
Y978552D01*
G01D02*
X942150D01*
G01D02*
Y984752D01*
G01X950327Y989049D02*
X962443D01*
G01X945748Y983977D02*
Y990177D01*
G01D02*
X948948D01*
G01D02*
Y983977D01*
G01D02*
X945748D01*
G01X942150Y984752D02*
X945350D01*
G01X950410Y999022D02*
Y995822D01*
G01X944210D02*
Y999022D01*
G01X950410Y995822D02*
X944210D01*
G01Y999022D02*
X950410D01*
G01X947313Y1536203D02*
Y1539303D01*
X948233D01*
X948540Y1539148D01*
X948770Y1538786D01*
X948847Y1538373D01*
X948770Y1537960D01*
X948578Y1537650D01*
X948233Y1537495D01*
X947313D01*
G01X950413Y1536203D02*
Y1539303D01*
X951333D01*
X951640Y1539148D01*
X951870Y1538786D01*
X951947Y1538373D01*
X951870Y1537960D01*
X951678Y1537650D01*
X951333Y1537495D01*
X950413D01*
G01X954280Y1536203D02*
X953973Y1536255D01*
X953705Y1536461D01*
X953475Y1536771D01*
X953322Y1537133D01*
X953245Y1537546D01*
Y1537960D01*
X953322Y1538373D01*
X953475Y1538735D01*
X953705Y1539045D01*
X953973Y1539251D01*
X954280Y1539303D01*
X954587Y1539251D01*
X954855Y1539045D01*
X955085Y1538735D01*
X955238Y1538373D01*
X955315Y1537960D01*
Y1537546D01*
X955238Y1537133D01*
X955085Y1536771D01*
X954855Y1536461D01*
X954587Y1536255D01*
X954280Y1536203D01*
G01X954587Y1537030D02*
X955047Y1536203D01*
G01X957380D02*
Y1539303D01*
X956920Y1538683D01*
G01Y1536203D02*
X957840D01*
G01X944304Y1560748D02*
X943471D01*
Y1579252D01*
X944104D01*
G01X949486Y1619684D02*
X977686D01*
Y1588284D01*
X949486D01*
Y1619684D01*
G01X955872Y1682410D02*
X941688D01*
G01X969475Y141476D02*
Y143716D01*
G01X967850Y142503D02*
X971100D01*
G01X963327Y145117D02*
Y174676D01*
G01X974823Y145117D02*
X963327D01*
G01X961452Y167103D02*
Y155103D01*
G01X969375Y178216D02*
Y175790D01*
G01X963327Y174676D02*
X974823D01*
G01X960173Y186409D02*
Y189509D01*
X961093D01*
X961400Y189354D01*
X961630Y188992D01*
X961707Y188579D01*
X961630Y188166D01*
X961438Y187856D01*
X961093Y187701D01*
X960173D01*
G01X963197Y186409D02*
Y189509D01*
X963963D01*
X964270Y189354D01*
X964500Y189147D01*
X964692Y188837D01*
X964845Y188476D01*
X964883Y187959D01*
X964845Y187442D01*
X964692Y187081D01*
X964500Y186771D01*
X964270Y186564D01*
X963963Y186409D01*
X963197D01*
G01X967140D02*
Y189509D01*
X966680Y188889D01*
G01Y186409D02*
X967600D01*
G01X970240D02*
Y189509D01*
X969780Y188889D01*
G01Y186409D02*
X970700D01*
G01X972612Y188992D02*
X972842Y189302D01*
X973110Y189457D01*
X973417Y189509D01*
X973800Y189406D01*
X974068Y189147D01*
X974145Y188837D01*
X974107Y188527D01*
X973953Y188269D01*
X973187Y187752D01*
X972842Y187391D01*
X972612Y186874D01*
X972535Y186409D01*
X974145D01*
G01X971483Y196969D02*
Y200069D01*
X972403D01*
X972710Y199914D01*
X972940Y199552D01*
X973017Y199139D01*
X972940Y198726D01*
X972748Y198416D01*
X972403Y198261D01*
X971483D01*
G01X974507Y200069D02*
Y197847D01*
X974660Y197382D01*
X974967Y197072D01*
X975350Y196969D01*
X975733Y197072D01*
X976040Y197382D01*
X976193Y197847D01*
Y200069D01*
G01X977722Y199552D02*
X977952Y199862D01*
X978220Y200017D01*
X978527Y200069D01*
X978910Y199966D01*
X979178Y199707D01*
X979255Y199397D01*
X979217Y199087D01*
X979063Y198829D01*
X978297Y198312D01*
X977952Y197951D01*
X977722Y197434D01*
X977645Y196969D01*
X979255D01*
G01X980898Y197331D02*
X981167Y197072D01*
X981473Y196969D01*
X981780Y197072D01*
X982048Y197382D01*
X982240Y197847D01*
X982317Y198312D01*
Y198881D01*
X982240Y199346D01*
X982048Y199759D01*
X981818Y199966D01*
X981550Y200069D01*
X981243Y199966D01*
X981013Y199759D01*
X980860Y199449D01*
X980783Y199036D01*
X980860Y198674D01*
X981052Y198312D01*
X981282Y198106D01*
X981550Y198054D01*
X981857Y198157D01*
X982087Y198416D01*
X982317Y198881D01*
G01X983922Y199552D02*
X984152Y199862D01*
X984420Y200017D01*
X984727Y200069D01*
X985110Y199966D01*
X985378Y199707D01*
X985455Y199397D01*
X985417Y199087D01*
X985263Y198829D01*
X984497Y198312D01*
X984152Y197951D01*
X983922Y197434D01*
X983845Y196969D01*
X985455D01*
G01X958627Y200497D02*
Y194297D01*
G01X962737Y194249D02*
X959537D01*
G01X962737Y200449D02*
Y194249D01*
G01X959537Y200449D02*
X962737D01*
G01X959537Y194249D02*
Y200449D01*
G01X966390Y214589D02*
X972390D01*
G01X966390Y202589D02*
Y214589D01*
G01X972390Y202589D02*
X966390D01*
G01X972390Y214589D02*
Y202589D01*
G01X982537Y353867D02*
Y341751D01*
X967285D01*
Y353867D01*
X982537D01*
G01X968493Y358496D02*
X974693D01*
G01X968493Y355296D02*
Y358496D01*
G01X974693Y355296D02*
X968493D01*
G01X959945Y485871D02*
Y484060D01*
G01X959920Y480710D02*
Y478662D01*
G01X958410Y966762D02*
Y968157D01*
X957643Y969862D01*
G01X959177D02*
X958410Y968157D01*
G01X960667Y967382D02*
X960897Y967020D01*
X961203Y966814D01*
X961548Y966762D01*
X961855Y966814D01*
X962162Y967072D01*
X962353Y967382D01*
X962392Y967692D01*
X962315Y968054D01*
X962047Y968312D01*
X961778Y968415D01*
X961433D01*
G01X961778D02*
X962008Y968570D01*
X962200Y968829D01*
X962277Y969139D01*
X962200Y969449D01*
X962008Y969707D01*
X961663Y969862D01*
X961318Y969810D01*
X960973Y969604D01*
G01X962443Y989049D02*
Y973797D01*
G01X956690Y995896D02*
Y999096D01*
G01X962890Y995896D02*
X956690D01*
G01X962890Y999096D02*
Y995896D01*
G01X956690Y999096D02*
X962890D01*
G01X971973Y1536237D02*
Y1539337D01*
X972893D01*
X973200Y1539182D01*
X973430Y1538820D01*
X973507Y1538407D01*
X973430Y1537994D01*
X973238Y1537684D01*
X972893Y1537529D01*
X971973D01*
G01X975073Y1536237D02*
Y1539337D01*
X975993D01*
X976300Y1539182D01*
X976530Y1538820D01*
X976607Y1538407D01*
X976530Y1537994D01*
X976338Y1537684D01*
X975993Y1537529D01*
X975073D01*
G01X978940Y1536237D02*
X978633Y1536289D01*
X978365Y1536495D01*
X978135Y1536805D01*
X977982Y1537167D01*
X977905Y1537580D01*
Y1537994D01*
X977982Y1538407D01*
X978135Y1538769D01*
X978365Y1539079D01*
X978633Y1539285D01*
X978940Y1539337D01*
X979247Y1539285D01*
X979515Y1539079D01*
X979745Y1538769D01*
X979898Y1538407D01*
X979975Y1537994D01*
Y1537580D01*
X979898Y1537167D01*
X979745Y1536805D01*
X979515Y1536495D01*
X979247Y1536289D01*
X978940Y1536237D01*
G01X979247Y1537064D02*
X979707Y1536237D01*
G01X981312Y1538820D02*
X981542Y1539130D01*
X981810Y1539285D01*
X982117Y1539337D01*
X982500Y1539234D01*
X982768Y1538975D01*
X982845Y1538665D01*
X982807Y1538355D01*
X982653Y1538097D01*
X981887Y1537580D01*
X981542Y1537219D01*
X981312Y1536702D01*
X981235Y1536237D01*
X982845D01*
G01X959879Y1553455D02*
X966079D01*
Y1550255D01*
X959879D01*
Y1553455D01*
G01X964337Y1579252D02*
Y1560748D01*
X963404D01*
G01X967670D02*
X966837D01*
Y1579252D01*
X967470D01*
G01X963704D02*
X964337D01*
G01X990872Y1682410D02*
X971688D01*
G01X982030Y-19800D02*
Y-3200D01*
X991630D01*
Y-19800D01*
X982030D01*
G01Y10200D02*
Y26800D01*
X991630D01*
Y10200D01*
X982030D01*
G01X982708Y160385D02*
Y148385D01*
G01D02*
X976708D01*
G01D02*
Y160385D01*
G01X974823Y174676D02*
Y145117D01*
G01X983900Y146699D02*
Y152899D01*
G01X987100Y146699D02*
X983900D01*
G01X987100Y152899D02*
Y146699D01*
G01X976708Y160385D02*
X982708D01*
G01X983900Y152899D02*
X987100D01*
G01X980024Y183747D02*
Y186947D01*
G01X986224Y183747D02*
X980024D01*
G01X986224Y186947D02*
Y183747D01*
G01X988005Y180153D02*
X991205D01*
G01X988005Y173953D02*
Y180153D01*
G01X991205Y173953D02*
X988005D01*
G01X983045Y173983D02*
X979845D01*
G01X983045Y180183D02*
Y173983D01*
G01X979845Y180183D02*
X983045D01*
G01X979845Y173983D02*
Y180183D01*
G01X983845D02*
X987045D01*
G01X983845Y173983D02*
Y180183D01*
G01X987045Y173983D02*
X983845D01*
G01X987045Y180183D02*
Y173983D01*
G01X980824Y173083D02*
X987024D01*
G01D02*
Y169883D01*
G01X980824D02*
Y173083D01*
G01X987024Y169883D02*
X980824D01*
G01X987870Y201319D02*
Y203819D01*
X987550Y203319D01*
G01Y201319D02*
X988190D01*
G01X989563Y203402D02*
X989723Y203652D01*
X989910Y203777D01*
X990123Y203819D01*
X990390Y203736D01*
X990577Y203527D01*
X990630Y203277D01*
X990603Y203027D01*
X990497Y202819D01*
X989963Y202402D01*
X989723Y202111D01*
X989563Y201694D01*
X989510Y201319D01*
X990630D01*
G01X987235Y192553D02*
X990435D01*
G01X987235Y186353D02*
Y192553D01*
G01X990435Y186353D02*
X987235D01*
G01X980024Y186947D02*
X986224D01*
G01X980085Y215433D02*
X984685D01*
G01X980085Y205233D02*
Y215433D01*
G01X984685Y205233D02*
X980085D01*
G01X984685Y215433D02*
Y205233D01*
G01X984985Y210333D02*
X989585D01*
G01X984985Y215433D02*
X989585D01*
G01Y205233D02*
X984985D01*
G01D02*
Y215433D01*
G01X986950Y218369D02*
Y220869D01*
X986630Y220369D01*
G01Y218369D02*
X987270D01*
G01X989150D02*
Y220869D01*
X988830Y220369D01*
G01Y218369D02*
X989470D01*
G01X975595Y208523D02*
X978795D01*
G01Y202323D02*
X975595D01*
G01X978795Y208523D02*
Y202323D01*
G01X975595D02*
Y208523D01*
G01X974667Y279688D02*
Y283096D01*
G01X992383Y279688D02*
X974667D01*
G01X979749Y274794D02*
Y277994D01*
G01X985949Y274794D02*
X979749D01*
G01X985949Y277994D02*
Y274794D01*
G01X979749Y277994D02*
X985949D01*
G01X974508Y298843D02*
Y301943D01*
X975428D01*
X975735Y301788D01*
X975965Y301426D01*
X976042Y301013D01*
X975965Y300600D01*
X975773Y300290D01*
X975428Y300135D01*
X974508D01*
G01X977608Y301943D02*
Y298843D01*
X979142D01*
G01X981475D02*
Y301943D01*
X981015Y301323D01*
G01Y298843D02*
X981935D01*
G01X984575D02*
Y301943D01*
X984115Y301323D01*
G01Y298843D02*
X985035D01*
G01X987675Y301943D02*
X987368Y301840D01*
X987138Y301581D01*
X986985Y301271D01*
X986870Y300858D01*
X986832Y300393D01*
X986870Y299928D01*
X986985Y299515D01*
X987138Y299205D01*
X987368Y298946D01*
X987675Y298843D01*
X987982Y298946D01*
X988212Y299205D01*
X988365Y299515D01*
X988480Y299928D01*
X988518Y300393D01*
X988480Y300858D01*
X988365Y301271D01*
X988212Y301581D01*
X987982Y301840D01*
X987675Y301943D01*
G01X974667Y297404D02*
X992383D01*
G01X974667Y293996D02*
Y297404D01*
G01X989233Y349203D02*
Y350598D01*
X988466Y352303D01*
G01X990000D02*
X989233Y350598D01*
G01X991605Y351786D02*
X991835Y352096D01*
X992103Y352251D01*
X992410Y352303D01*
X992793Y352200D01*
X993061Y351941D01*
X993138Y351631D01*
X993100Y351321D01*
X992946Y351063D01*
X992180Y350546D01*
X991835Y350185D01*
X991605Y349668D01*
X991528Y349203D01*
X993138D01*
G01X976194Y355310D02*
Y358510D01*
G01X982394Y355310D02*
X976194D01*
G01X982394Y358510D02*
Y355310D01*
G01X976194Y358510D02*
X982394D01*
G01X974693Y358496D02*
Y355296D01*
G01X983389Y359360D02*
X980189D01*
G01X983389Y365560D02*
Y359360D01*
G01X980189D02*
Y365560D01*
G01X984657Y362060D02*
Y365260D01*
G01X990857Y362060D02*
X984657D01*
G01X980189Y365560D02*
X983389D01*
G01X984657Y365260D02*
X990857D01*
G01X988739Y422856D02*
X985539D01*
G01X988739Y429056D02*
Y422856D01*
G01X985539D02*
Y429056D01*
G01D02*
X988739D01*
G01X1047736Y1420330D02*
G03I-31496J0D01*
G01X988829Y1494882D02*
Y1488882D01*
X982829D01*
G01Y1512504D02*
X988829D01*
Y1506504D01*
G01X983245Y1553455D02*
X989445D01*
Y1550255D01*
X983245D01*
Y1553455D01*
G01X987703Y1579252D02*
Y1560748D01*
X986770D01*
G01X987070Y1579252D02*
X987703D01*
G01X981098Y1619700D02*
X1009298D01*
Y1588300D01*
X981098D01*
Y1619700D01*
G01X1004380Y-15617D02*
X1004690Y-15425D01*
X1004897Y-15195D01*
X1005000Y-14927D01*
X1004897Y-14620D01*
X1004690Y-14390D01*
X1004380Y-14160D01*
X1003967Y-14083D01*
X1001900D01*
G01X1005000Y-11750D02*
X1004948Y-11482D01*
X1004793Y-11175D01*
X1004535Y-10983D01*
X1004173Y-10907D01*
X1003812Y-10983D01*
X1003502Y-11213D01*
X1003347Y-11558D01*
Y-11942D01*
X1003243Y-12172D01*
X1002985Y-12363D01*
X1002623Y-12440D01*
X1002262Y-12325D01*
X1002003Y-12057D01*
X1001900Y-11750D01*
X1002003Y-11443D01*
X1002262Y-11175D01*
X1002623Y-11060D01*
X1002985Y-11137D01*
X1003243Y-11328D01*
X1003347Y-11558D01*
Y-11942D01*
X1003502Y-12287D01*
X1003812Y-12517D01*
X1004173Y-12593D01*
X1004535Y-12517D01*
X1004793Y-12325D01*
X1004948Y-12018D01*
X1005000Y-11750D01*
G01X1004535Y-9493D02*
X1004793Y-9263D01*
X1004948Y-8995D01*
X1005000Y-8650D01*
X1004897Y-8305D01*
X1004690Y-8037D01*
X1004328Y-7845D01*
X1003915Y-7807D01*
X1003502Y-7883D01*
X1003243Y-8075D01*
X1003037Y-8343D01*
X1002985Y-8612D01*
X1003037Y-8880D01*
X1003243Y-9225D01*
X1001900Y-9110D01*
Y-8075D01*
G01X1004880Y14883D02*
X1005190Y15075D01*
X1005397Y15305D01*
X1005500Y15573D01*
X1005397Y15880D01*
X1005190Y16110D01*
X1004880Y16340D01*
X1004467Y16417D01*
X1002400D01*
G01X1004208Y18022D02*
X1003847Y18290D01*
X1003640Y18520D01*
X1003537Y18827D01*
X1003640Y19095D01*
X1003847Y19287D01*
X1004157Y19440D01*
X1004518Y19478D01*
X1004828Y19440D01*
X1005138Y19287D01*
X1005397Y19057D01*
X1005500Y18788D01*
X1005397Y18482D01*
X1005087Y18213D01*
X1004622Y18060D01*
X1004105Y18022D01*
X1003433Y18098D01*
X1003072Y18213D01*
X1002710Y18405D01*
X1002452Y18673D01*
X1002400Y18942D01*
X1002503Y19210D01*
X1002762Y19402D01*
G01X1005500Y21773D02*
X1004828Y21850D01*
X1004260Y21965D01*
X1003743Y22118D01*
X1003175Y22310D01*
X1002400Y22617D01*
Y21083D01*
G01X1004135Y152343D02*
Y158543D01*
G01X1007335Y152343D02*
X1004135D01*
G01X989900Y149899D02*
X996100D01*
G01X989900Y146699D02*
Y149899D01*
G01X996100Y146699D02*
X989900D01*
G01X996100Y149899D02*
Y146699D01*
G01X1003100Y149899D02*
Y146699D01*
G01X996900Y149899D02*
X1003100D01*
G01X996900Y146699D02*
Y149899D01*
G01X1003100Y146699D02*
X996900D01*
G01X1001101Y160692D02*
Y163792D01*
X1002021D01*
X1002328Y163637D01*
X1002558Y163275D01*
X1002635Y162862D01*
X1002558Y162449D01*
X1002366Y162139D01*
X1002021Y161984D01*
X1001101D01*
G01X1004125Y163792D02*
Y161570D01*
X1004278Y161105D01*
X1004585Y160795D01*
X1004968Y160692D01*
X1005351Y160795D01*
X1005658Y161105D01*
X1005811Y161570D01*
Y163792D01*
G01X1007340Y163275D02*
X1007570Y163585D01*
X1007838Y163740D01*
X1008145Y163792D01*
X1008528Y163689D01*
X1008796Y163430D01*
X1008873Y163120D01*
X1008835Y162810D01*
X1008681Y162552D01*
X1007915Y162035D01*
X1007570Y161674D01*
X1007340Y161157D01*
X1007263Y160692D01*
X1008873D01*
G01X1010516Y161054D02*
X1010785Y160795D01*
X1011091Y160692D01*
X1011398Y160795D01*
X1011666Y161105D01*
X1011858Y161570D01*
X1011935Y162035D01*
Y162604D01*
X1011858Y163069D01*
X1011666Y163482D01*
X1011436Y163689D01*
X1011168Y163792D01*
X1010861Y163689D01*
X1010631Y163482D01*
X1010478Y163172D01*
X1010401Y162759D01*
X1010478Y162397D01*
X1010670Y162035D01*
X1010900Y161829D01*
X1011168Y161777D01*
X1011475Y161880D01*
X1011705Y162139D01*
X1011935Y162604D01*
G01X1014728Y160692D02*
Y163792D01*
X1013310Y161570D01*
X1015226D01*
G01X999499Y168561D02*
X991311D01*
G01Y154585D02*
X999499D01*
G01X991311Y168561D02*
Y154585D01*
G01X999499D02*
Y168561D01*
G01X1004135Y158543D02*
X1007335D01*
G01X1007299Y165743D02*
X1004099D01*
G01D02*
Y171943D01*
G01X992603Y186272D02*
X992763Y186522D01*
X992950Y186647D01*
X993163Y186689D01*
X993430Y186606D01*
X993617Y186397D01*
X993670Y186147D01*
X993643Y185897D01*
X993537Y185689D01*
X993003Y185272D01*
X992763Y184981D01*
X992603Y184564D01*
X992550Y184189D01*
X993670D01*
G01X995310Y186689D02*
X995097Y186606D01*
X994937Y186397D01*
X994830Y186147D01*
X994750Y185814D01*
X994723Y185439D01*
X994750Y185064D01*
X994830Y184731D01*
X994937Y184481D01*
X995097Y184272D01*
X995310Y184189D01*
X995523Y184272D01*
X995683Y184481D01*
X995790Y184731D01*
X995870Y185064D01*
X995897Y185439D01*
X995870Y185814D01*
X995790Y186147D01*
X995683Y186397D01*
X995523Y186606D01*
X995310Y186689D01*
G01X1002493Y183072D02*
X1002653Y183322D01*
X1002840Y183447D01*
X1003053Y183489D01*
X1003320Y183406D01*
X1003507Y183197D01*
X1003560Y182947D01*
X1003533Y182697D01*
X1003427Y182489D01*
X1002893Y182072D01*
X1002653Y181781D01*
X1002493Y181364D01*
X1002440Y180989D01*
X1003560D01*
G01X1005200D02*
Y183489D01*
X1004880Y182989D01*
G01Y180989D02*
X1005520D01*
G01X1006600Y180156D02*
X1008200D01*
G01X1009093Y183072D02*
X1009253Y183322D01*
X1009440Y183447D01*
X1009653Y183489D01*
X1009920Y183406D01*
X1010107Y183197D01*
X1010160Y182947D01*
X1010133Y182697D01*
X1010027Y182489D01*
X1009493Y182072D01*
X1009253Y181781D01*
X1009093Y181364D01*
X1009040Y180989D01*
X1010160D01*
G01X1011293Y183072D02*
X1011453Y183322D01*
X1011640Y183447D01*
X1011853Y183489D01*
X1012120Y183406D01*
X1012307Y183197D01*
X1012360Y182947D01*
X1012333Y182697D01*
X1012227Y182489D01*
X1011693Y182072D01*
X1011453Y181781D01*
X1011293Y181364D01*
X1011240Y180989D01*
X1012360D01*
G01X1004099Y171943D02*
X1007299D01*
G01X991205Y180153D02*
Y173953D01*
G01X998015Y173473D02*
X994815D01*
G01X998015Y179673D02*
Y173473D01*
G01X994815Y179673D02*
X998015D01*
G01X994815Y173473D02*
Y179673D01*
G01X1001515Y173473D02*
X998315D01*
G01X1001515Y179673D02*
Y173473D01*
G01X998315Y179673D02*
X1001515D01*
G01X998315Y173473D02*
Y179673D01*
G01X993353Y188254D02*
X996494D01*
G01X1002416D02*
X1005557D01*
G01X993353Y189419D02*
Y188254D01*
G01X998505D02*
X1000405D01*
G01X990435Y192553D02*
Y186353D01*
G01X989585Y215433D02*
Y205233D01*
G01X1005557Y208332D02*
X1002423D01*
G01X1000423D02*
X998487D01*
G01X993353D02*
Y207167D01*
G01X996487Y208332D02*
X993353D01*
G01X992812Y215633D02*
Y218833D01*
G01X999012Y215633D02*
X992812D01*
G01X999012Y218833D02*
Y215633D01*
G01X999795Y212823D02*
Y219023D01*
G01X1002995Y212823D02*
X999795D01*
G01X1002995Y219023D02*
Y212823D01*
G01X1006995D02*
X1003795D01*
G01D02*
Y219023D01*
G01X999012Y214833D02*
Y211633D01*
G01X992812Y214833D02*
X999012D01*
G01X992812Y211633D02*
Y214833D01*
G01X999012Y211633D02*
X992812D01*
G01Y222833D02*
X999012D01*
G01X992812Y219633D02*
Y222833D01*
G01X999012Y219633D02*
X992812D01*
G01X999012Y222833D02*
Y219633D01*
G01X992812Y218833D02*
X999012D01*
G01X999795Y219023D02*
X1002995D01*
G01X1003795D02*
X1006995D01*
G01X1003582Y283324D02*
Y271324D01*
G01X997582D02*
Y283324D01*
G01X1003582Y271324D02*
X997582D01*
G01X992383Y283096D02*
Y279688D01*
G01X997582Y283324D02*
X1003582D01*
G01X992383Y297404D02*
Y293996D01*
G01X998051Y289260D02*
X1002178D01*
G01X995051Y292260D02*
X998051Y289260D01*
G01X995051Y310914D02*
Y292260D01*
G01X1002178Y310914D02*
X995051D01*
G01X990857Y365260D02*
Y362060D01*
G01X991923Y361555D02*
Y364755D01*
G01X998123Y361555D02*
X991923D01*
G01X998123Y364755D02*
Y361555D01*
G01X999210Y361752D02*
Y364952D01*
G01X1005410Y361752D02*
X999210D01*
G01X990877Y378281D02*
Y376233D01*
X992925D01*
G01X991923Y364755D02*
X998123D01*
G01X999210Y364952D02*
X1005410D01*
G01X992925Y407729D02*
X990877D01*
Y405681D01*
G01X992740Y422856D02*
X989540D01*
G01X992740Y429056D02*
Y422856D01*
G01X989540D02*
Y429056D01*
G01D02*
X992740D01*
G01X1003467Y1335007D02*
Y697211D01*
G01D02*
X1029057D01*
G01Y732644D02*
X1003467D01*
G01X1029057Y1299574D02*
X1003467D01*
G01X1002145Y1336996D02*
X1002337Y1336686D01*
X1002567Y1336479D01*
X1002835Y1336376D01*
X1003142Y1336479D01*
X1003372Y1336686D01*
X1003602Y1336996D01*
X1003679Y1337409D01*
Y1339476D01*
G01X1005935Y1336376D02*
X1006012Y1337048D01*
X1006127Y1337616D01*
X1006280Y1338133D01*
X1006472Y1338701D01*
X1006779Y1339476D01*
X1005245D01*
G01X1029057Y1335007D02*
X1003467D01*
G01X989325Y1449317D02*
Y1452417D01*
G01X990935D02*
Y1449317D01*
G01Y1450867D02*
X989325D01*
G01X993230Y1449317D02*
Y1452417D01*
X992770Y1451797D01*
G01Y1449317D02*
X993690D01*
G01X996330D02*
Y1452417D01*
X995870Y1451797D01*
G01Y1449317D02*
X996790D01*
G01X998587Y1449937D02*
X998817Y1449575D01*
X999123Y1449369D01*
X999468Y1449317D01*
X999775Y1449369D01*
X1000082Y1449627D01*
X1000273Y1449937D01*
X1000312Y1450247D01*
X1000235Y1450609D01*
X999967Y1450867D01*
X999698Y1450970D01*
X999353D01*
G01X999698D02*
X999928Y1451125D01*
X1000120Y1451384D01*
X1000197Y1451694D01*
X1000120Y1452004D01*
X999928Y1452262D01*
X999583Y1452417D01*
X999238Y1452365D01*
X998893Y1452159D01*
G01X993483Y1536141D02*
Y1539241D01*
X994403D01*
X994710Y1539086D01*
X994940Y1538724D01*
X995017Y1538311D01*
X994940Y1537898D01*
X994748Y1537588D01*
X994403Y1537433D01*
X993483D01*
G01X996583Y1536141D02*
Y1539241D01*
X997503D01*
X997810Y1539086D01*
X998040Y1538724D01*
X998117Y1538311D01*
X998040Y1537898D01*
X997848Y1537588D01*
X997503Y1537433D01*
X996583D01*
G01X1000450Y1536141D02*
X1000143Y1536193D01*
X999875Y1536399D01*
X999645Y1536709D01*
X999492Y1537071D01*
X999415Y1537484D01*
Y1537898D01*
X999492Y1538311D01*
X999645Y1538673D01*
X999875Y1538983D01*
X1000143Y1539189D01*
X1000450Y1539241D01*
X1000757Y1539189D01*
X1001025Y1538983D01*
X1001255Y1538673D01*
X1001408Y1538311D01*
X1001485Y1537898D01*
Y1537484D01*
X1001408Y1537071D01*
X1001255Y1536709D01*
X1001025Y1536399D01*
X1000757Y1536193D01*
X1000450Y1536141D01*
G01X1000757Y1536968D02*
X1001217Y1536141D01*
G01X1002707Y1536606D02*
X1002937Y1536348D01*
X1003205Y1536193D01*
X1003550Y1536141D01*
X1003895Y1536244D01*
X1004163Y1536451D01*
X1004355Y1536813D01*
X1004393Y1537226D01*
X1004317Y1537639D01*
X1004125Y1537898D01*
X1003857Y1538104D01*
X1003588Y1538156D01*
X1003320Y1538104D01*
X1002975Y1537898D01*
X1003090Y1539241D01*
X1004125D01*
G01X991036Y1560748D02*
X990203D01*
Y1579252D01*
X990836D01*
G01X994216Y2128230D02*
X997316D01*
X994733Y2127233D01*
X997316Y2126236D01*
X994216D01*
G01Y2123366D02*
Y2124900D01*
X997316D01*
Y2123366D01*
G01X995818Y2123980D02*
Y2124900D01*
G01X996799Y2121761D02*
X997109Y2121531D01*
X997264Y2121263D01*
X997316Y2120956D01*
X997213Y2120573D01*
X996954Y2120305D01*
X996644Y2120228D01*
X996334Y2120266D01*
X996076Y2120420D01*
X995559Y2121186D01*
X995198Y2121531D01*
X994681Y2121761D01*
X994216Y2121838D01*
Y2120228D01*
G01Y2118010D02*
X994888Y2117933D01*
X995456Y2117818D01*
X995973Y2117665D01*
X996541Y2117473D01*
X997316Y2117166D01*
Y2118700D01*
G01X1010880Y-25117D02*
X1011190Y-24925D01*
X1011397Y-24695D01*
X1011500Y-24427D01*
X1011397Y-24120D01*
X1011190Y-23890D01*
X1010880Y-23660D01*
X1010467Y-23583D01*
X1008400D01*
G01X1011500Y-21327D02*
X1010828Y-21250D01*
X1010260Y-21135D01*
X1009743Y-20982D01*
X1009175Y-20790D01*
X1008400Y-20483D01*
Y-22017D01*
G01X1011500Y-18150D02*
X1011448Y-17882D01*
X1011293Y-17575D01*
X1011035Y-17383D01*
X1010673Y-17307D01*
X1010312Y-17383D01*
X1010002Y-17613D01*
X1009847Y-17958D01*
Y-18342D01*
X1009743Y-18572D01*
X1009485Y-18763D01*
X1009123Y-18840D01*
X1008762Y-18725D01*
X1008503Y-18457D01*
X1008400Y-18150D01*
X1008503Y-17843D01*
X1008762Y-17575D01*
X1009123Y-17460D01*
X1009485Y-17537D01*
X1009743Y-17728D01*
X1009847Y-17958D01*
Y-18342D01*
X1010002Y-18687D01*
X1010312Y-18917D01*
X1010673Y-18993D01*
X1011035Y-18917D01*
X1011293Y-18725D01*
X1011448Y-18418D01*
X1011500Y-18150D01*
G01X1010880Y-4617D02*
X1011190Y-4425D01*
X1011397Y-4195D01*
X1011500Y-3927D01*
X1011397Y-3620D01*
X1011190Y-3390D01*
X1010880Y-3160D01*
X1010467Y-3083D01*
X1008400D01*
G01X1011500Y-827D02*
X1010828Y-750D01*
X1010260Y-635D01*
X1009743Y-482D01*
X1009175Y-290D01*
X1008400Y17D01*
Y-1517D01*
G01X1011500Y2273D02*
X1010828Y2350D01*
X1010260Y2465D01*
X1009743Y2618D01*
X1009175Y2810D01*
X1008400Y3117D01*
Y1583D01*
G01X1010880Y14883D02*
X1011190Y15075D01*
X1011397Y15305D01*
X1011500Y15573D01*
X1011397Y15880D01*
X1011190Y16110D01*
X1010880Y16340D01*
X1010467Y16417D01*
X1008400D01*
G01X1011500Y18673D02*
X1010828Y18750D01*
X1010260Y18865D01*
X1009743Y19018D01*
X1009175Y19210D01*
X1008400Y19517D01*
Y17983D01*
G01X1011035Y21007D02*
X1011293Y21237D01*
X1011448Y21505D01*
X1011500Y21850D01*
X1011397Y22195D01*
X1011190Y22463D01*
X1010828Y22655D01*
X1010415Y22693D01*
X1010002Y22617D01*
X1009743Y22425D01*
X1009537Y22157D01*
X1009485Y21888D01*
X1009537Y21620D01*
X1009743Y21275D01*
X1008400Y21390D01*
Y22425D01*
G01X1018547Y143655D02*
X1026421D01*
G01X1018547Y162873D02*
Y143655D01*
G01X1020784Y151014D02*
X1022284Y154014D01*
G01X1023784Y151014D02*
X1020784D01*
G01X1007335Y158543D02*
Y152343D01*
G01X1011335D02*
X1008135D01*
G01X1011335Y158543D02*
Y152343D01*
G01X1008135D02*
Y158543D01*
G01X1016875Y152349D02*
X1013675D01*
G01X1016875Y158549D02*
Y152349D01*
G01X1013675D02*
Y158549D01*
G01X1022484Y163701D02*
Y166127D01*
G01X1026421Y162873D02*
X1018547D01*
G01X1020784Y154014D02*
X1023784D01*
G01X1007299Y171943D02*
Y165743D01*
G01X1008135Y158543D02*
X1011335D01*
G01X1013675Y158549D02*
X1016875D01*
G01X1014476Y168878D02*
Y165678D01*
G01X1008276D02*
Y168878D01*
G01X1014476Y165678D02*
X1008276D01*
G01X1018233Y170299D02*
Y173399D01*
X1019153D01*
X1019460Y173244D01*
X1019690Y172882D01*
X1019767Y172469D01*
X1019690Y172056D01*
X1019498Y171746D01*
X1019153Y171591D01*
X1018233D01*
G01X1021257Y170299D02*
Y173399D01*
X1022023D01*
X1022330Y173244D01*
X1022560Y173037D01*
X1022752Y172727D01*
X1022905Y172366D01*
X1022943Y171849D01*
X1022905Y171332D01*
X1022752Y170971D01*
X1022560Y170661D01*
X1022330Y170454D01*
X1022023Y170299D01*
X1021257D01*
G01X1025200D02*
Y173399D01*
X1024740Y172779D01*
G01Y170299D02*
X1025660D01*
G01X1028300D02*
Y173399D01*
X1027840Y172779D01*
G01Y170299D02*
X1028760D01*
G01X1031860D02*
Y173399D01*
X1030442Y171177D01*
X1032358D01*
G01X1008276Y172878D02*
X1014476D01*
G01D02*
Y169678D01*
G01X1008276D02*
Y172878D01*
G01X1014476Y169678D02*
X1008276D01*
G01Y168878D02*
X1014476D01*
G01X1005557Y188254D02*
Y189427D01*
G01X1014127Y193514D02*
Y196714D01*
G01X1020327Y193514D02*
X1014127D01*
G01X1020327Y196714D02*
Y193514D01*
G01X1014127Y196714D02*
X1020327D01*
G01X1013490Y191776D02*
X1019690D01*
G01D02*
Y188576D01*
G01X1013490D02*
Y191776D01*
G01X1019690Y188576D02*
X1013490D01*
G01X1014120Y197476D02*
Y200676D01*
G01X1020320Y197476D02*
X1014120D01*
G01X1020320Y200676D02*
Y197476D01*
G01X1014120Y200676D02*
X1020320D01*
G01X1007740Y209009D02*
Y211509D01*
X1007420Y211009D01*
G01Y209009D02*
X1008060D01*
G01X1009940Y211509D02*
X1009727Y211426D01*
X1009567Y211217D01*
X1009460Y210967D01*
X1009380Y210634D01*
X1009353Y210259D01*
X1009380Y209884D01*
X1009460Y209551D01*
X1009567Y209301D01*
X1009727Y209092D01*
X1009940Y209009D01*
X1010153Y209092D01*
X1010313Y209301D01*
X1010420Y209551D01*
X1010500Y209884D01*
X1010527Y210259D01*
X1010500Y210634D01*
X1010420Y210967D01*
X1010313Y211217D01*
X1010153Y211426D01*
X1009940Y211509D01*
G01X1008617Y203281D02*
X1008803Y203072D01*
X1009017Y202989D01*
X1009230Y203072D01*
X1009417Y203322D01*
X1009550Y203697D01*
X1009603Y204072D01*
Y204531D01*
X1009550Y204906D01*
X1009417Y205239D01*
X1009257Y205406D01*
X1009070Y205489D01*
X1008857Y205406D01*
X1008697Y205239D01*
X1008590Y204989D01*
X1008537Y204656D01*
X1008590Y204364D01*
X1008723Y204072D01*
X1008883Y203906D01*
X1009070Y203864D01*
X1009283Y203947D01*
X1009443Y204156D01*
X1009603Y204531D01*
G01X1005557Y207167D02*
Y208332D01*
G01X1012095Y201823D02*
Y205023D01*
G01X1018295Y201823D02*
X1012095D01*
G01X1018295Y205023D02*
Y201823D01*
G01X1012095Y205023D02*
X1018295D01*
G01X1012095Y208823D02*
Y212023D01*
G01X1018295Y208823D02*
X1012095D01*
G01X1018295Y212023D02*
Y208823D01*
G01X1012095Y212023D02*
X1018295D01*
G01X1012095Y212823D02*
Y216023D01*
G01X1018295Y212823D02*
X1012095D01*
G01X1018295Y216023D02*
Y212823D01*
G01X1012095Y216023D02*
X1018295D01*
G01X1012095Y216823D02*
Y220023D01*
G01X1018295Y216823D02*
X1012095D01*
G01X1018295Y220023D02*
Y216823D01*
G01X1006995Y219023D02*
Y212823D01*
G01X1018295Y224823D02*
X1012095D01*
Y228023D01*
X1018295D01*
Y224823D01*
G01X1015170Y224898D02*
Y231098D01*
X1018370D01*
Y224898D01*
X1015170D01*
G01X1020263Y229594D02*
Y232694D01*
G01X1021873D02*
Y229594D01*
G01Y231144D02*
X1020263D01*
G01X1024168Y229594D02*
Y232694D01*
X1023708Y232074D01*
G01Y229594D02*
X1024628D01*
G01X1027268D02*
Y232694D01*
X1026808Y232074D01*
G01Y229594D02*
X1027728D01*
G01X1030368D02*
Y232694D01*
X1029908Y232074D01*
G01Y229594D02*
X1030828D01*
G01X1012095Y220023D02*
X1018295D01*
G01X1012095Y224023D02*
X1018295D01*
G01X1012095Y220823D02*
Y224023D01*
G01X1018295Y220823D02*
X1012095D01*
G01X1018295Y224023D02*
Y220823D01*
G01X1019175Y283190D02*
Y271190D01*
G01X1013175D02*
Y283190D01*
G01X1019175Y271190D02*
X1013175D01*
G01X1011445Y283190D02*
Y271190D01*
G01X1005445D02*
Y283190D01*
G01X1011445Y271190D02*
X1005445D01*
G01X1013175Y283190D02*
X1019175D01*
G01X1005445D02*
X1011445D01*
G01X1016705Y292260D02*
Y310914D01*
G01X1013705Y289260D02*
X1016705Y292260D01*
G01X1009578Y289260D02*
X1013705D01*
G01X1018339Y295813D02*
Y302013D01*
G01X1021539Y295813D02*
X1018339D01*
G01X1016705Y310914D02*
X1009578D01*
G01X1018339Y302013D02*
X1021539D01*
G01X1005410Y364952D02*
Y361752D01*
G01X1006638Y361756D02*
Y364956D01*
G01X1012838Y361756D02*
X1006638D01*
G01X1012838Y364956D02*
Y361756D01*
G01X1019570Y364822D02*
Y361622D01*
G01X1013370D02*
Y364822D01*
G01X1019570Y361622D02*
X1013370D01*
G01X1020325Y376233D02*
X1022373D01*
Y378281D01*
G01X1006638Y364956D02*
X1012838D01*
G01X1013370Y364822D02*
X1019570D01*
G01X1022373Y407729D02*
X1020325D01*
G01X1019658Y425248D02*
Y423026D01*
X1019811Y422561D01*
X1020118Y422251D01*
X1020501Y422148D01*
X1020884Y422251D01*
X1021191Y422561D01*
X1021344Y423026D01*
Y425248D01*
G01X1023601Y422148D02*
Y425248D01*
X1023141Y424628D01*
G01Y422148D02*
X1024061D01*
G01X1025858Y422768D02*
X1026088Y422406D01*
X1026394Y422200D01*
X1026739Y422148D01*
X1027046Y422200D01*
X1027353Y422458D01*
X1027544Y422768D01*
X1027583Y423078D01*
X1027506Y423440D01*
X1027238Y423698D01*
X1026969Y423801D01*
X1026624D01*
G01X1026969D02*
X1027199Y423956D01*
X1027391Y424215D01*
X1027468Y424525D01*
X1027391Y424835D01*
X1027199Y425093D01*
X1026854Y425248D01*
X1026509Y425196D01*
X1026164Y424990D01*
G01X1018106Y422704D02*
X1014906D01*
G01X1018106Y428904D02*
Y422704D01*
G01X1014906Y428904D02*
X1018106D01*
G01X1014906Y422704D02*
Y428904D01*
G01X1014106Y422704D02*
X1010906D01*
G01X1014106Y428904D02*
Y422704D01*
G01X1010906Y428904D02*
X1014106D01*
G01X1010906Y422704D02*
Y428904D01*
G01X1016669Y516128D02*
Y519328D01*
G01X1022869Y516128D02*
X1016669D01*
G01Y519328D02*
X1022869D01*
G01X1016669Y510974D02*
Y514174D01*
G01X1022869Y510974D02*
X1016669D01*
G01Y514174D02*
X1022869D01*
G01X1016753Y1536695D02*
Y1539795D01*
X1017673D01*
X1017980Y1539640D01*
X1018210Y1539278D01*
X1018287Y1538865D01*
X1018210Y1538452D01*
X1018018Y1538142D01*
X1017673Y1537987D01*
X1016753D01*
G01X1019853Y1536695D02*
Y1539795D01*
X1020773D01*
X1021080Y1539640D01*
X1021310Y1539278D01*
X1021387Y1538865D01*
X1021310Y1538452D01*
X1021118Y1538142D01*
X1020773Y1537987D01*
X1019853D01*
G01X1023720Y1536695D02*
X1023413Y1536747D01*
X1023145Y1536953D01*
X1022915Y1537263D01*
X1022762Y1537625D01*
X1022685Y1538038D01*
Y1538452D01*
X1022762Y1538865D01*
X1022915Y1539227D01*
X1023145Y1539537D01*
X1023413Y1539743D01*
X1023720Y1539795D01*
X1024027Y1539743D01*
X1024295Y1539537D01*
X1024525Y1539227D01*
X1024678Y1538865D01*
X1024755Y1538452D01*
Y1538038D01*
X1024678Y1537625D01*
X1024525Y1537263D01*
X1024295Y1536953D01*
X1024027Y1536747D01*
X1023720Y1536695D01*
G01X1024027Y1537522D02*
X1024487Y1536695D01*
G01X1026092Y1537987D02*
X1026360Y1538348D01*
X1026590Y1538555D01*
X1026897Y1538658D01*
X1027165Y1538555D01*
X1027357Y1538348D01*
X1027510Y1538038D01*
X1027548Y1537677D01*
X1027510Y1537367D01*
X1027357Y1537057D01*
X1027127Y1536798D01*
X1026858Y1536695D01*
X1026552Y1536798D01*
X1026283Y1537108D01*
X1026130Y1537573D01*
X1026092Y1538090D01*
X1026168Y1538762D01*
X1026283Y1539123D01*
X1026475Y1539485D01*
X1026743Y1539743D01*
X1027012Y1539795D01*
X1027280Y1539692D01*
X1027472Y1539433D01*
G01X1006611Y1553455D02*
X1012811D01*
Y1550255D01*
X1006611D01*
Y1553455D01*
G01X1011069Y1579252D02*
Y1560748D01*
X1010136D01*
G01X1014402D02*
X1013569D01*
Y1579252D01*
X1014202D01*
G01X1010436D02*
X1011069D01*
G01X1012698Y1619700D02*
X1040898D01*
Y1588300D01*
X1012698D01*
Y1619700D01*
G01X1025872Y1682410D02*
X1006688D01*
G01X1031302Y-13211D02*
Y-29811D01*
X1021702D01*
Y-13211D01*
X1031302D01*
G01Y6789D02*
Y-9811D01*
X1021702D01*
Y6789D01*
X1031302D01*
G01Y26789D02*
Y10189D01*
X1021702D01*
Y26789D01*
X1031302D01*
G01X1028450Y108562D02*
Y111662D01*
G01X1030060D02*
Y108562D01*
G01Y110112D02*
X1028450D01*
G01X1032355Y108562D02*
Y111662D01*
X1031895Y111042D01*
G01Y108562D02*
X1032815D01*
G01X1035455Y111662D02*
X1035148Y111559D01*
X1034918Y111300D01*
X1034765Y110990D01*
X1034650Y110577D01*
X1034612Y110112D01*
X1034650Y109647D01*
X1034765Y109234D01*
X1034918Y108924D01*
X1035148Y108665D01*
X1035455Y108562D01*
X1035762Y108665D01*
X1035992Y108924D01*
X1036145Y109234D01*
X1036260Y109647D01*
X1036298Y110112D01*
X1036260Y110577D01*
X1036145Y110990D01*
X1035992Y111300D01*
X1035762Y111559D01*
X1035455Y111662D01*
G01X1037827Y111145D02*
X1038057Y111455D01*
X1038325Y111610D01*
X1038632Y111662D01*
X1039015Y111559D01*
X1039283Y111300D01*
X1039360Y110990D01*
X1039322Y110680D01*
X1039168Y110422D01*
X1038402Y109905D01*
X1038057Y109544D01*
X1037827Y109027D01*
X1037750Y108562D01*
X1039360D01*
G01X1033592Y142377D02*
X1033822Y142015D01*
X1034128Y141809D01*
X1034473Y141757D01*
X1034780Y141809D01*
X1035087Y142067D01*
X1035278Y142377D01*
X1035317Y142687D01*
X1035240Y143049D01*
X1034972Y143307D01*
X1034703Y143410D01*
X1034358D01*
G01X1034703D02*
X1034933Y143565D01*
X1035125Y143824D01*
X1035202Y144134D01*
X1035125Y144444D01*
X1034933Y144702D01*
X1034588Y144857D01*
X1034243Y144805D01*
X1033898Y144599D01*
G01X1036514Y138160D02*
Y168554D01*
G01X1046356Y138160D02*
X1036514D01*
G01X1029230Y139172D02*
Y141412D01*
G01X1027605Y140199D02*
X1030855D01*
G01X1026421Y143655D02*
Y162873D01*
G01X1022284Y151014D02*
Y149914D01*
G01Y154014D02*
X1023784Y151014D01*
G01X1036514Y168554D02*
X1046356D01*
G01X1022284Y154014D02*
Y155014D01*
G01X1036268Y170494D02*
X1036460Y170184D01*
X1036690Y169977D01*
X1036958Y169874D01*
X1037265Y169977D01*
X1037495Y170184D01*
X1037725Y170494D01*
X1037802Y170907D01*
Y172974D01*
G01X1039368Y169874D02*
Y172974D01*
X1040288D01*
X1040595Y172819D01*
X1040825Y172457D01*
X1040902Y172044D01*
X1040825Y171631D01*
X1040633Y171321D01*
X1040288Y171166D01*
X1039368D01*
G01X1043695Y169874D02*
Y172974D01*
X1042277Y170752D01*
X1044193D01*
G01X1089154Y204724D02*
G03I-31496J0D01*
G01X1024820Y180499D02*
X1021620D01*
G01X1024820Y186699D02*
Y180499D01*
G01X1021620D02*
Y186699D01*
G01D02*
X1024820D01*
G01X1032733Y262530D02*
Y265730D01*
G01X1038933Y262530D02*
X1032733D01*
G01Y265730D02*
X1038933D01*
G01X1032733Y269864D02*
X1038933D01*
G01X1032733Y266664D02*
Y269864D01*
G01X1038933Y266664D02*
X1032733D01*
G01X1022262Y281264D02*
Y275162D01*
X1022733D01*
G01X1036435Y294610D02*
X1033235D01*
G01X1036435Y300810D02*
Y294610D01*
G01X1033235D02*
Y300810D01*
G01X1032625Y294610D02*
X1029425D01*
G01X1032625Y300810D02*
Y294610D01*
G01X1029425D02*
Y300810D01*
G01X1040206Y294610D02*
X1037006D01*
G01D02*
Y300810D01*
G01X1021539Y302013D02*
Y295813D01*
G01X1022733Y295664D02*
Y298864D01*
G01X1028933Y295664D02*
X1022733D01*
G01X1028933Y298864D02*
Y295664D01*
G01X1022733Y298864D02*
X1028933D01*
G01X1022533Y287366D02*
X1022262D01*
G01D02*
Y283564D01*
G01X1029670Y308162D02*
X1032870D01*
G01X1029670Y301962D02*
Y308162D01*
G01X1032870Y301962D02*
X1029670D01*
G01X1032870Y308162D02*
Y301962D01*
G01X1033235Y300810D02*
X1036435D01*
G01X1029425D02*
X1032625D01*
G01X1022733Y303713D02*
Y306913D01*
G01X1028933Y303713D02*
X1022733D01*
G01X1028933Y306913D02*
Y303713D01*
G01X1022733Y306913D02*
X1028933D01*
G01X1037006Y300810D02*
X1040206D01*
G01X1022733Y299713D02*
Y302913D01*
G01X1028933Y299713D02*
X1022733D01*
G01X1028933Y302913D02*
Y299713D01*
G01X1022733Y302913D02*
X1028933D01*
G01X1027558Y361064D02*
X1024358D01*
G01X1027558Y367264D02*
Y361064D01*
G01X1024358D02*
Y367264D01*
G01X1031522Y361069D02*
X1028322D01*
G01X1031522Y367269D02*
Y361069D01*
G01X1028322D02*
Y367269D01*
G01X1037569Y375877D02*
Y371277D01*
G01X1032469D02*
Y375877D01*
G01X1042669Y371277D02*
X1032469D01*
G01Y375877D02*
X1042669D01*
G01X1032369Y365644D02*
Y370244D01*
G01X1042569Y365644D02*
X1032369D01*
G01Y370244D02*
X1042569D01*
G01X1024358Y367264D02*
X1027558D01*
G01X1028322Y367269D02*
X1031522D01*
G01X1022373Y405681D02*
Y407729D01*
G01X1036769Y508006D02*
Y511206D01*
G01X1042969Y508006D02*
X1036769D01*
G01X1031668Y506902D02*
X1034868D01*
G01X1031668Y500702D02*
Y506902D01*
G01X1034868Y500702D02*
X1031668D01*
G01X1034868Y506902D02*
Y500702D01*
G01X1036769Y511206D02*
X1042969D01*
G01X1022869Y519328D02*
Y516128D01*
G01Y514174D02*
Y510974D01*
G01X1032378Y525228D02*
Y522028D01*
G01X1026178Y525228D02*
X1032378D01*
G01X1026178Y522028D02*
Y525228D01*
G01X1032378Y522028D02*
X1026178D01*
G01X1032378Y515776D02*
Y512576D01*
G01X1026178Y515776D02*
X1032378D01*
G01X1026178Y512576D02*
Y515776D01*
G01X1032378Y512576D02*
X1026178D01*
G01X1034510Y525242D02*
X1040710D01*
G01X1034510Y522042D02*
Y525242D01*
G01X1040710Y522042D02*
X1034510D01*
G01X1034930Y515782D02*
X1041130D01*
G01X1034930Y512582D02*
Y515782D01*
G01X1041130Y512582D02*
X1034930D01*
G01X1033167Y710212D02*
Y697211D01*
G01D02*
X1058757D01*
G01X1029057D02*
Y1335007D01*
G01X1033167D02*
Y732482D01*
G01X1058757Y732644D02*
X1033167D01*
G01X1058757Y1299574D02*
X1033167D01*
G01X1031845Y1336996D02*
X1032037Y1336686D01*
X1032267Y1336479D01*
X1032535Y1336376D01*
X1032842Y1336479D01*
X1033072Y1336686D01*
X1033302Y1336996D01*
X1033379Y1337409D01*
Y1339476D01*
G01X1035712Y1336376D02*
X1035980Y1336428D01*
X1036287Y1336583D01*
X1036479Y1336841D01*
X1036555Y1337203D01*
X1036479Y1337564D01*
X1036249Y1337874D01*
X1035904Y1338029D01*
X1035520D01*
X1035290Y1338133D01*
X1035099Y1338391D01*
X1035022Y1338753D01*
X1035137Y1339114D01*
X1035405Y1339373D01*
X1035712Y1339476D01*
X1036019Y1339373D01*
X1036287Y1339114D01*
X1036402Y1338753D01*
X1036325Y1338391D01*
X1036134Y1338133D01*
X1035904Y1338029D01*
X1035520D01*
X1035175Y1337874D01*
X1034945Y1337564D01*
X1034869Y1337203D01*
X1034945Y1336841D01*
X1035137Y1336583D01*
X1035444Y1336428D01*
X1035712Y1336376D01*
G01X1058757Y1335007D02*
X1033167D01*
G01X1022900Y1351862D02*
Y1361562D01*
G01Y1350462D02*
Y1351862D01*
G01Y1350462D02*
X1096500D01*
Y1351862D01*
G01X1034225Y1366935D02*
X1033910Y1366465D01*
X1033700Y1365917D01*
Y1365290D01*
X1034015Y1364585D01*
X1034540Y1364037D01*
X1035170Y1363645D01*
X1036220Y1363332D01*
X1037165Y1363254D01*
X1038110Y1363410D01*
X1038740Y1363645D01*
X1039370Y1364115D01*
X1039790Y1364664D01*
X1040000Y1365212D01*
Y1365760D01*
X1039790Y1366309D01*
X1039475Y1366779D01*
X1039055Y1367170D01*
G01X1038740Y1369789D02*
X1039475Y1370259D01*
X1039895Y1370885D01*
X1040000Y1371590D01*
X1039895Y1372217D01*
X1039370Y1372844D01*
X1038740Y1373235D01*
X1038110Y1373314D01*
X1037375Y1373157D01*
X1036850Y1372609D01*
X1036640Y1372060D01*
Y1371355D01*
G01Y1372060D02*
X1036325Y1372530D01*
X1035800Y1372922D01*
X1035170Y1373079D01*
X1034540Y1372922D01*
X1034015Y1372530D01*
X1033700Y1371825D01*
X1033805Y1371120D01*
X1034225Y1370415D01*
G01X1030500Y1363254D02*
X1024200Y1365212D01*
X1030500Y1367170D01*
G01X1028295Y1366465D02*
Y1363959D01*
G01X1029240Y1369789D02*
X1029975Y1370259D01*
X1030395Y1370885D01*
X1030500Y1371590D01*
X1030395Y1372217D01*
X1029870Y1372844D01*
X1029240Y1373235D01*
X1028610Y1373314D01*
X1027875Y1373157D01*
X1027350Y1372609D01*
X1027140Y1372060D01*
Y1371355D01*
G01Y1372060D02*
X1026825Y1372530D01*
X1026300Y1372922D01*
X1025670Y1373079D01*
X1025040Y1372922D01*
X1024515Y1372530D01*
X1024200Y1371825D01*
X1024305Y1371120D01*
X1024725Y1370415D01*
G01X1022900Y1375062D02*
X1032100D01*
Y1361562D01*
X1022900D01*
Y1375062D01*
G01X1041300Y1361562D02*
X1032100D01*
G01Y1375062D02*
X1041300D01*
G01X1029977Y1553455D02*
X1036177D01*
Y1550255D01*
X1029977D01*
Y1553455D01*
G01X1034435Y1579252D02*
Y1560748D01*
X1033502D01*
G01X1037768D02*
X1036935D01*
Y1579252D01*
X1037568D01*
G01X1033802D02*
X1034435D01*
G01X1046356Y168554D02*
Y138160D01*
G01X1048382Y142151D02*
X1048612Y141789D01*
X1048918Y141583D01*
X1049263Y141531D01*
X1049570Y141583D01*
X1049877Y141841D01*
X1050068Y142151D01*
X1050107Y142461D01*
X1050030Y142823D01*
X1049762Y143081D01*
X1049493Y143184D01*
X1049148D01*
G01X1049493D02*
X1049723Y143339D01*
X1049915Y143598D01*
X1049992Y143908D01*
X1049915Y144218D01*
X1049723Y144476D01*
X1049378Y144631D01*
X1049033Y144579D01*
X1048688Y144373D01*
G01X1051304Y137934D02*
Y168328D01*
G01X1061146Y137934D02*
X1051304D01*
G01X1051058Y170268D02*
X1051250Y169958D01*
X1051480Y169751D01*
X1051748Y169648D01*
X1052055Y169751D01*
X1052285Y169958D01*
X1052515Y170268D01*
X1052592Y170681D01*
Y172748D01*
G01X1054158Y169648D02*
Y172748D01*
X1055078D01*
X1055385Y172593D01*
X1055615Y172231D01*
X1055692Y171818D01*
X1055615Y171405D01*
X1055423Y171095D01*
X1055078Y170940D01*
X1054158D01*
G01X1057373Y170010D02*
X1057642Y169751D01*
X1057948Y169648D01*
X1058255Y169751D01*
X1058523Y170061D01*
X1058715Y170526D01*
X1058792Y170991D01*
Y171560D01*
X1058715Y172025D01*
X1058523Y172438D01*
X1058293Y172645D01*
X1058025Y172748D01*
X1057718Y172645D01*
X1057488Y172438D01*
X1057335Y172128D01*
X1057258Y171715D01*
X1057335Y171353D01*
X1057527Y170991D01*
X1057757Y170785D01*
X1058025Y170733D01*
X1058332Y170836D01*
X1058562Y171095D01*
X1058792Y171560D01*
G01X1051304Y168328D02*
X1061146D01*
G01X1043783Y254342D02*
X1041357D01*
G01X1050291Y245306D02*
Y262236D01*
G01X1086031Y245306D02*
X1050291D01*
G01Y262236D02*
X1086031D01*
G01X1038933Y265730D02*
Y262530D01*
G01X1048920Y268802D02*
Y274750D01*
G01X1086716Y268802D02*
X1048920D01*
G01X1038933Y269864D02*
Y266664D01*
G01X1045024Y281398D02*
X1041824D01*
G01X1045024Y287598D02*
Y281398D01*
G01X1041824D02*
Y287598D01*
G01X1040248Y278165D02*
X1043348D01*
Y277245D01*
X1043193Y276938D01*
X1042831Y276708D01*
X1042418Y276631D01*
X1042005Y276708D01*
X1041695Y276900D01*
X1041540Y277245D01*
Y278165D01*
G01X1043348Y275141D02*
X1041126D01*
X1040661Y274988D01*
X1040351Y274681D01*
X1040248Y274298D01*
X1040351Y273915D01*
X1040661Y273608D01*
X1041126Y273455D01*
X1043348D01*
G01X1040248Y271275D02*
X1040920Y271198D01*
X1041488Y271083D01*
X1042005Y270930D01*
X1042573Y270738D01*
X1043348Y270431D01*
Y271965D01*
G01X1040868Y268941D02*
X1040506Y268711D01*
X1040300Y268405D01*
X1040248Y268060D01*
X1040300Y267753D01*
X1040558Y267446D01*
X1040868Y267255D01*
X1041178Y267216D01*
X1041540Y267293D01*
X1041798Y267561D01*
X1041901Y267830D01*
Y268175D01*
G01Y267830D02*
X1042056Y267600D01*
X1042315Y267408D01*
X1042625Y267331D01*
X1042935Y267408D01*
X1043193Y267600D01*
X1043348Y267945D01*
X1043296Y268290D01*
X1043090Y268635D01*
G01X1038133Y275162D02*
X1038404D01*
Y278964D01*
G01X1049303Y295998D02*
Y299098D01*
X1050223D01*
X1050530Y298943D01*
X1050760Y298581D01*
X1050837Y298168D01*
X1050760Y297755D01*
X1050568Y297445D01*
X1050223Y297290D01*
X1049303D01*
G01X1052403Y299098D02*
Y295998D01*
X1053937D01*
G01X1056270D02*
Y299098D01*
X1055810Y298478D01*
G01Y295998D02*
X1056730D01*
G01X1058527Y296463D02*
X1058757Y296205D01*
X1059025Y296050D01*
X1059370Y295998D01*
X1059715Y296101D01*
X1059983Y296308D01*
X1060175Y296670D01*
X1060213Y297083D01*
X1060137Y297496D01*
X1059945Y297755D01*
X1059677Y297961D01*
X1059408Y298013D01*
X1059140Y297961D01*
X1058795Y297755D01*
X1058910Y299098D01*
X1059945D01*
G01X1062470D02*
X1062163Y298995D01*
X1061933Y298736D01*
X1061780Y298426D01*
X1061665Y298013D01*
X1061627Y297548D01*
X1061665Y297083D01*
X1061780Y296670D01*
X1061933Y296360D01*
X1062163Y296101D01*
X1062470Y295998D01*
X1062777Y296101D01*
X1063007Y296360D01*
X1063160Y296670D01*
X1063275Y297083D01*
X1063313Y297548D01*
X1063275Y298013D01*
X1063160Y298426D01*
X1063007Y298736D01*
X1062777Y298995D01*
X1062470Y299098D01*
G01X1048920Y293998D02*
X1086716D01*
G01X1048920Y288050D02*
Y293998D01*
G01X1041824Y287598D02*
X1045024D01*
G01X1039427Y289505D02*
Y292705D01*
G01X1045627Y289505D02*
X1039427D01*
G01X1045627Y292705D02*
Y289505D01*
G01X1039427Y292705D02*
X1045627D01*
G01X1040206Y300810D02*
Y294610D01*
G01X1038404Y283564D02*
Y287366D01*
X1038133D01*
G01X1051105Y361595D02*
Y367795D01*
G01X1054305Y361595D02*
X1051105D01*
G01X1042669Y375877D02*
Y371277D01*
G01X1045071Y370837D02*
X1049671D01*
G01Y365737D02*
X1045071D01*
G01X1049671Y375937D02*
Y365737D01*
G01X1045071Y375937D02*
X1049671D01*
G01X1045071Y365737D02*
Y375937D01*
G01X1042569Y370244D02*
Y365644D01*
G01X1051105Y367795D02*
X1054305D01*
G01X1051987Y507822D02*
Y520026D01*
G01X1054749Y507822D02*
X1051987D01*
G01X1042969Y511206D02*
Y508006D01*
G01X1040888Y500561D02*
Y503761D01*
G01X1047088Y500561D02*
X1040888D01*
G01X1047088Y503761D02*
Y500561D01*
G01X1040888Y503761D02*
X1047088D01*
G01X1053598Y526227D02*
Y524005D01*
X1053751Y523540D01*
X1054058Y523230D01*
X1054441Y523127D01*
X1054824Y523230D01*
X1055131Y523540D01*
X1055284Y524005D01*
Y526227D01*
G01X1056698Y523747D02*
X1056928Y523385D01*
X1057234Y523179D01*
X1057579Y523127D01*
X1057886Y523179D01*
X1058193Y523437D01*
X1058384Y523747D01*
X1058423Y524057D01*
X1058346Y524419D01*
X1058078Y524677D01*
X1057809Y524780D01*
X1057464D01*
G01X1057809D02*
X1058039Y524935D01*
X1058231Y525194D01*
X1058308Y525504D01*
X1058231Y525814D01*
X1058039Y526072D01*
X1057694Y526227D01*
X1057349Y526175D01*
X1057004Y525969D01*
G01X1060641Y523127D02*
Y526227D01*
X1060181Y525607D01*
G01Y523127D02*
X1061101D01*
G01X1062898Y523592D02*
X1063128Y523334D01*
X1063396Y523179D01*
X1063741Y523127D01*
X1064086Y523230D01*
X1064354Y523437D01*
X1064546Y523799D01*
X1064584Y524212D01*
X1064508Y524625D01*
X1064316Y524884D01*
X1064048Y525090D01*
X1063779Y525142D01*
X1063511Y525090D01*
X1063166Y524884D01*
X1063281Y526227D01*
X1064316D01*
G01X1051987Y520026D02*
X1063511D01*
G01X1040710Y525242D02*
Y522042D01*
G01X1041130Y515782D02*
Y512582D01*
G01X1049627Y1352762D02*
Y1359062D01*
X1051193D01*
X1051820Y1358747D01*
X1052290Y1358327D01*
X1052682Y1357697D01*
X1052995Y1356962D01*
X1053073Y1355912D01*
X1052995Y1354862D01*
X1052682Y1354127D01*
X1052290Y1353497D01*
X1051820Y1353077D01*
X1051193Y1352762D01*
X1049627D01*
G01X1056710Y1359062D02*
X1058590D01*
G01X1057650D02*
Y1352762D01*
G01X1056710D02*
X1058590D01*
G01X1061913D02*
Y1359062D01*
X1063950Y1353812D01*
X1065987Y1359062D01*
Y1352762D01*
G01X1068213D02*
Y1359062D01*
X1070250Y1353812D01*
X1072287Y1359062D01*
Y1352762D01*
G01X1049000Y1363254D02*
X1042700Y1365212D01*
X1049000Y1367170D01*
G01X1046795Y1366465D02*
Y1363959D01*
G01X1043750Y1370024D02*
X1043120Y1370494D01*
X1042805Y1371042D01*
X1042700Y1371669D01*
X1042910Y1372452D01*
X1043435Y1373000D01*
X1044065Y1373157D01*
X1044695Y1373079D01*
X1045220Y1372765D01*
X1046270Y1371199D01*
X1047005Y1370494D01*
X1048055Y1370024D01*
X1049000Y1369867D01*
Y1373157D01*
G01X1052725Y1366935D02*
X1052410Y1366465D01*
X1052200Y1365917D01*
Y1365290D01*
X1052515Y1364585D01*
X1053040Y1364037D01*
X1053670Y1363645D01*
X1054720Y1363332D01*
X1055665Y1363254D01*
X1056610Y1363410D01*
X1057240Y1363645D01*
X1057870Y1364115D01*
X1058290Y1364664D01*
X1058500Y1365212D01*
Y1365760D01*
X1058290Y1366309D01*
X1057975Y1366779D01*
X1057555Y1367170D01*
G01X1053250Y1370024D02*
X1052620Y1370494D01*
X1052305Y1371042D01*
X1052200Y1371669D01*
X1052410Y1372452D01*
X1052935Y1373000D01*
X1053565Y1373157D01*
X1054195Y1373079D01*
X1054720Y1372765D01*
X1055770Y1371199D01*
X1056505Y1370494D01*
X1057555Y1370024D01*
X1058500Y1369867D01*
Y1373157D01*
G01X1050500Y1375062D02*
Y1361562D01*
G01X1059700D02*
X1050500D01*
G01X1041300Y1375062D02*
Y1361562D01*
G01X1050500D02*
X1041300D01*
G01X1050500Y1375062D02*
X1059700D01*
G01X1041300D02*
X1050500D01*
G01X1040353Y1536409D02*
Y1539509D01*
X1041273D01*
X1041580Y1539354D01*
X1041810Y1538992D01*
X1041887Y1538579D01*
X1041810Y1538166D01*
X1041618Y1537856D01*
X1041273Y1537701D01*
X1040353D01*
G01X1043453Y1536409D02*
Y1539509D01*
X1044373D01*
X1044680Y1539354D01*
X1044910Y1538992D01*
X1044987Y1538579D01*
X1044910Y1538166D01*
X1044718Y1537856D01*
X1044373Y1537701D01*
X1043453D01*
G01X1047320Y1536409D02*
X1047013Y1536461D01*
X1046745Y1536667D01*
X1046515Y1536977D01*
X1046362Y1537339D01*
X1046285Y1537752D01*
Y1538166D01*
X1046362Y1538579D01*
X1046515Y1538941D01*
X1046745Y1539251D01*
X1047013Y1539457D01*
X1047320Y1539509D01*
X1047627Y1539457D01*
X1047895Y1539251D01*
X1048125Y1538941D01*
X1048278Y1538579D01*
X1048355Y1538166D01*
Y1537752D01*
X1048278Y1537339D01*
X1048125Y1536977D01*
X1047895Y1536667D01*
X1047627Y1536461D01*
X1047320Y1536409D01*
G01X1047627Y1537236D02*
X1048087Y1536409D01*
G01X1050343D02*
X1050420Y1537081D01*
X1050535Y1537649D01*
X1050688Y1538166D01*
X1050880Y1538734D01*
X1051187Y1539509D01*
X1049653D01*
G01X1053343Y1553455D02*
X1059543D01*
Y1550255D01*
X1053343D01*
Y1553455D01*
G01X1044298Y1619700D02*
X1072498D01*
Y1588300D01*
X1044298D01*
Y1619700D01*
G01X1074272Y1682410D02*
X1041688D01*
G01X1062236Y59299D02*
Y57077D01*
X1062389Y56612D01*
X1062696Y56302D01*
X1063079Y56199D01*
X1063462Y56302D01*
X1063769Y56612D01*
X1063922Y57077D01*
Y59299D01*
G01X1065451Y58782D02*
X1065681Y59092D01*
X1065949Y59247D01*
X1066256Y59299D01*
X1066639Y59196D01*
X1066907Y58937D01*
X1066984Y58627D01*
X1066946Y58317D01*
X1066792Y58059D01*
X1066026Y57542D01*
X1065681Y57181D01*
X1065451Y56664D01*
X1065374Y56199D01*
X1066984D01*
G01X1069279D02*
Y59299D01*
X1068819Y58679D01*
G01Y56199D02*
X1069739D01*
G01X1071727Y56561D02*
X1071996Y56302D01*
X1072302Y56199D01*
X1072609Y56302D01*
X1072877Y56612D01*
X1073069Y57077D01*
X1073146Y57542D01*
Y58111D01*
X1073069Y58576D01*
X1072877Y58989D01*
X1072647Y59196D01*
X1072379Y59299D01*
X1072072Y59196D01*
X1071842Y58989D01*
X1071689Y58679D01*
X1071612Y58266D01*
X1071689Y57904D01*
X1071881Y57542D01*
X1072111Y57336D01*
X1072379Y57284D01*
X1072686Y57387D01*
X1072916Y57646D01*
X1073146Y58111D01*
G01X1066614Y118068D02*
G03X1149537Y118512I41378J15798D01*
G01X1066614Y119204D02*
Y118068D01*
G01X1149262Y118905D02*
G02X1066535Y119432I-41270J14961D01*
G01D02*
Y148300D01*
G01X1061146Y168328D02*
Y137934D01*
G01X1066614Y149664D02*
Y148528D01*
G01X1149537Y149220D02*
G03X1066614Y149664I-41545J-15354D01*
G01X1066535Y148300D02*
G02X1149262Y148827I41457J-14434D01*
G01X1069321Y263974D02*
Y267174D01*
G01X1075521Y263974D02*
X1069321D01*
G01Y267174D02*
X1075521D01*
G01X1058347Y360482D02*
Y358260D01*
X1058500Y357795D01*
X1058807Y357485D01*
X1059190Y357382D01*
X1059573Y357485D01*
X1059880Y357795D01*
X1060033Y358260D01*
Y360482D01*
G01X1062213Y357382D02*
X1062290Y358054D01*
X1062405Y358622D01*
X1062558Y359139D01*
X1062750Y359707D01*
X1063057Y360482D01*
X1061523D01*
G01X1065390D02*
X1065083Y360379D01*
X1064853Y360120D01*
X1064700Y359810D01*
X1064585Y359397D01*
X1064547Y358932D01*
X1064585Y358467D01*
X1064700Y358054D01*
X1064853Y357744D01*
X1065083Y357485D01*
X1065390Y357382D01*
X1065697Y357485D01*
X1065927Y357744D01*
X1066080Y358054D01*
X1066195Y358467D01*
X1066233Y358932D01*
X1066195Y359397D01*
X1066080Y359810D01*
X1065927Y360120D01*
X1065697Y360379D01*
X1065390Y360482D01*
G01X1056991Y362285D02*
Y377639D01*
G01X1069669Y362285D02*
X1056991D01*
G01X1069669Y377639D02*
Y362285D01*
G01X1054305Y367795D02*
Y361595D01*
G01X1057188Y377639D02*
X1069669D01*
G01X1068105Y380541D02*
Y383741D01*
G01X1074305Y380541D02*
X1068105D01*
G01Y383741D02*
X1074305D01*
G01X1068055Y388323D02*
X1074255D01*
G01X1068055Y385123D02*
Y388323D01*
G01X1074255Y385123D02*
X1068055D01*
G01X1063511Y520026D02*
Y507822D01*
G01X1057749Y510924D02*
X1054749Y507822D01*
G01X1060851D02*
X1057749Y510924D01*
G01X1063511Y507822D02*
X1060851D01*
G01X1058757Y697211D02*
Y699742D01*
G01X1062867Y1335007D02*
Y719652D01*
G01X1058757Y720042D02*
Y1335007D01*
G01X1088457Y732644D02*
X1062867D01*
G01X1088457Y1299574D02*
X1062867D01*
G01X1061545Y1336996D02*
X1061737Y1336686D01*
X1061967Y1336479D01*
X1062235Y1336376D01*
X1062542Y1336479D01*
X1062772Y1336686D01*
X1063002Y1336996D01*
X1063079Y1337409D01*
Y1339476D01*
G01X1064569Y1336841D02*
X1064799Y1336583D01*
X1065067Y1336428D01*
X1065412Y1336376D01*
X1065757Y1336479D01*
X1066025Y1336686D01*
X1066217Y1337048D01*
X1066255Y1337461D01*
X1066179Y1337874D01*
X1065987Y1338133D01*
X1065719Y1338339D01*
X1065450Y1338391D01*
X1065182Y1338339D01*
X1064837Y1338133D01*
X1064952Y1339476D01*
X1065987D01*
G01X1088457Y1335007D02*
X1062867D01*
G01X1067500Y1363754D02*
X1061200Y1365712D01*
X1067500Y1367670D01*
G01X1065295Y1366965D02*
Y1364459D01*
G01X1067500Y1372012D02*
X1061200D01*
X1062460Y1371072D01*
G01X1067500D02*
Y1372952D01*
G01X1070725Y1366935D02*
X1070410Y1366465D01*
X1070200Y1365917D01*
Y1365290D01*
X1070515Y1364585D01*
X1071040Y1364037D01*
X1071670Y1363645D01*
X1072720Y1363332D01*
X1073665Y1363254D01*
X1074610Y1363410D01*
X1075240Y1363645D01*
X1075870Y1364115D01*
X1076290Y1364664D01*
X1076500Y1365212D01*
Y1365760D01*
X1076290Y1366309D01*
X1075975Y1366779D01*
X1075555Y1367170D01*
G01X1076500Y1371512D02*
X1070200D01*
X1071460Y1370572D01*
G01X1076500D02*
Y1372452D01*
G01X1068900Y1375062D02*
Y1361562D01*
G01X1078100D02*
X1068900D01*
G01X1059700Y1375062D02*
Y1361562D01*
G01X1068900D02*
X1059700D01*
G01X1068900Y1375062D02*
X1078100D01*
G01X1059700D02*
X1068900D01*
G01X1063443Y1536643D02*
Y1539743D01*
X1064363D01*
X1064670Y1539588D01*
X1064900Y1539226D01*
X1064977Y1538813D01*
X1064900Y1538400D01*
X1064708Y1538090D01*
X1064363Y1537935D01*
X1063443D01*
G01X1066543Y1536643D02*
Y1539743D01*
X1067463D01*
X1067770Y1539588D01*
X1068000Y1539226D01*
X1068077Y1538813D01*
X1068000Y1538400D01*
X1067808Y1538090D01*
X1067463Y1537935D01*
X1066543D01*
G01X1070410Y1536643D02*
X1070103Y1536695D01*
X1069835Y1536901D01*
X1069605Y1537211D01*
X1069452Y1537573D01*
X1069375Y1537986D01*
Y1538400D01*
X1069452Y1538813D01*
X1069605Y1539175D01*
X1069835Y1539485D01*
X1070103Y1539691D01*
X1070410Y1539743D01*
X1070717Y1539691D01*
X1070985Y1539485D01*
X1071215Y1539175D01*
X1071368Y1538813D01*
X1071445Y1538400D01*
Y1537986D01*
X1071368Y1537573D01*
X1071215Y1537211D01*
X1070985Y1536901D01*
X1070717Y1536695D01*
X1070410Y1536643D01*
G01X1070717Y1537470D02*
X1071177Y1536643D01*
G01X1073510D02*
X1073778Y1536695D01*
X1074085Y1536850D01*
X1074277Y1537108D01*
X1074353Y1537470D01*
X1074277Y1537831D01*
X1074047Y1538141D01*
X1073702Y1538296D01*
X1073318D01*
X1073088Y1538400D01*
X1072897Y1538658D01*
X1072820Y1539020D01*
X1072935Y1539381D01*
X1073203Y1539640D01*
X1073510Y1539743D01*
X1073817Y1539640D01*
X1074085Y1539381D01*
X1074200Y1539020D01*
X1074123Y1538658D01*
X1073932Y1538400D01*
X1073702Y1538296D01*
X1073318D01*
X1072973Y1538141D01*
X1072743Y1537831D01*
X1072667Y1537470D01*
X1072743Y1537108D01*
X1072935Y1536850D01*
X1073242Y1536695D01*
X1073510Y1536643D01*
G01X1057801Y1579252D02*
Y1560748D01*
X1056868D01*
G01X1061134D02*
X1060301D01*
Y1579252D01*
X1060934D01*
G01X1057168D02*
X1057801D01*
G01X1077125Y53320D02*
X1090773D01*
G01X1077125Y65524D02*
Y53320D01*
G01X1086551Y65524D02*
X1083949Y62922D01*
G01X1081347Y65524D02*
X1077125D01*
G01X1083949Y62922D02*
X1081347Y65524D01*
G01X1082621Y68002D02*
Y71202D01*
G01X1088821Y68002D02*
X1082621D01*
G01Y71202D02*
X1088821D01*
G01X1077589Y76953D02*
Y80153D01*
G01X1083789Y76953D02*
X1077589D01*
G01X1083789Y80153D02*
Y76953D01*
G01X1077589Y80153D02*
X1083789D01*
G01Y85298D02*
Y82098D01*
G01X1077589Y85298D02*
X1083789D01*
G01X1077589Y82098D02*
Y85298D01*
G01X1083789Y82098D02*
X1077589D01*
G01X1085657Y242032D02*
X1083417D01*
G01X1084630Y240407D02*
Y243657D01*
G01X1086031Y245304D02*
X1086034Y262244D01*
G01X1087231Y245304D02*
X1086031D01*
G01Y262236D02*
Y245306D01*
G01X1087181Y262237D02*
X1085672Y262233D01*
G01X1075521Y267174D02*
Y263974D01*
G01X1084710Y380851D02*
Y377651D01*
G01X1078510D02*
Y380851D01*
G01X1084710Y377651D02*
X1078510D01*
G01X1084590Y370661D02*
Y367461D01*
G01X1078390Y370661D02*
X1084590D01*
G01X1078390Y367461D02*
Y370661D01*
G01X1084590Y367461D02*
X1078390D01*
G01X1084650Y375731D02*
Y372531D01*
G01X1078450Y375731D02*
X1084650D01*
G01X1078450Y372531D02*
Y375731D01*
G01X1084650Y372531D02*
X1078450D01*
G01X1074305Y383741D02*
Y380541D01*
G01X1074255Y388323D02*
Y385123D01*
G01X1078510Y380851D02*
X1084710D01*
G01X1072064Y508045D02*
Y511245D01*
G01X1078264Y508045D02*
X1072064D01*
G01X1078264Y511245D02*
Y508045D01*
G01X1072064Y511245D02*
X1078264D01*
G01X1116974Y605380D02*
G03I-22900J0D01*
G01X1084369Y636280D02*
Y639380D01*
G01X1085979D02*
Y636280D01*
G01Y637830D02*
X1084369D01*
G01X1088274Y636280D02*
Y639380D01*
X1087814Y638760D01*
G01Y636280D02*
X1088734D01*
G01X1090646Y638863D02*
X1090876Y639173D01*
X1091144Y639328D01*
X1091451Y639380D01*
X1091834Y639277D01*
X1092102Y639018D01*
X1092179Y638708D01*
X1092141Y638398D01*
X1091987Y638140D01*
X1091221Y637623D01*
X1090876Y637262D01*
X1090646Y636745D01*
X1090569Y636280D01*
X1092179D01*
G01X1093746Y638863D02*
X1093976Y639173D01*
X1094244Y639328D01*
X1094551Y639380D01*
X1094934Y639277D01*
X1095202Y639018D01*
X1095279Y638708D01*
X1095241Y638398D01*
X1095087Y638140D01*
X1094321Y637623D01*
X1093976Y637262D01*
X1093746Y636745D01*
X1093669Y636280D01*
X1095279D01*
G01X1086000Y1363254D02*
X1079700Y1365212D01*
X1086000Y1367170D01*
G01X1083795Y1366465D02*
Y1363959D01*
G01X1079700Y1371512D02*
X1079910Y1370885D01*
X1080435Y1370415D01*
X1081065Y1370102D01*
X1081905Y1369867D01*
X1082850Y1369789D01*
X1083795Y1369867D01*
X1084635Y1370102D01*
X1085265Y1370415D01*
X1085790Y1370885D01*
X1086000Y1371512D01*
X1085790Y1372139D01*
X1085265Y1372609D01*
X1084635Y1372922D01*
X1083795Y1373157D01*
X1082850Y1373235D01*
X1081905Y1373157D01*
X1081065Y1372922D01*
X1080435Y1372609D01*
X1079910Y1372139D01*
X1079700Y1371512D01*
G01X1078100Y1375062D02*
Y1361562D01*
G01X1087300D02*
X1078100D01*
G01Y1375062D02*
X1087300D01*
G01X1086283Y1536357D02*
Y1539457D01*
X1087203D01*
X1087510Y1539302D01*
X1087740Y1538940D01*
X1087817Y1538527D01*
X1087740Y1538114D01*
X1087548Y1537804D01*
X1087203Y1537649D01*
X1086283D01*
G01X1089383Y1536357D02*
Y1539457D01*
X1090303D01*
X1090610Y1539302D01*
X1090840Y1538940D01*
X1090917Y1538527D01*
X1090840Y1538114D01*
X1090648Y1537804D01*
X1090303Y1537649D01*
X1089383D01*
G01X1093250Y1536357D02*
X1092943Y1536409D01*
X1092675Y1536615D01*
X1092445Y1536925D01*
X1092292Y1537287D01*
X1092215Y1537700D01*
Y1538114D01*
X1092292Y1538527D01*
X1092445Y1538889D01*
X1092675Y1539199D01*
X1092943Y1539405D01*
X1093250Y1539457D01*
X1093557Y1539405D01*
X1093825Y1539199D01*
X1094055Y1538889D01*
X1094208Y1538527D01*
X1094285Y1538114D01*
Y1537700D01*
X1094208Y1537287D01*
X1094055Y1536925D01*
X1093825Y1536615D01*
X1093557Y1536409D01*
X1093250Y1536357D01*
G01X1093557Y1537184D02*
X1094017Y1536357D01*
G01X1095698Y1536719D02*
X1095967Y1536460D01*
X1096273Y1536357D01*
X1096580Y1536460D01*
X1096848Y1536770D01*
X1097040Y1537235D01*
X1097117Y1537700D01*
Y1538269D01*
X1097040Y1538734D01*
X1096848Y1539147D01*
X1096618Y1539354D01*
X1096350Y1539457D01*
X1096043Y1539354D01*
X1095813Y1539147D01*
X1095660Y1538837D01*
X1095583Y1538424D01*
X1095660Y1538062D01*
X1095852Y1537700D01*
X1096082Y1537494D01*
X1096350Y1537442D01*
X1096657Y1537545D01*
X1096887Y1537804D01*
X1097117Y1538269D01*
G01X1076709Y1553455D02*
X1082909D01*
Y1550255D01*
X1076709D01*
Y1553455D01*
G01X1081167Y1579252D02*
Y1560748D01*
X1080234D01*
G01X1084500D02*
X1083667D01*
Y1579252D01*
X1084300D01*
G01X1080534D02*
X1081167D01*
G01X1071800Y1645540D02*
Y1643318D01*
X1071953Y1642853D01*
X1072260Y1642543D01*
X1072643Y1642440D01*
X1073026Y1642543D01*
X1073333Y1642853D01*
X1073486Y1643318D01*
Y1645540D01*
G01X1074900Y1643060D02*
X1075130Y1642698D01*
X1075436Y1642492D01*
X1075781Y1642440D01*
X1076088Y1642492D01*
X1076395Y1642750D01*
X1076586Y1643060D01*
X1076625Y1643370D01*
X1076548Y1643732D01*
X1076280Y1643990D01*
X1076011Y1644093D01*
X1075666D01*
G01X1076011D02*
X1076241Y1644248D01*
X1076433Y1644507D01*
X1076510Y1644817D01*
X1076433Y1645127D01*
X1076241Y1645385D01*
X1075896Y1645540D01*
X1075551Y1645488D01*
X1075206Y1645282D01*
G01X1078115Y1645023D02*
X1078345Y1645333D01*
X1078613Y1645488D01*
X1078920Y1645540D01*
X1079303Y1645437D01*
X1079571Y1645178D01*
X1079648Y1644868D01*
X1079610Y1644558D01*
X1079456Y1644300D01*
X1078690Y1643783D01*
X1078345Y1643422D01*
X1078115Y1642905D01*
X1078038Y1642440D01*
X1079648D01*
G01X1081291Y1642802D02*
X1081560Y1642543D01*
X1081866Y1642440D01*
X1082173Y1642543D01*
X1082441Y1642853D01*
X1082633Y1643318D01*
X1082710Y1643783D01*
Y1644352D01*
X1082633Y1644817D01*
X1082441Y1645230D01*
X1082211Y1645437D01*
X1081943Y1645540D01*
X1081636Y1645437D01*
X1081406Y1645230D01*
X1081253Y1644920D01*
X1081176Y1644507D01*
X1081253Y1644145D01*
X1081445Y1643783D01*
X1081675Y1643577D01*
X1081943Y1643525D01*
X1082250Y1643628D01*
X1082480Y1643887D01*
X1082710Y1644352D01*
G01X1074145Y1648044D02*
Y1659856D01*
X1086769D01*
Y1648044D01*
X1074145D01*
G01X1074857Y1665550D02*
X1081057D01*
Y1662350D01*
X1074857D01*
Y1665550D01*
G01X1074272Y1692083D02*
Y1682410D01*
G01Y1775402D02*
Y1717697D01*
G01X1090773Y53320D02*
Y65524D01*
G01X1102532Y53905D02*
Y57105D01*
G01X1108732Y53905D02*
X1102532D01*
G01X1090773Y65524D02*
X1086551D01*
G01X1093119Y63662D02*
Y66862D01*
G01X1099319Y63662D02*
X1093119D01*
G01X1099319Y66862D02*
Y63662D01*
G01X1093119Y66862D02*
X1099319D01*
G01X1088821Y71202D02*
Y68002D01*
G01X1102572Y61628D02*
X1108772D01*
G01X1102572Y58428D02*
Y61628D01*
G01X1108772Y58428D02*
X1102572D01*
G01X1102532Y57105D02*
X1108732D01*
G01X1091586Y84869D02*
Y82647D01*
X1091739Y82182D01*
X1092046Y81872D01*
X1092429Y81769D01*
X1092812Y81872D01*
X1093119Y82182D01*
X1093272Y82647D01*
Y84869D01*
G01X1094801Y84352D02*
X1095031Y84662D01*
X1095299Y84817D01*
X1095606Y84869D01*
X1095989Y84766D01*
X1096257Y84507D01*
X1096334Y84197D01*
X1096296Y83887D01*
X1096142Y83629D01*
X1095376Y83112D01*
X1095031Y82751D01*
X1094801Y82234D01*
X1094724Y81769D01*
X1096334D01*
G01X1098629D02*
Y84869D01*
X1098169Y84249D01*
G01Y81769D02*
X1099089D01*
G01X1101652D02*
X1101729Y82441D01*
X1101844Y83009D01*
X1101997Y83526D01*
X1102189Y84094D01*
X1102496Y84869D01*
X1100962D01*
G01X1101633Y80233D02*
Y71571D01*
G01X1090609Y80233D02*
X1101633D01*
G01X1090609Y71571D02*
Y80233D01*
G01Y71571D02*
X1101633D01*
G01X1086631Y245304D02*
X1086635Y262279D01*
G01X1087231Y245304D02*
X1087225Y262287D01*
G01X1111627Y255425D02*
G03I-10827J0D01*
G01D02*
X1089973D01*
G01X1086716Y274750D02*
Y268802D01*
G01X1111527Y279725D02*
X1089873D01*
G01X1111527D02*
G03I-10827J0D01*
G01X1086716Y293998D02*
Y288050D01*
G01X1090010Y377651D02*
Y380851D01*
G01X1096210Y377651D02*
X1090010D01*
G01X1096210Y380851D02*
Y377651D01*
G01X1089890Y367461D02*
Y370661D01*
G01X1096090Y367461D02*
X1089890D01*
G01X1096090Y370661D02*
Y367461D01*
G01X1089890Y370661D02*
X1096090D01*
G01X1089950Y372531D02*
Y375731D01*
G01X1096150Y372531D02*
X1089950D01*
G01X1096150Y375731D02*
Y372531D01*
G01X1089950Y375731D02*
X1096150D01*
G01X1090010Y380851D02*
X1096210D01*
G01X1092567Y1335007D02*
Y708932D01*
G01X1088457Y709002D02*
Y1335007D01*
G01X1118157Y732644D02*
X1092567D01*
G01X1118157Y1299574D02*
X1092567D01*
G01X1091245Y1336996D02*
X1091437Y1336686D01*
X1091667Y1336479D01*
X1091935Y1336376D01*
X1092242Y1336479D01*
X1092472Y1336686D01*
X1092702Y1336996D01*
X1092779Y1337409D01*
Y1339476D01*
G01X1094384Y1337668D02*
X1094652Y1338029D01*
X1094882Y1338236D01*
X1095189Y1338339D01*
X1095457Y1338236D01*
X1095649Y1338029D01*
X1095802Y1337719D01*
X1095840Y1337358D01*
X1095802Y1337048D01*
X1095649Y1336738D01*
X1095419Y1336479D01*
X1095150Y1336376D01*
X1094844Y1336479D01*
X1094575Y1336789D01*
X1094422Y1337254D01*
X1094384Y1337771D01*
X1094460Y1338443D01*
X1094575Y1338804D01*
X1094767Y1339166D01*
X1095035Y1339424D01*
X1095304Y1339476D01*
X1095572Y1339373D01*
X1095764Y1339114D01*
G01X1118157Y1335007D02*
X1092567D01*
G01X1096500Y1351862D02*
Y1375062D01*
G01X1089225Y1366935D02*
X1088910Y1366465D01*
X1088700Y1365917D01*
Y1365290D01*
X1089015Y1364585D01*
X1089540Y1364037D01*
X1090170Y1363645D01*
X1091220Y1363332D01*
X1092165Y1363254D01*
X1093110Y1363410D01*
X1093740Y1363645D01*
X1094370Y1364115D01*
X1094790Y1364664D01*
X1095000Y1365212D01*
Y1365760D01*
X1094790Y1366309D01*
X1094475Y1366779D01*
X1094055Y1367170D01*
G01X1088700Y1371512D02*
X1088910Y1370885D01*
X1089435Y1370415D01*
X1090065Y1370102D01*
X1090905Y1369867D01*
X1091850Y1369789D01*
X1092795Y1369867D01*
X1093635Y1370102D01*
X1094265Y1370415D01*
X1094790Y1370885D01*
X1095000Y1371512D01*
X1094790Y1372139D01*
X1094265Y1372609D01*
X1093635Y1372922D01*
X1092795Y1373157D01*
X1091850Y1373235D01*
X1090905Y1373157D01*
X1090065Y1372922D01*
X1089435Y1372609D01*
X1088910Y1372139D01*
X1088700Y1371512D01*
G01X1087300Y1375062D02*
Y1361562D01*
G01X1096500D02*
X1087300D01*
G01Y1375062D02*
X1096500D01*
G01X1094383Y1456362D02*
Y1459462D01*
X1095303D01*
X1095610Y1459307D01*
X1095840Y1458945D01*
X1095917Y1458532D01*
X1095840Y1458119D01*
X1095648Y1457809D01*
X1095303Y1457654D01*
X1094383D01*
G01X1097407Y1459462D02*
Y1457240D01*
X1097560Y1456775D01*
X1097867Y1456465D01*
X1098250Y1456362D01*
X1098633Y1456465D01*
X1098940Y1456775D01*
X1099093Y1457240D01*
Y1459462D01*
G01X1101273Y1456362D02*
X1101350Y1457034D01*
X1101465Y1457602D01*
X1101618Y1458119D01*
X1101810Y1458687D01*
X1102117Y1459462D01*
X1100583D01*
G01X1103722Y1458945D02*
X1103952Y1459255D01*
X1104220Y1459410D01*
X1104527Y1459462D01*
X1104910Y1459359D01*
X1105178Y1459100D01*
X1105255Y1458790D01*
X1105217Y1458480D01*
X1105063Y1458222D01*
X1104297Y1457705D01*
X1103952Y1457344D01*
X1103722Y1456827D01*
X1103645Y1456362D01*
X1105255D01*
G01X1106400Y1455329D02*
X1108700D01*
G01X1109883Y1456362D02*
Y1459462D01*
X1110803D01*
X1111110Y1459307D01*
X1111340Y1458945D01*
X1111417Y1458532D01*
X1111340Y1458119D01*
X1111148Y1457809D01*
X1110803Y1457654D01*
X1109883D01*
G01X1113750Y1459462D02*
X1113443Y1459359D01*
X1113213Y1459100D01*
X1113060Y1458790D01*
X1112945Y1458377D01*
X1112907Y1457912D01*
X1112945Y1457447D01*
X1113060Y1457034D01*
X1113213Y1456724D01*
X1113443Y1456465D01*
X1113750Y1456362D01*
X1114057Y1456465D01*
X1114287Y1456724D01*
X1114440Y1457034D01*
X1114555Y1457447D01*
X1114593Y1457912D01*
X1114555Y1458377D01*
X1114440Y1458790D01*
X1114287Y1459100D01*
X1114057Y1459359D01*
X1113750Y1459462D01*
G01X1115700Y1455329D02*
X1118000D01*
G01X1120410Y1456362D02*
Y1459462D01*
X1118992Y1457240D01*
X1120908D01*
G01X1100075Y1553455D02*
X1106275D01*
Y1550255D01*
X1100075D01*
Y1553455D01*
G01X1100836Y1619844D02*
Y1588044D01*
X1087036D01*
Y1619844D01*
X1100836D01*
G01X1089857Y1639750D02*
Y1645950D01*
X1093057D01*
Y1639750D01*
X1089857D01*
G01X1097057Y1645950D02*
Y1639750D01*
X1093857D01*
Y1645950D01*
X1097057D01*
G01X1101857Y1639750D02*
Y1645950D01*
X1105057D01*
Y1639750D01*
X1101857D01*
G01X1101057Y1645950D02*
Y1639750D01*
X1097857D01*
Y1645950D01*
X1101057D01*
G01X1093798Y1655950D02*
X1090353Y1652705D01*
Y1647935D01*
X1102361D01*
Y1663965D01*
X1090353D01*
Y1659195D01*
X1093798Y1655950D01*
G01X1096930Y1681470D02*
X1103130D01*
Y1678270D01*
X1096930D01*
Y1681470D01*
G01Y1677570D02*
X1103130D01*
Y1674370D01*
X1096930D01*
Y1677570D01*
G01X1092890Y1669363D02*
X1086690D01*
Y1672563D01*
X1092890D01*
Y1669363D01*
G01X1095450Y1673630D02*
X1101650D01*
Y1670430D01*
X1095450D01*
Y1673630D01*
G01X1095049Y1727767D02*
X1104891D01*
Y1697373D01*
X1095049D01*
Y1727767D01*
G01X1088503Y1684297D02*
X1088695Y1683987D01*
X1088925Y1683780D01*
X1089193Y1683677D01*
X1089500Y1683780D01*
X1089730Y1683987D01*
X1089960Y1684297D01*
X1090037Y1684710D01*
Y1686777D01*
G01X1092830Y1683677D02*
Y1686777D01*
X1091412Y1684555D01*
X1093328D01*
G01X1094627Y1684142D02*
X1094857Y1683884D01*
X1095125Y1683729D01*
X1095470Y1683677D01*
X1095815Y1683780D01*
X1096083Y1683987D01*
X1096275Y1684349D01*
X1096313Y1684762D01*
X1096237Y1685175D01*
X1096045Y1685434D01*
X1095777Y1685640D01*
X1095508Y1685692D01*
X1095240Y1685640D01*
X1094895Y1685434D01*
X1095010Y1686777D01*
X1096045D01*
G01X1092127Y1701590D02*
X1092357Y1701228D01*
X1092663Y1701022D01*
X1093008Y1700970D01*
X1093315Y1701022D01*
X1093622Y1701280D01*
X1093813Y1701590D01*
X1093852Y1701900D01*
X1093775Y1702262D01*
X1093507Y1702520D01*
X1093238Y1702623D01*
X1092893D01*
G01X1093238D02*
X1093468Y1702778D01*
X1093660Y1703037D01*
X1093737Y1703347D01*
X1093660Y1703657D01*
X1093468Y1703915D01*
X1093123Y1704070D01*
X1092778Y1704018D01*
X1092433Y1703812D01*
G01X1094803Y1729707D02*
X1094995Y1729397D01*
X1095225Y1729190D01*
X1095493Y1729087D01*
X1095800Y1729190D01*
X1096030Y1729397D01*
X1096260Y1729707D01*
X1096337Y1730120D01*
Y1732187D01*
G01X1097903Y1729087D02*
Y1732187D01*
X1098823D01*
X1099130Y1732032D01*
X1099360Y1731670D01*
X1099437Y1731257D01*
X1099360Y1730844D01*
X1099168Y1730534D01*
X1098823Y1730379D01*
X1097903D01*
G01X1101770Y1729087D02*
Y1732187D01*
X1101310Y1731567D01*
G01Y1729087D02*
X1102230D01*
G01X1104870Y1732187D02*
X1104563Y1732084D01*
X1104333Y1731825D01*
X1104180Y1731515D01*
X1104065Y1731102D01*
X1104027Y1730637D01*
X1104065Y1730172D01*
X1104180Y1729759D01*
X1104333Y1729449D01*
X1104563Y1729190D01*
X1104870Y1729087D01*
X1105177Y1729190D01*
X1105407Y1729449D01*
X1105560Y1729759D01*
X1105675Y1730172D01*
X1105713Y1730637D01*
X1105675Y1731102D01*
X1105560Y1731515D01*
X1105407Y1731825D01*
X1105177Y1732084D01*
X1104870Y1732187D01*
G01X1108732Y57105D02*
Y53905D01*
G01X1108772Y61628D02*
Y58428D01*
G01X1115119Y74403D02*
Y71203D01*
G01X1108919Y74403D02*
X1115119D01*
G01X1108919Y71203D02*
Y74403D01*
G01X1115119Y71203D02*
X1108919D01*
G01X1115119Y79159D02*
Y75959D01*
G01X1108919Y79159D02*
X1115119D01*
G01X1108919Y75959D02*
Y79159D01*
G01X1115119Y75959D02*
X1108919D01*
G01X1112465Y361892D02*
X1126865D01*
G01X1112465Y381578D02*
Y361892D01*
G01X1119665Y377335D02*
X1115422Y381578D01*
G01X1114072Y387602D02*
Y385380D01*
X1114225Y384915D01*
X1114532Y384605D01*
X1114915Y384502D01*
X1115298Y384605D01*
X1115605Y384915D01*
X1115758Y385380D01*
Y387602D01*
G01X1117287Y385794D02*
X1117555Y386155D01*
X1117785Y386362D01*
X1118092Y386465D01*
X1118360Y386362D01*
X1118552Y386155D01*
X1118705Y385845D01*
X1118743Y385484D01*
X1118705Y385174D01*
X1118552Y384864D01*
X1118322Y384605D01*
X1118053Y384502D01*
X1117747Y384605D01*
X1117478Y384915D01*
X1117325Y385380D01*
X1117287Y385897D01*
X1117363Y386569D01*
X1117478Y386930D01*
X1117670Y387292D01*
X1117938Y387550D01*
X1118207Y387602D01*
X1118475Y387499D01*
X1118667Y387240D01*
G01X1121575Y384502D02*
Y387602D01*
X1120157Y385380D01*
X1122073D01*
G01X1115422Y381578D02*
X1112465D01*
G01X1118157Y697211D02*
Y1335007D01*
G01X1105383Y1402362D02*
Y1405462D01*
X1106303D01*
X1106610Y1405307D01*
X1106840Y1404945D01*
X1106917Y1404532D01*
X1106840Y1404119D01*
X1106648Y1403809D01*
X1106303Y1403654D01*
X1105383D01*
G01X1108483Y1405462D02*
Y1402362D01*
X1110017D01*
G01X1111622Y1404945D02*
X1111852Y1405255D01*
X1112120Y1405410D01*
X1112427Y1405462D01*
X1112810Y1405359D01*
X1113078Y1405100D01*
X1113155Y1404790D01*
X1113117Y1404480D01*
X1112963Y1404222D01*
X1112197Y1403705D01*
X1111852Y1403344D01*
X1111622Y1402827D01*
X1111545Y1402362D01*
X1113155D01*
G01X1115450D02*
Y1405462D01*
X1114990Y1404842D01*
G01Y1402362D02*
X1115910D01*
G01X1118550Y1405462D02*
X1118243Y1405359D01*
X1118013Y1405100D01*
X1117860Y1404790D01*
X1117745Y1404377D01*
X1117707Y1403912D01*
X1117745Y1403447D01*
X1117860Y1403034D01*
X1118013Y1402724D01*
X1118243Y1402465D01*
X1118550Y1402362D01*
X1118857Y1402465D01*
X1119087Y1402724D01*
X1119240Y1403034D01*
X1119355Y1403447D01*
X1119393Y1403912D01*
X1119355Y1404377D01*
X1119240Y1404790D01*
X1119087Y1405100D01*
X1118857Y1405359D01*
X1118550Y1405462D01*
G01X1114328Y1427474D02*
Y1430674D01*
G01X1120528Y1427474D02*
X1114328D01*
G01Y1430674D02*
X1120528D01*
G01X1114328Y1431004D02*
Y1434204D01*
G01X1120528Y1431004D02*
X1114328D01*
G01Y1434204D02*
X1120528D01*
G01X1104533Y1579252D02*
Y1560748D01*
X1103600D01*
G01X1104840Y1563837D02*
X1107062D01*
X1107527Y1563990D01*
X1107837Y1564297D01*
X1107940Y1564680D01*
X1107837Y1565063D01*
X1107527Y1565370D01*
X1107062Y1565523D01*
X1104840D01*
G01X1107320Y1566937D02*
X1107682Y1567167D01*
X1107888Y1567473D01*
X1107940Y1567818D01*
X1107888Y1568125D01*
X1107630Y1568432D01*
X1107320Y1568623D01*
X1107010Y1568662D01*
X1106648Y1568585D01*
X1106390Y1568317D01*
X1106287Y1568048D01*
Y1567703D01*
G01Y1568048D02*
X1106132Y1568278D01*
X1105873Y1568470D01*
X1105563Y1568547D01*
X1105253Y1568470D01*
X1104995Y1568278D01*
X1104840Y1567933D01*
X1104892Y1567588D01*
X1105098Y1567243D01*
G01X1106648Y1570152D02*
X1106287Y1570420D01*
X1106080Y1570650D01*
X1105977Y1570957D01*
X1106080Y1571225D01*
X1106287Y1571417D01*
X1106597Y1571570D01*
X1106958Y1571608D01*
X1107268Y1571570D01*
X1107578Y1571417D01*
X1107837Y1571187D01*
X1107940Y1570918D01*
X1107837Y1570612D01*
X1107527Y1570343D01*
X1107062Y1570190D01*
X1106545Y1570152D01*
X1105873Y1570228D01*
X1105512Y1570343D01*
X1105150Y1570535D01*
X1104892Y1570803D01*
X1104840Y1571072D01*
X1104943Y1571340D01*
X1105202Y1571532D01*
G01X1107475Y1573137D02*
X1107733Y1573367D01*
X1107888Y1573635D01*
X1107940Y1573980D01*
X1107837Y1574325D01*
X1107630Y1574593D01*
X1107268Y1574785D01*
X1106855Y1574823D01*
X1106442Y1574747D01*
X1106183Y1574555D01*
X1105977Y1574287D01*
X1105925Y1574018D01*
X1105977Y1573750D01*
X1106183Y1573405D01*
X1104840Y1573520D01*
Y1574555D01*
G01X1108940Y1578530D02*
X1121940D01*
Y1563530D01*
X1108940D01*
Y1578530D01*
G01X1103900Y1579252D02*
X1104533D01*
G01X1118872Y1616160D02*
Y1622360D01*
G01X1122072Y1616160D02*
X1118872D01*
G01X1117402Y1622370D02*
Y1616170D01*
G01X1114202D02*
Y1622370D01*
G01X1117402Y1616170D02*
X1114202D01*
G01X1117510Y1613920D02*
X1123710D01*
Y1610720D01*
X1117510D01*
Y1613920D01*
G01X1117480Y1610020D02*
X1123680D01*
Y1606820D01*
X1117480D01*
Y1610020D01*
G01X1118872Y1622360D02*
X1122072D01*
G01X1114202Y1622370D02*
X1117402D01*
G01X1122032Y1623820D02*
X1118832D01*
G01D02*
Y1630020D01*
G01D02*
X1122032D01*
G01X1109890Y1649957D02*
X1112112D01*
X1112577Y1650110D01*
X1112887Y1650417D01*
X1112990Y1650800D01*
X1112887Y1651183D01*
X1112577Y1651490D01*
X1112112Y1651643D01*
X1109890D01*
G01X1112370Y1653057D02*
X1112732Y1653287D01*
X1112938Y1653593D01*
X1112990Y1653938D01*
X1112938Y1654245D01*
X1112680Y1654552D01*
X1112370Y1654743D01*
X1112060Y1654782D01*
X1111698Y1654705D01*
X1111440Y1654437D01*
X1111337Y1654168D01*
Y1653823D01*
G01Y1654168D02*
X1111182Y1654398D01*
X1110923Y1654590D01*
X1110613Y1654667D01*
X1110303Y1654590D01*
X1110045Y1654398D01*
X1109890Y1654053D01*
X1109942Y1653708D01*
X1110148Y1653363D01*
G01X1111698Y1656272D02*
X1111337Y1656540D01*
X1111130Y1656770D01*
X1111027Y1657077D01*
X1111130Y1657345D01*
X1111337Y1657537D01*
X1111647Y1657690D01*
X1112008Y1657728D01*
X1112318Y1657690D01*
X1112628Y1657537D01*
X1112887Y1657307D01*
X1112990Y1657038D01*
X1112887Y1656732D01*
X1112577Y1656463D01*
X1112112Y1656310D01*
X1111595Y1656272D01*
X1110923Y1656348D01*
X1110562Y1656463D01*
X1110200Y1656655D01*
X1109942Y1656923D01*
X1109890Y1657192D01*
X1109993Y1657460D01*
X1110252Y1657652D01*
G01X1112628Y1659448D02*
X1112887Y1659717D01*
X1112990Y1660023D01*
X1112887Y1660330D01*
X1112577Y1660598D01*
X1112112Y1660790D01*
X1111647Y1660867D01*
X1111078D01*
X1110613Y1660790D01*
X1110200Y1660598D01*
X1109993Y1660368D01*
X1109890Y1660100D01*
X1109993Y1659793D01*
X1110200Y1659563D01*
X1110510Y1659410D01*
X1110923Y1659333D01*
X1111285Y1659410D01*
X1111647Y1659602D01*
X1111853Y1659832D01*
X1111905Y1660100D01*
X1111802Y1660407D01*
X1111543Y1660637D01*
X1111078Y1660867D01*
G01X1111540Y1668391D02*
Y1674591D01*
X1114740D01*
Y1668391D01*
X1111540D01*
G01X1110887Y1674540D02*
Y1668340D01*
X1107687D01*
Y1674540D01*
X1110887D01*
G01X1103857Y1668350D02*
Y1674550D01*
X1107057D01*
Y1668350D01*
X1103857D01*
G01X1117183Y1701515D02*
X1114083D01*
G01Y1703125D02*
X1117183D01*
G01X1115633D02*
Y1701515D01*
G01X1116770Y1704615D02*
X1117028Y1704922D01*
X1117183Y1705267D01*
Y1705573D01*
X1117028Y1705880D01*
X1116770Y1706110D01*
X1116408Y1706225D01*
X1116046Y1706148D01*
X1115736Y1705957D01*
X1115530Y1705612D01*
X1115426Y1705152D01*
X1115220Y1704883D01*
X1114858Y1704768D01*
X1114496Y1704845D01*
X1114238Y1705037D01*
X1114083Y1705305D01*
Y1705573D01*
X1114186Y1705842D01*
X1114445Y1706072D01*
G01X1114341Y1709363D02*
X1114186Y1709133D01*
X1114083Y1708865D01*
Y1708558D01*
X1114238Y1708213D01*
X1114496Y1707945D01*
X1114806Y1707753D01*
X1115323Y1707600D01*
X1115788Y1707562D01*
X1116253Y1707638D01*
X1116563Y1707753D01*
X1116873Y1707983D01*
X1117080Y1708252D01*
X1117183Y1708520D01*
Y1708788D01*
X1117080Y1709057D01*
X1116925Y1709287D01*
X1116718Y1709478D01*
G01X1117183Y1713953D02*
X1114083D01*
Y1714873D01*
X1114238Y1715180D01*
X1114600Y1715410D01*
X1115013Y1715487D01*
X1115426Y1715410D01*
X1115736Y1715218D01*
X1115891Y1714873D01*
Y1713953D01*
G01X1117183Y1716823D02*
X1114083D01*
X1116666Y1717820D01*
X1114083Y1718817D01*
X1117183D01*
G01X1115530Y1721227D02*
X1115375Y1721380D01*
X1115116Y1721495D01*
X1114755Y1721572D01*
X1114445Y1721495D01*
X1114238Y1721342D01*
X1114083Y1721073D01*
Y1720038D01*
X1117183D01*
Y1721303D01*
X1116976Y1721572D01*
X1116666Y1721725D01*
X1116305Y1721802D01*
X1115943Y1721725D01*
X1115633Y1721495D01*
X1115530Y1721227D01*
Y1720038D01*
G01X1114083Y1723177D02*
X1116305D01*
X1116770Y1723330D01*
X1117080Y1723637D01*
X1117183Y1724020D01*
X1117080Y1724403D01*
X1116770Y1724710D01*
X1116305Y1724863D01*
X1114083D01*
G01X1116770Y1726315D02*
X1117028Y1726622D01*
X1117183Y1726967D01*
Y1727273D01*
X1117028Y1727580D01*
X1116770Y1727810D01*
X1116408Y1727925D01*
X1116046Y1727848D01*
X1115736Y1727657D01*
X1115530Y1727312D01*
X1115426Y1726852D01*
X1115220Y1726583D01*
X1114858Y1726468D01*
X1114496Y1726545D01*
X1114238Y1726737D01*
X1114083Y1727005D01*
Y1727273D01*
X1114186Y1727542D01*
X1114445Y1727772D01*
G01X1119252Y1711134D02*
X1119559Y1710876D01*
X1119904Y1710721D01*
X1120210D01*
X1120517Y1710876D01*
X1120747Y1711134D01*
X1120862Y1711496D01*
X1120785Y1711858D01*
X1120594Y1712168D01*
X1120249Y1712374D01*
X1119789Y1712478D01*
X1119520Y1712684D01*
X1119405Y1713046D01*
X1119482Y1713408D01*
X1119674Y1713666D01*
X1119942Y1713821D01*
X1120210D01*
X1120479Y1713718D01*
X1120709Y1713459D01*
G01X1122314Y1710721D02*
Y1713821D01*
X1123080D01*
X1123387Y1713666D01*
X1123617Y1713459D01*
X1123809Y1713149D01*
X1123962Y1712788D01*
X1124000Y1712271D01*
X1123962Y1711754D01*
X1123809Y1711393D01*
X1123617Y1711083D01*
X1123387Y1710876D01*
X1123080Y1710721D01*
X1122314D01*
G01X1125299D02*
X1126257Y1713821D01*
X1127215Y1710721D01*
G01X1126870Y1711806D02*
X1125644D01*
G01X1120287Y1701271D02*
X1121054D01*
Y1700341D01*
X1120824Y1700031D01*
X1120555Y1699824D01*
X1120172Y1699721D01*
X1119789Y1699824D01*
X1119520Y1700031D01*
X1119290Y1700341D01*
X1119137Y1700703D01*
X1119060Y1701116D01*
Y1701478D01*
X1119137Y1701788D01*
X1119290Y1702149D01*
X1119520Y1702459D01*
X1119750Y1702666D01*
X1120057Y1702821D01*
X1120325D01*
X1120632Y1702718D01*
X1120862Y1702511D01*
G01X1122275Y1699721D02*
Y1702821D01*
X1124039Y1699721D01*
Y1702821D01*
G01X1125414Y1699721D02*
Y1702821D01*
X1126180D01*
X1126487Y1702666D01*
X1126717Y1702459D01*
X1126909Y1702149D01*
X1127062Y1701788D01*
X1127100Y1701271D01*
X1127062Y1700754D01*
X1126909Y1700393D01*
X1126717Y1700083D01*
X1126487Y1699876D01*
X1126180Y1699721D01*
X1125414D01*
G01X1119252Y1722134D02*
X1119559Y1721876D01*
X1119904Y1721721D01*
X1120210D01*
X1120517Y1721876D01*
X1120747Y1722134D01*
X1120862Y1722496D01*
X1120785Y1722858D01*
X1120594Y1723168D01*
X1120249Y1723374D01*
X1119789Y1723478D01*
X1119520Y1723684D01*
X1119405Y1724046D01*
X1119482Y1724408D01*
X1119674Y1724666D01*
X1119942Y1724821D01*
X1120210D01*
X1120479Y1724718D01*
X1120709Y1724459D01*
G01X1124000Y1724563D02*
X1123770Y1724718D01*
X1123502Y1724821D01*
X1123195D01*
X1122850Y1724666D01*
X1122582Y1724408D01*
X1122390Y1724098D01*
X1122237Y1723581D01*
X1122199Y1723116D01*
X1122275Y1722651D01*
X1122390Y1722341D01*
X1122620Y1722031D01*
X1122889Y1721824D01*
X1123157Y1721721D01*
X1123425D01*
X1123694Y1721824D01*
X1123924Y1721979D01*
X1124115Y1722186D01*
G01X1125490Y1724821D02*
Y1721721D01*
X1127024D01*
G01X1120003Y58945D02*
Y62145D01*
G01X1126203Y58945D02*
X1120003D01*
G01X1126203Y62145D02*
Y58945D01*
G01X1120003Y62145D02*
X1126203D01*
G01X1119903Y54945D02*
Y58145D01*
G01X1126103Y54945D02*
X1119903D01*
G01X1126103Y58145D02*
Y54945D01*
G01X1119903Y58145D02*
X1126103D01*
G01X1120003Y62945D02*
Y66145D01*
G01X1126203Y62945D02*
X1120003D01*
G01X1126203Y66145D02*
Y62945D01*
G01X1120003Y66145D02*
X1126203D01*
G01X1133582Y75683D02*
Y73461D01*
X1133735Y72996D01*
X1134042Y72686D01*
X1134425Y72583D01*
X1134808Y72686D01*
X1135115Y72996D01*
X1135268Y73461D01*
Y75683D01*
G01X1136797Y75166D02*
X1137027Y75476D01*
X1137295Y75631D01*
X1137602Y75683D01*
X1137985Y75580D01*
X1138253Y75321D01*
X1138330Y75011D01*
X1138292Y74701D01*
X1138138Y74443D01*
X1137372Y73926D01*
X1137027Y73565D01*
X1136797Y73048D01*
X1136720Y72583D01*
X1138330D01*
G01X1140548D02*
X1140625Y73255D01*
X1140740Y73823D01*
X1140893Y74340D01*
X1141085Y74908D01*
X1141392Y75683D01*
X1139858D01*
G01X1143725Y72583D02*
Y75683D01*
X1143265Y75063D01*
G01Y72583D02*
X1144185D01*
G01X1131365Y201886D02*
X1131058Y201938D01*
X1130790Y202144D01*
X1130560Y202454D01*
X1130407Y202816D01*
X1130330Y203229D01*
Y203643D01*
X1130407Y204056D01*
X1130560Y204418D01*
X1130790Y204728D01*
X1131058Y204934D01*
X1131365Y204986D01*
X1131672Y204934D01*
X1131940Y204728D01*
X1132170Y204418D01*
X1132323Y204056D01*
X1132400Y203643D01*
Y203229D01*
X1132323Y202816D01*
X1132170Y202454D01*
X1131940Y202144D01*
X1131672Y201938D01*
X1131365Y201886D01*
G01X1131672Y202713D02*
X1132132Y201886D01*
G01X1134465D02*
Y204986D01*
X1134005Y204366D01*
G01Y201886D02*
X1134925D01*
G01X1136837Y204469D02*
X1137067Y204779D01*
X1137335Y204934D01*
X1137642Y204986D01*
X1138025Y204883D01*
X1138293Y204624D01*
X1138370Y204314D01*
X1138332Y204004D01*
X1138178Y203746D01*
X1137412Y203229D01*
X1137067Y202868D01*
X1136837Y202351D01*
X1136760Y201886D01*
X1138370D01*
G01X1140588D02*
X1140665Y202558D01*
X1140780Y203126D01*
X1140933Y203643D01*
X1141125Y204211D01*
X1141432Y204986D01*
X1139898D01*
G01X1125135Y223222D02*
X1124828Y223274D01*
X1124560Y223480D01*
X1124330Y223790D01*
X1124177Y224152D01*
X1124100Y224565D01*
Y224979D01*
X1124177Y225392D01*
X1124330Y225754D01*
X1124560Y226064D01*
X1124828Y226270D01*
X1125135Y226322D01*
X1125442Y226270D01*
X1125710Y226064D01*
X1125940Y225754D01*
X1126093Y225392D01*
X1126170Y224979D01*
Y224565D01*
X1126093Y224152D01*
X1125940Y223790D01*
X1125710Y223480D01*
X1125442Y223274D01*
X1125135Y223222D01*
G01X1125442Y224049D02*
X1125902Y223222D01*
G01X1128235D02*
Y226322D01*
X1127775Y225702D01*
G01Y223222D02*
X1128695D01*
G01X1130607Y225805D02*
X1130837Y226115D01*
X1131105Y226270D01*
X1131412Y226322D01*
X1131795Y226219D01*
X1132063Y225960D01*
X1132140Y225650D01*
X1132102Y225340D01*
X1131948Y225082D01*
X1131182Y224565D01*
X1130837Y224204D01*
X1130607Y223687D01*
X1130530Y223222D01*
X1132140D01*
G01X1133707Y224514D02*
X1133975Y224875D01*
X1134205Y225082D01*
X1134512Y225185D01*
X1134780Y225082D01*
X1134972Y224875D01*
X1135125Y224565D01*
X1135163Y224204D01*
X1135125Y223894D01*
X1134972Y223584D01*
X1134742Y223325D01*
X1134473Y223222D01*
X1134167Y223325D01*
X1133898Y223635D01*
X1133745Y224100D01*
X1133707Y224617D01*
X1133783Y225289D01*
X1133898Y225650D01*
X1134090Y226012D01*
X1134358Y226270D01*
X1134627Y226322D01*
X1134895Y226219D01*
X1135087Y225960D01*
G01X1126865Y361892D02*
Y381578D01*
G01X1123908D02*
X1119665Y377335D01*
G01X1126865Y381578D02*
X1123908D01*
G01X1122267Y697211D02*
X1147857D01*
G01X1122267Y1335007D02*
Y697211D01*
G01X1147857Y732644D02*
X1122267D01*
G01X1147857Y1299574D02*
X1122267D01*
G01X1120945Y1336996D02*
X1121137Y1336686D01*
X1121367Y1336479D01*
X1121635Y1336376D01*
X1121942Y1336479D01*
X1122172Y1336686D01*
X1122402Y1336996D01*
X1122479Y1337409D01*
Y1339476D01*
G01X1123969Y1336996D02*
X1124199Y1336634D01*
X1124505Y1336428D01*
X1124850Y1336376D01*
X1125157Y1336428D01*
X1125464Y1336686D01*
X1125655Y1336996D01*
X1125694Y1337306D01*
X1125617Y1337668D01*
X1125349Y1337926D01*
X1125080Y1338029D01*
X1124735D01*
G01X1125080D02*
X1125310Y1338184D01*
X1125502Y1338443D01*
X1125579Y1338753D01*
X1125502Y1339063D01*
X1125310Y1339321D01*
X1124965Y1339476D01*
X1124620Y1339424D01*
X1124275Y1339218D01*
G01X1147857Y1335007D02*
X1122267D01*
G01X1141927Y1361025D02*
G03I-10827J0D01*
G01D02*
X1120273D01*
G01X1122224Y1374019D02*
Y1393704D01*
G01X1128188Y1374019D02*
X1122224D01*
G01Y1393704D02*
Y1413389D01*
G01X1127110Y1416439D02*
Y1419039D01*
G01X1127903Y1416439D02*
X1127110D01*
G01X1122224Y1413389D02*
X1128138D01*
G01X1127110Y1425650D02*
Y1427348D01*
G01X1124479Y1434899D02*
X1121279D01*
G01X1124479Y1441099D02*
Y1434899D01*
G01X1121279D02*
Y1441099D01*
G01Y1430599D02*
X1124479D01*
G01X1121279Y1424399D02*
Y1430599D01*
G01X1124479Y1424399D02*
X1121279D01*
G01X1124479Y1430599D02*
Y1424399D01*
G01X1120528Y1430674D02*
Y1427474D01*
G01Y1434204D02*
Y1431004D01*
G01X1127110Y1440061D02*
X1128118D01*
G01X1127110Y1438207D02*
Y1440061D01*
G01X1124517Y1449388D02*
X1127717D01*
G01X1124517Y1443188D02*
Y1449388D01*
G01X1127717Y1443188D02*
X1124517D01*
G01X1127717Y1449388D02*
Y1443188D01*
G01X1121279Y1441099D02*
X1124479D01*
G01X1128769Y1446902D02*
Y1450102D01*
G01X1134969Y1446902D02*
X1128769D01*
G01X1134969Y1450102D02*
Y1446902D01*
G01X1128769Y1450102D02*
X1134969D01*
G01X1123658Y1527401D02*
X1123347D01*
Y1547087D01*
X1123658D01*
G01X1133998Y1527401D02*
X1130358D01*
G01Y1547087D02*
X1132030D01*
G01X1139242Y1553701D02*
X1133042D01*
Y1556901D01*
X1139242D01*
Y1553701D01*
G01X1140650Y1596030D02*
X1134450D01*
Y1599230D01*
X1140650D01*
Y1596030D01*
G01Y1600030D02*
X1134450D01*
Y1603230D01*
X1140650D01*
Y1600030D01*
G01X1135520Y1609290D02*
X1130920D01*
G01X1135520Y1614390D02*
Y1604190D01*
X1130920D01*
Y1614390D01*
X1135520D01*
G01X1133740Y1615089D02*
X1133433Y1615141D01*
X1133165Y1615347D01*
X1132935Y1615657D01*
X1132782Y1616019D01*
X1132705Y1616432D01*
Y1616846D01*
X1132782Y1617259D01*
X1132935Y1617621D01*
X1133165Y1617931D01*
X1133433Y1618137D01*
X1133740Y1618189D01*
X1134047Y1618137D01*
X1134315Y1617931D01*
X1134545Y1617621D01*
X1134698Y1617259D01*
X1134775Y1616846D01*
Y1616432D01*
X1134698Y1616019D01*
X1134545Y1615657D01*
X1134315Y1615347D01*
X1134047Y1615141D01*
X1133740Y1615089D01*
G01X1134047Y1615916D02*
X1134507Y1615089D01*
G01X1136840D02*
Y1618189D01*
X1136380Y1617569D01*
G01Y1615089D02*
X1137300D01*
G01X1140400D02*
Y1618189D01*
X1138982Y1615967D01*
X1140898D01*
G01X1142197Y1615554D02*
X1142427Y1615296D01*
X1142695Y1615141D01*
X1143040Y1615089D01*
X1143385Y1615192D01*
X1143653Y1615399D01*
X1143845Y1615761D01*
X1143883Y1616174D01*
X1143807Y1616587D01*
X1143615Y1616846D01*
X1143347Y1617052D01*
X1143078Y1617104D01*
X1142810Y1617052D01*
X1142465Y1616846D01*
X1142580Y1618189D01*
X1143615D01*
G01X1122072Y1622360D02*
Y1616160D01*
G01X1123262Y1616150D02*
Y1622350D01*
G01X1126462D02*
Y1616150D01*
G01D02*
X1123262D01*
G01X1133005Y1627741D02*
X1136352D01*
G01X1143499Y1619079D02*
X1133005D01*
G01D02*
Y1627741D01*
G01X1123262Y1622350D02*
X1126462D01*
G01X1123162Y1623810D02*
Y1630010D01*
G01D02*
X1126362D01*
G01D02*
Y1623810D01*
G01D02*
X1123162D01*
G01X1122032Y1630020D02*
Y1623820D01*
G01X1120484Y1671663D02*
Y1674763D01*
G01X1122094D02*
Y1671663D01*
G01Y1673213D02*
X1120484D01*
G01X1124389Y1671663D02*
Y1674763D01*
X1123929Y1674143D01*
G01Y1671663D02*
X1124849D01*
G01X1126761Y1674246D02*
X1126991Y1674556D01*
X1127259Y1674711D01*
X1127566Y1674763D01*
X1127949Y1674660D01*
X1128217Y1674401D01*
X1128294Y1674091D01*
X1128256Y1673781D01*
X1128102Y1673523D01*
X1127336Y1673006D01*
X1126991Y1672645D01*
X1126761Y1672128D01*
X1126684Y1671663D01*
X1128294D01*
G01X1129937Y1672025D02*
X1130206Y1671766D01*
X1130512Y1671663D01*
X1130819Y1671766D01*
X1131087Y1672076D01*
X1131279Y1672541D01*
X1131356Y1673006D01*
Y1673575D01*
X1131279Y1674040D01*
X1131087Y1674453D01*
X1130857Y1674660D01*
X1130589Y1674763D01*
X1130282Y1674660D01*
X1130052Y1674453D01*
X1129899Y1674143D01*
X1129822Y1673730D01*
X1129899Y1673368D01*
X1130091Y1673006D01*
X1130321Y1672800D01*
X1130589Y1672748D01*
X1130896Y1672851D01*
X1131126Y1673110D01*
X1131356Y1673575D01*
G01X1129225Y1729250D02*
Y1732350D01*
G01X1130835D02*
Y1729250D01*
G01Y1730800D02*
X1129225D01*
G01X1132478Y1729612D02*
X1132747Y1729353D01*
X1133053Y1729250D01*
X1133360Y1729353D01*
X1133628Y1729663D01*
X1133820Y1730128D01*
X1133897Y1730593D01*
Y1731162D01*
X1133820Y1731627D01*
X1133628Y1732040D01*
X1133398Y1732247D01*
X1133130Y1732350D01*
X1132823Y1732247D01*
X1132593Y1732040D01*
X1132440Y1731730D01*
X1132363Y1731317D01*
X1132440Y1730955D01*
X1132632Y1730593D01*
X1132862Y1730387D01*
X1133130Y1730335D01*
X1133437Y1730438D01*
X1133667Y1730697D01*
X1133897Y1731162D01*
G01X1136230Y1729250D02*
Y1732350D01*
X1135770Y1731730D01*
G01Y1729250D02*
X1136690D01*
G01X1135371Y50583D02*
X1162519D01*
G01X1135371Y70269D02*
Y50583D01*
G01X1154788Y70269D02*
X1148945Y64426D01*
G01X1143102Y70269D02*
X1135371D01*
G01X1148945Y64426D02*
X1143102Y70269D01*
G01X1147437Y75279D02*
X1153637D01*
G01X1147437Y72079D02*
Y75279D01*
G01X1153637Y72079D02*
X1147437D01*
G01X1138625Y93549D02*
X1138778Y93704D01*
X1138893Y93963D01*
X1138970Y94324D01*
X1138893Y94634D01*
X1138740Y94841D01*
X1138471Y94996D01*
X1137436D01*
Y91896D01*
X1138701D01*
X1138970Y92103D01*
X1139123Y92413D01*
X1139200Y92774D01*
X1139123Y93136D01*
X1138893Y93446D01*
X1138625Y93549D01*
X1137436D01*
G01X1142108Y91896D02*
Y93963D01*
G01Y93601D02*
X1141955Y93808D01*
X1141725Y93911D01*
X1141456Y93963D01*
X1141188Y93859D01*
X1140958Y93653D01*
X1140805Y93343D01*
X1140728Y92929D01*
X1140805Y92516D01*
X1140958Y92206D01*
X1141188Y91999D01*
X1141456Y91896D01*
X1141725Y91948D01*
X1141955Y92103D01*
X1142108Y92309D01*
G01X1144518Y94996D02*
Y91896D01*
G01X1143981Y93963D02*
X1145055D01*
G01X1147618Y94996D02*
Y91896D01*
G01X1147081Y93963D02*
X1148155D01*
G01X1150143Y93291D02*
X1151370D01*
X1151255Y93653D01*
X1151063Y93859D01*
X1150795Y93963D01*
X1150526Y93911D01*
X1150296Y93756D01*
X1150143Y93394D01*
X1150066Y93084D01*
Y92774D01*
X1150143Y92464D01*
X1150335Y92154D01*
X1150565Y91948D01*
X1150833Y91896D01*
X1151101Y91999D01*
X1151370Y92309D01*
G01X1153281Y91896D02*
Y93963D01*
G01Y93549D02*
X1153473Y93756D01*
X1153665Y93911D01*
X1153933Y93963D01*
X1154125Y93911D01*
X1154355Y93756D01*
G01X1156113Y90966D02*
X1156343Y90863D01*
X1156650Y90966D01*
X1156841Y91173D01*
X1156995Y91431D01*
X1157225Y92258D01*
X1157723Y93963D01*
G01X1156496D02*
X1157225Y92258D01*
G01X1149537Y118512D02*
X1161339D01*
G01X1161024Y118905D02*
X1149262D01*
G01X1161339Y149220D02*
X1149537D01*
G01X1149262Y148827D02*
X1161024D01*
G01X1154320Y181762D02*
X1151120D01*
G01D02*
Y187962D01*
G01X1160154Y195900D02*
X1151492D01*
G01Y199247D02*
X1153692Y201147D01*
G01X1151492Y195900D02*
Y199247D01*
G01X1151120Y187962D02*
X1154320D01*
G01X1151492Y206394D02*
X1160154D01*
G01X1151492Y203047D02*
Y206394D01*
G01X1153692Y201147D02*
X1151492Y203047D01*
G01X1147270Y209631D02*
Y212831D01*
G01X1153470Y209631D02*
X1147270D01*
G01Y212831D02*
X1153470D01*
G01X1148932Y231664D02*
X1157594D01*
G01X1148932Y221170D02*
Y231664D01*
G01X1157594Y221170D02*
X1148932D01*
G01X1148980Y361631D02*
Y364831D01*
G01X1155180Y361631D02*
X1148980D01*
G01X1135790Y375411D02*
Y378611D01*
G01X1141990Y375411D02*
X1135790D01*
G01X1141990Y378611D02*
Y375411D01*
G01X1135790Y378611D02*
X1141990D01*
G01X1148910Y371631D02*
Y374831D01*
G01X1155110Y371631D02*
X1148910D01*
G01Y374831D02*
X1155110D01*
G01X1148910Y369641D02*
X1155110D01*
G01X1148910Y366441D02*
Y369641D01*
G01X1155110Y366441D02*
X1148910D01*
G01X1148980Y364831D02*
X1155180D01*
G01X1147857Y697211D02*
Y1335007D01*
G01X1150645Y1336996D02*
X1150837Y1336686D01*
X1151067Y1336479D01*
X1151335Y1336376D01*
X1151642Y1336479D01*
X1151872Y1336686D01*
X1152102Y1336996D01*
X1152179Y1337409D01*
Y1339476D01*
G01X1154972Y1336376D02*
Y1339476D01*
X1153554Y1337254D01*
X1155470D01*
G01X1166327Y1361025D02*
G03I-10827J0D01*
G01D02*
X1144673D01*
G01X1151752Y1374019D02*
X1145838D01*
G01X1146796Y1416439D02*
X1146003D01*
G01X1146796Y1419039D02*
Y1416439D01*
G01X1145838Y1413389D02*
X1151752D01*
G01X1149413Y1431619D02*
X1152613D01*
G01X1149413Y1425419D02*
Y1431619D01*
G01X1152613Y1425419D02*
X1149413D01*
G01X1147854Y1449244D02*
X1159854D01*
G01X1147854Y1443244D02*
Y1449244D01*
G01X1159854Y1443244D02*
X1147854D01*
G01X1146796Y1440061D02*
Y1437870D01*
G01X1146063Y1440061D02*
X1146796D01*
G01X1142384Y1449474D02*
X1145584D01*
G01X1142384Y1443274D02*
Y1449474D01*
G01X1145584Y1443274D02*
X1142384D01*
G01X1145584Y1449474D02*
Y1443274D01*
G01X1141542D02*
X1138342D01*
G01X1141542Y1449474D02*
Y1443274D01*
G01X1138342Y1449474D02*
X1141542D01*
G01X1138342Y1443274D02*
Y1449474D01*
G01X1136318Y1457564D02*
Y1460972D01*
G01X1154034Y1457564D02*
X1136318D01*
G01X1139779Y1482409D02*
Y1485509D01*
X1140699D01*
X1141006Y1485354D01*
X1141236Y1484992D01*
X1141313Y1484579D01*
X1141236Y1484166D01*
X1141044Y1483856D01*
X1140699Y1483701D01*
X1139779D01*
G01X1142879Y1485509D02*
Y1482409D01*
X1144413D01*
G01X1147206D02*
Y1485509D01*
X1145788Y1483287D01*
X1147704D01*
G01X1150306Y1482409D02*
Y1485509D01*
X1148888Y1483287D01*
X1150804D01*
G01X1136318Y1475280D02*
X1154034D01*
G01X1136318Y1471872D02*
Y1475280D01*
G01X1140433Y1477713D02*
Y1480913D01*
G01X1146633Y1477713D02*
X1140433D01*
G01X1146633Y1480913D02*
Y1477713D01*
G01X1140433Y1480913D02*
X1146633D01*
G01X1148885Y1615452D02*
X1151536D01*
X1154587Y1611452D01*
X1157638Y1615452D01*
G01X1160289D02*
Y1603248D01*
X1148885D01*
Y1615452D01*
G01X1136352Y1627741D02*
X1138252Y1625541D01*
G01D02*
X1140152Y1627741D01*
G01D02*
X1143499D01*
G01D02*
Y1619079D01*
G01X1147870Y1620560D02*
X1154070D01*
Y1617360D01*
X1147870D01*
Y1620560D01*
G01X1153782Y1624680D02*
X1147582D01*
G01D02*
Y1627880D01*
G01D02*
X1153782D01*
G01X1162519Y50583D02*
Y70269D01*
G01X1166771Y62911D02*
X1172971D01*
G01X1166771Y59711D02*
Y62911D01*
G01X1172971Y59711D02*
X1166771D01*
G01Y67411D02*
X1172971D01*
G01X1166771Y64211D02*
Y67411D01*
G01X1172971Y64211D02*
X1166771D01*
G01X1166791Y58711D02*
X1172991D01*
G01X1166791Y55511D02*
Y58711D01*
G01X1172991Y55511D02*
X1166791D01*
G01X1162519Y70269D02*
X1154788D01*
G01X1153637Y75279D02*
Y72079D01*
G01X1161339Y118512D02*
Y149220D01*
G01X1161024Y148827D02*
Y118905D01*
G01X1165653Y138980D02*
X1165806Y139135D01*
X1165921Y139394D01*
X1165998Y139755D01*
X1165921Y140065D01*
X1165768Y140272D01*
X1165499Y140427D01*
X1164464D01*
Y137327D01*
X1165729D01*
X1165998Y137534D01*
X1166151Y137844D01*
X1166228Y138205D01*
X1166151Y138567D01*
X1165921Y138877D01*
X1165653Y138980D01*
X1164464D01*
G01X1168446Y140427D02*
Y137327D01*
G01X1167564Y140427D02*
X1169328D01*
G01X1171546Y137327D02*
Y140427D01*
X1171086Y139807D01*
G01Y137327D02*
X1172006D01*
G01X1154320Y187962D02*
Y181762D01*
G01X1158320D02*
X1155120D01*
G01X1158320Y187962D02*
Y181762D01*
G01X1155120D02*
Y187962D01*
G01X1159120Y181762D02*
Y187962D01*
G01X1162320Y181762D02*
X1159120D01*
G01X1162320Y187962D02*
Y181762D01*
G01X1160154Y206394D02*
Y195900D01*
G01X1155120Y187962D02*
X1158320D01*
G01X1159120D02*
X1162320D01*
G01X1153470Y212831D02*
Y209631D01*
G01X1162120Y212970D02*
Y209770D01*
G01X1155920Y212970D02*
X1162120D01*
G01X1155920Y209770D02*
Y212970D01*
G01X1162120Y209770D02*
X1155920D01*
G01X1157594Y224517D02*
Y221170D01*
G01X1155394Y226417D02*
X1157594Y224517D01*
G01Y228317D02*
X1155394Y226417D01*
G01X1157594Y231664D02*
Y228317D01*
G01X1155180Y364831D02*
Y361631D01*
G01X1155110Y374831D02*
Y371631D01*
G01Y369641D02*
Y366441D01*
G01X1151967Y697211D02*
X1177557D01*
G01X1151967Y1335007D02*
Y697211D01*
G01X1177557Y732644D02*
X1151967D01*
G01X1177557Y1299574D02*
X1151967D01*
G01X1177557Y1335007D02*
X1151967D01*
G01X1160324Y1374019D02*
Y1393704D01*
G01X1166288Y1374019D02*
X1160324D01*
G01X1151752Y1413389D02*
Y1374019D01*
G01X1160324Y1393704D02*
Y1413389D01*
G01X1165253Y1416439D02*
Y1419039D01*
G01X1166046Y1416439D02*
X1165253D01*
G01X1160324Y1413389D02*
X1166238D01*
G01X1165253Y1425650D02*
Y1427348D01*
G01X1162622Y1434899D02*
X1159422D01*
G01X1162622Y1441099D02*
Y1434899D01*
G01X1159422D02*
Y1441099D01*
G01X1153517Y1431619D02*
X1156717D01*
G01X1153517Y1425419D02*
Y1431619D01*
G01X1156717Y1425419D02*
X1153517D01*
G01X1156717Y1431619D02*
Y1425419D01*
G01X1159422Y1430599D02*
X1162622D01*
G01X1159422Y1424399D02*
Y1430599D01*
G01X1162622Y1424399D02*
X1159422D01*
G01X1162622Y1430599D02*
Y1424399D01*
G01X1152613Y1431619D02*
Y1425419D01*
G01X1159854Y1449244D02*
Y1443244D01*
G01X1165253Y1440061D02*
X1166261D01*
G01X1165253Y1438207D02*
Y1440061D01*
G01X1162660Y1449388D02*
X1165860D01*
G01X1162660Y1443188D02*
Y1449388D01*
G01X1165860Y1443188D02*
X1162660D01*
G01X1165860Y1449388D02*
Y1443188D01*
G01X1159422Y1441099D02*
X1162622D01*
G01X1166912Y1446902D02*
Y1450102D01*
G01X1173112Y1446902D02*
X1166912D01*
G01Y1450102D02*
X1173112D01*
G01X1154034Y1460972D02*
Y1457564D01*
G01X1186934Y1466363D02*
G03I-13386J0D01*
G01X1154034Y1475280D02*
Y1471872D01*
G01X1153434Y1600837D02*
Y1598615D01*
X1153587Y1598150D01*
X1153894Y1597840D01*
X1154277Y1597737D01*
X1154660Y1597840D01*
X1154967Y1598150D01*
X1155120Y1598615D01*
Y1600837D01*
G01X1156534Y1598357D02*
X1156764Y1597995D01*
X1157070Y1597789D01*
X1157415Y1597737D01*
X1157722Y1597789D01*
X1158029Y1598047D01*
X1158220Y1598357D01*
X1158259Y1598667D01*
X1158182Y1599029D01*
X1157914Y1599287D01*
X1157645Y1599390D01*
X1157300D01*
G01X1157645D02*
X1157875Y1599545D01*
X1158067Y1599804D01*
X1158144Y1600114D01*
X1158067Y1600424D01*
X1157875Y1600682D01*
X1157530Y1600837D01*
X1157185Y1600785D01*
X1156840Y1600579D01*
G01X1160937Y1597737D02*
Y1600837D01*
X1159519Y1598615D01*
X1161435D01*
G01X1162734Y1598202D02*
X1162964Y1597944D01*
X1163232Y1597789D01*
X1163577Y1597737D01*
X1163922Y1597840D01*
X1164190Y1598047D01*
X1164382Y1598409D01*
X1164420Y1598822D01*
X1164344Y1599235D01*
X1164152Y1599494D01*
X1163884Y1599700D01*
X1163615Y1599752D01*
X1163347Y1599700D01*
X1163002Y1599494D01*
X1163117Y1600837D01*
X1164152D01*
G01X1153782Y1627880D02*
Y1624680D01*
G01X1154561Y1623940D02*
X1160761D01*
Y1620740D01*
X1154561D01*
Y1623940D01*
G01Y1627820D02*
X1160761D01*
Y1624620D01*
X1154561D01*
Y1627820D01*
G01Y1635480D02*
X1160761D01*
Y1632280D01*
X1154561D01*
Y1635480D01*
G01Y1631690D02*
X1160761D01*
Y1628490D01*
X1154561D01*
Y1631690D01*
G01X1167150Y1637118D02*
Y1634896D01*
X1167303Y1634431D01*
X1167610Y1634121D01*
X1167993Y1634018D01*
X1168376Y1634121D01*
X1168683Y1634431D01*
X1168836Y1634896D01*
Y1637118D01*
G01X1170250Y1634638D02*
X1170480Y1634276D01*
X1170786Y1634070D01*
X1171131Y1634018D01*
X1171438Y1634070D01*
X1171745Y1634328D01*
X1171936Y1634638D01*
X1171975Y1634948D01*
X1171898Y1635310D01*
X1171630Y1635568D01*
X1171361Y1635671D01*
X1171016D01*
G01X1171361D02*
X1171591Y1635826D01*
X1171783Y1636085D01*
X1171860Y1636395D01*
X1171783Y1636705D01*
X1171591Y1636963D01*
X1171246Y1637118D01*
X1170901Y1637066D01*
X1170556Y1636860D01*
G01X1173350Y1634638D02*
X1173580Y1634276D01*
X1173886Y1634070D01*
X1174231Y1634018D01*
X1174538Y1634070D01*
X1174845Y1634328D01*
X1175036Y1634638D01*
X1175075Y1634948D01*
X1174998Y1635310D01*
X1174730Y1635568D01*
X1174461Y1635671D01*
X1174116D01*
G01X1174461D02*
X1174691Y1635826D01*
X1174883Y1636085D01*
X1174960Y1636395D01*
X1174883Y1636705D01*
X1174691Y1636963D01*
X1174346Y1637118D01*
X1174001Y1637066D01*
X1173656Y1636860D01*
G01X1177293Y1634018D02*
Y1637118D01*
X1176833Y1636498D01*
G01Y1634018D02*
X1177753D01*
G01X1166430Y1652815D02*
Y1646615D01*
G01D02*
X1163230D01*
G01D02*
Y1652815D01*
G01X1159325Y1644200D02*
X1165525D01*
Y1641000D01*
X1159325D01*
Y1644200D01*
G01X1161530Y1652815D02*
Y1646615D01*
G01D02*
X1158330D01*
G01D02*
Y1652815D01*
G01X1165561Y1674562D02*
Y1664068D01*
G01D02*
X1156899D01*
G01D02*
Y1667415D01*
G01X1163230Y1652815D02*
X1166430D01*
G01X1158330D02*
X1161530D01*
G01X1163230Y1662215D02*
X1166430D01*
G01D02*
Y1656015D01*
G01D02*
X1163230D01*
G01D02*
Y1662215D01*
G01X1158330Y1656015D02*
Y1662215D01*
G01D02*
X1161530D01*
G01D02*
Y1656015D01*
G01D02*
X1158330D01*
G01X1167899Y1667415D02*
X1170099Y1669315D01*
G01D02*
X1167899Y1671215D01*
G01X1156899Y1667415D02*
X1159099Y1669315D01*
G01D02*
X1156899Y1671215D01*
G01Y1674562D02*
X1165561D01*
G01X1156899Y1671215D02*
Y1674562D01*
G01X1165176Y1682149D02*
Y1675949D01*
G01D02*
X1161976D01*
G01D02*
Y1682149D01*
G01D02*
X1165176D01*
G01X1180971Y59711D02*
Y62911D01*
G01X1187171Y59711D02*
X1180971D01*
G01Y62911D02*
X1187171D01*
G01X1180871Y64211D02*
Y67411D01*
G01X1187071Y64211D02*
X1180871D01*
G01Y67411D02*
X1187071D01*
G01X1172971Y62911D02*
Y59711D01*
G01Y67411D02*
Y64211D01*
G01X1180891Y55511D02*
Y58711D01*
G01X1187091Y55511D02*
X1180891D01*
G01Y58711D02*
X1187091D01*
G01X1172991D02*
Y55511D01*
G01X1177229Y120776D02*
Y118554D01*
X1177382Y118089D01*
X1177689Y117779D01*
X1178072Y117676D01*
X1178455Y117779D01*
X1178762Y118089D01*
X1178915Y118554D01*
Y120776D01*
G01X1180444Y118968D02*
X1180712Y119329D01*
X1180942Y119536D01*
X1181249Y119639D01*
X1181517Y119536D01*
X1181709Y119329D01*
X1181862Y119019D01*
X1181900Y118658D01*
X1181862Y118348D01*
X1181709Y118038D01*
X1181479Y117779D01*
X1181210Y117676D01*
X1180904Y117779D01*
X1180635Y118089D01*
X1180482Y118554D01*
X1180444Y119071D01*
X1180520Y119743D01*
X1180635Y120104D01*
X1180827Y120466D01*
X1181095Y120724D01*
X1181364Y120776D01*
X1181632Y120673D01*
X1181824Y120414D01*
G01X1183544Y120259D02*
X1183774Y120569D01*
X1184042Y120724D01*
X1184349Y120776D01*
X1184732Y120673D01*
X1185000Y120414D01*
X1185077Y120104D01*
X1185039Y119794D01*
X1184885Y119536D01*
X1184119Y119019D01*
X1183774Y118658D01*
X1183544Y118141D01*
X1183467Y117676D01*
X1185077D01*
G01X1180700Y110000D02*
Y113200D01*
G01X1186900Y110000D02*
X1180700D01*
G01Y113200D02*
X1186900D01*
G01X1174974Y168531D02*
X1171774D01*
G01X1174974Y174731D02*
Y168531D01*
G01X1171774D02*
Y174731D01*
G01X1179876Y168406D02*
X1183076D01*
G01X1179876Y162206D02*
Y168406D01*
G01X1183076Y162206D02*
X1179876D01*
G01X1183076Y168406D02*
Y162206D01*
G01X1171774Y174731D02*
X1174974D01*
G01X1174145Y184574D02*
Y187774D01*
G01X1180345Y184574D02*
X1174145D01*
G01X1180345Y187774D02*
Y184574D01*
G01X1174145Y200574D02*
Y203774D01*
G01X1180345Y200574D02*
X1174145D01*
G01X1180345Y203774D02*
Y200574D01*
G01X1174145Y196574D02*
Y199774D01*
G01X1180345Y196574D02*
X1174145D01*
G01X1180345Y199774D02*
Y196574D01*
G01X1174145Y199774D02*
X1180345D01*
G01Y195774D02*
Y192574D01*
G01X1174145Y195774D02*
X1180345D01*
G01X1174145Y192574D02*
Y195774D01*
G01X1180345Y192574D02*
X1174145D01*
G01X1180345Y191774D02*
Y188574D01*
G01X1174145Y191774D02*
X1180345D01*
G01X1174145Y188574D02*
Y191774D01*
G01X1180345Y188574D02*
X1174145D01*
G01Y187774D02*
X1180345D01*
G01X1174145Y203774D02*
X1180345D01*
G01X1174145Y216574D02*
Y219774D01*
G01X1180345Y216574D02*
X1174145D01*
G01X1180345Y219774D02*
Y216574D01*
G01Y207774D02*
Y204574D01*
G01X1174145Y207774D02*
X1180345D01*
G01X1174145Y204574D02*
Y207774D01*
G01X1180345Y204574D02*
X1174145D01*
G01X1180345Y211774D02*
Y208574D01*
G01X1174145Y211774D02*
X1180345D01*
G01X1174145Y208574D02*
Y211774D01*
G01X1180345Y208574D02*
X1174145D01*
G01Y212574D02*
Y215774D01*
G01X1180345Y212574D02*
X1174145D01*
G01X1180345Y215774D02*
Y212574D01*
G01X1174145Y215774D02*
X1180345D01*
G01Y223774D02*
Y220574D01*
G01X1174145Y223774D02*
X1180345D01*
G01X1174145Y220574D02*
Y223774D01*
G01X1180345Y220574D02*
X1174145D01*
G01Y219774D02*
X1180345D01*
G01X1181667Y697211D02*
X1207257D01*
G01X1181667Y1335007D02*
Y697211D01*
G01X1177557D02*
Y1335007D01*
G01X1207257Y732644D02*
X1181667D01*
G01X1207257Y1299574D02*
X1181667D01*
G01X1180345Y1336996D02*
X1180537Y1336686D01*
X1180767Y1336479D01*
X1181035Y1336376D01*
X1181342Y1336479D01*
X1181572Y1336686D01*
X1181802Y1336996D01*
X1181879Y1337409D01*
Y1339476D01*
G01X1184212Y1336376D02*
Y1339476D01*
X1183752Y1338856D01*
G01Y1336376D02*
X1184672D01*
G01X1207257Y1335007D02*
X1181667D01*
G01X1190727Y1361025D02*
G03I-10827J0D01*
G01D02*
X1169073D01*
G01X1189852Y1374019D02*
X1183938D01*
G01Y1413389D02*
X1189852D01*
G01X1180527Y1449474D02*
X1183727D01*
G01X1180527Y1443274D02*
Y1449474D01*
G01X1183727Y1443274D02*
X1180527D01*
G01X1183727Y1449474D02*
Y1443274D01*
G01X1179685D02*
X1176485D01*
G01X1179685Y1449474D02*
Y1443274D01*
G01X1176485Y1449474D02*
X1179685D01*
G01X1176485Y1443274D02*
Y1449474D01*
G01X1173112Y1450102D02*
Y1446902D01*
G01X1173548Y1452977D02*
Y1479749D01*
G01X1183272Y1547087D02*
X1183583D01*
Y1527401D01*
G01X1176572D02*
X1172932D01*
G01X1183583D02*
X1183272D01*
G01X1174900Y1547087D02*
X1176572D01*
G01X1170780Y1602700D02*
X1176980D01*
Y1599500D01*
X1170780D01*
Y1602700D01*
G01Y1610700D02*
X1176980D01*
Y1607500D01*
X1170780D01*
Y1610700D01*
G01Y1606700D02*
X1176980D01*
Y1603500D01*
X1170780D01*
Y1606700D01*
G01X1170660Y1614560D02*
X1176860D01*
Y1611360D01*
X1170660D01*
Y1614560D01*
G01X1177471D02*
X1183671D01*
Y1611360D01*
X1177471D01*
Y1614560D01*
G01X1180587Y1621267D02*
Y1619314D01*
X1178634D01*
G01X1170728D02*
X1168775D01*
Y1621267D01*
G01Y1629173D02*
Y1631126D01*
G01X1178634D02*
X1180587D01*
Y1629173D01*
G01X1168775Y1631126D02*
X1170728D01*
G01X1186680Y1623589D02*
Y1617389D01*
X1183480D01*
Y1623589D01*
X1186680D01*
G01X1183430Y1625861D02*
Y1632061D01*
X1186630D01*
Y1625861D01*
X1183430D01*
G01X1177430Y1652815D02*
Y1646615D01*
G01D02*
X1174230D01*
G01D02*
Y1652815D01*
G01X1181325Y1644200D02*
X1187525D01*
Y1641000D01*
X1181325D01*
Y1644200D01*
G01X1170325D02*
X1176525D01*
Y1641000D01*
X1170325D01*
Y1644200D01*
G01X1183530Y1652815D02*
Y1646615D01*
G01D02*
X1180330D01*
G01D02*
Y1652815D01*
G01X1172530D02*
Y1646615D01*
G01D02*
X1169330D01*
G01D02*
Y1652815D01*
G01X1187561Y1664068D02*
X1178899D01*
G01D02*
Y1667415D01*
G01X1176561Y1674562D02*
Y1664068D01*
G01D02*
X1167899D01*
G01D02*
Y1667415D01*
G01X1174230Y1652815D02*
X1177430D01*
G01X1180330D02*
X1183530D01*
G01X1169330D02*
X1172530D01*
G01X1180330Y1662215D02*
X1183530D01*
G01D02*
Y1656015D01*
G01D02*
X1180330D01*
G01D02*
Y1662215D01*
G01X1174230Y1656015D02*
Y1662215D01*
G01D02*
X1177430D01*
G01D02*
Y1656015D01*
G01D02*
X1174230D01*
G01X1169330Y1662215D02*
X1172530D01*
G01D02*
Y1656015D01*
G01D02*
X1169330D01*
G01D02*
Y1662215D01*
G01X1178899Y1674562D02*
X1187561D01*
G01X1178899Y1667415D02*
X1181099Y1669315D01*
G01D02*
X1178899Y1671215D01*
G01D02*
Y1674562D01*
G01X1167899Y1671215D02*
Y1674562D01*
G01D02*
X1176561D01*
G01X1187176Y1675949D02*
X1183976D01*
G01D02*
Y1682149D01*
G01X1176176D02*
Y1675949D01*
G01D02*
X1172976D01*
G01D02*
Y1682149D01*
G01X1184843Y1687205D02*
X1184791Y1686898D01*
X1184585Y1686630D01*
X1184275Y1686400D01*
X1183913Y1686247D01*
X1183500Y1686170D01*
X1183086D01*
X1182673Y1686247D01*
X1182311Y1686400D01*
X1182001Y1686630D01*
X1181795Y1686898D01*
X1181743Y1687205D01*
X1181795Y1687512D01*
X1182001Y1687780D01*
X1182311Y1688010D01*
X1182673Y1688163D01*
X1183086Y1688240D01*
X1183500D01*
X1183913Y1688163D01*
X1184275Y1688010D01*
X1184585Y1687780D01*
X1184791Y1687512D01*
X1184843Y1687205D01*
G01X1184016Y1687512D02*
X1184843Y1687972D01*
G01Y1690305D02*
X1181743D01*
X1182363Y1689845D01*
G01X1184843D02*
Y1690765D01*
G01X1184223Y1692562D02*
X1184585Y1692792D01*
X1184791Y1693098D01*
X1184843Y1693443D01*
X1184791Y1693750D01*
X1184533Y1694057D01*
X1184223Y1694248D01*
X1183913Y1694287D01*
X1183551Y1694210D01*
X1183293Y1693942D01*
X1183190Y1693673D01*
Y1693328D01*
G01Y1693673D02*
X1183035Y1693903D01*
X1182776Y1694095D01*
X1182466Y1694172D01*
X1182156Y1694095D01*
X1181898Y1693903D01*
X1181743Y1693558D01*
X1181795Y1693213D01*
X1182001Y1692868D01*
G01X1181743Y1696505D02*
X1181846Y1696198D01*
X1182105Y1695968D01*
X1182415Y1695815D01*
X1182828Y1695700D01*
X1183293Y1695662D01*
X1183758Y1695700D01*
X1184171Y1695815D01*
X1184481Y1695968D01*
X1184740Y1696198D01*
X1184843Y1696505D01*
X1184740Y1696812D01*
X1184481Y1697042D01*
X1184171Y1697195D01*
X1183758Y1697310D01*
X1183293Y1697348D01*
X1182828Y1697310D01*
X1182415Y1697195D01*
X1182105Y1697042D01*
X1181846Y1696812D01*
X1181743Y1696505D01*
G01X1183976Y1682149D02*
X1187176D01*
G01X1172976D02*
X1176176D01*
G01X1187171Y62911D02*
Y59711D01*
G01X1187071Y67411D02*
Y64211D01*
G01X1187091Y58711D02*
Y55511D01*
G01X1199900Y87400D02*
X1193700D01*
Y90600D01*
X1199900D01*
Y87400D01*
G01Y95800D02*
X1193700D01*
Y99000D01*
X1199900D01*
Y95800D01*
G01Y100000D02*
X1193700D01*
Y103200D01*
X1199900D01*
Y100000D01*
G01X1193700Y94800D02*
X1199900D01*
Y91600D01*
X1193700D01*
Y94800D01*
G01X1188807Y107927D02*
X1200619D01*
G01X1188807Y120401D02*
Y107927D01*
G01X1186900Y113200D02*
Y110000D01*
G01X1200619Y120401D02*
X1188807D01*
G01X1193678Y134449D02*
Y140649D01*
G01X1196878Y134449D02*
X1193678D01*
G01X1196878Y140649D02*
Y134449D01*
G01X1191876Y126204D02*
Y129404D01*
G01X1198076Y126204D02*
X1191876D01*
G01X1198076Y129404D02*
Y126204D01*
G01X1191876Y129404D02*
X1198076D01*
G01X1192806Y134449D02*
X1189606D01*
G01X1192806Y140649D02*
Y134449D01*
G01X1189606D02*
Y140649D01*
G01X1193678D02*
X1196878D01*
G01X1189606D02*
X1192806D01*
G01X1198000Y185362D02*
Y179362D01*
G01D02*
X1186000D01*
G01D02*
Y185362D01*
G01D02*
X1198000D01*
G01X1197500Y195362D02*
X1185500D01*
G01X1197500Y201362D02*
Y195362D01*
G01X1185500D02*
Y201362D01*
G01D02*
X1197500D01*
G01X1200088Y214248D02*
Y211048D01*
G01X1193888Y214248D02*
X1200088D01*
G01X1193888Y211048D02*
Y214248D01*
G01X1200088Y211048D02*
X1193888D01*
G01X1195875Y234992D02*
Y238192D01*
G01X1202075Y234992D02*
X1195875D01*
G01Y238192D02*
X1202075D01*
G01X1195875Y242272D02*
X1202075D01*
G01X1195875Y239072D02*
Y242272D01*
G01X1202075Y239072D02*
X1195875D01*
G01Y246292D02*
X1202075D01*
G01X1195875Y243092D02*
Y246292D01*
G01X1202075Y243092D02*
X1195875D01*
G01X1198595Y1361236D02*
Y1358036D01*
G01X1192395Y1361236D02*
X1198595D01*
G01X1192395Y1358036D02*
Y1361236D01*
G01X1198595Y1358036D02*
X1192395D01*
G01X1198595Y1364746D02*
Y1361546D01*
G01X1192395Y1364746D02*
X1198595D01*
G01X1192395Y1361546D02*
Y1364746D01*
G01X1198595Y1361546D02*
X1192395D01*
G01X1189852Y1413389D02*
Y1374019D01*
G01X1195383Y1400362D02*
Y1403462D01*
X1196303D01*
X1196610Y1403307D01*
X1196840Y1402945D01*
X1196917Y1402532D01*
X1196840Y1402119D01*
X1196648Y1401809D01*
X1196303Y1401654D01*
X1195383D01*
G01X1198483Y1403462D02*
Y1400362D01*
X1200017D01*
G01X1201507Y1400982D02*
X1201737Y1400620D01*
X1202043Y1400414D01*
X1202388Y1400362D01*
X1202695Y1400414D01*
X1203002Y1400672D01*
X1203193Y1400982D01*
X1203232Y1401292D01*
X1203155Y1401654D01*
X1202887Y1401912D01*
X1202618Y1402015D01*
X1202273D01*
G01X1202618D02*
X1202848Y1402170D01*
X1203040Y1402429D01*
X1203117Y1402739D01*
X1203040Y1403049D01*
X1202848Y1403307D01*
X1202503Y1403462D01*
X1202158Y1403410D01*
X1201813Y1403204D01*
G01X1205910Y1400362D02*
Y1403462D01*
X1204492Y1401240D01*
X1206408D01*
G01X1184939Y1416439D02*
X1184146D01*
G01X1184939Y1419039D02*
Y1416439D01*
G01X1191082Y1433732D02*
Y1439732D01*
G01X1203082Y1433732D02*
X1191082D01*
G01X1191660Y1431619D02*
X1194860D01*
G01X1191660Y1425419D02*
Y1431619D01*
G01X1194860Y1425419D02*
X1191660D01*
G01X1194860Y1431619D02*
Y1425419D01*
G01X1187556Y1431619D02*
X1190756D01*
G01X1187556Y1425419D02*
Y1431619D01*
G01X1190756Y1425419D02*
X1187556D01*
G01X1190756Y1431619D02*
Y1425419D01*
G01X1189052Y1450022D02*
Y1456022D01*
G01X1201052Y1450022D02*
X1189052D01*
G01X1189092Y1449212D02*
X1201092D01*
G01X1189092Y1443212D02*
Y1449212D01*
G01X1201092Y1443212D02*
X1189092D01*
G01X1191082Y1439732D02*
X1203082D01*
G01X1184939Y1440061D02*
Y1437870D01*
G01X1184206Y1440061D02*
X1184939D01*
G01X1189052Y1456022D02*
X1201052D01*
G01X1188415Y1529469D02*
X1185315D01*
Y1530389D01*
X1185470Y1530696D01*
X1185832Y1530926D01*
X1186245Y1531003D01*
X1186658Y1530926D01*
X1186968Y1530734D01*
X1187123Y1530389D01*
Y1529469D01*
G01X1187795Y1532569D02*
X1188105Y1532761D01*
X1188312Y1532991D01*
X1188415Y1533259D01*
X1188312Y1533566D01*
X1188105Y1533796D01*
X1187795Y1534026D01*
X1187382Y1534103D01*
X1185315D01*
G01X1188415Y1536896D02*
X1185315D01*
X1187537Y1535478D01*
Y1537394D01*
G01X1185832Y1538808D02*
X1185522Y1539038D01*
X1185367Y1539306D01*
X1185315Y1539613D01*
X1185418Y1539996D01*
X1185677Y1540264D01*
X1185987Y1540341D01*
X1186297Y1540303D01*
X1186555Y1540149D01*
X1187072Y1539383D01*
X1187433Y1539038D01*
X1187950Y1538808D01*
X1188415Y1538731D01*
Y1540341D01*
G01X1199000Y1653125D02*
Y1646925D01*
G01D02*
X1195800D01*
G01D02*
Y1653125D01*
G01X1188430Y1652815D02*
Y1646615D01*
G01D02*
X1185230D01*
G01D02*
Y1652815D01*
G01X1191895Y1644510D02*
X1198095D01*
Y1641310D01*
X1191895D01*
Y1644510D01*
G01X1194100Y1653125D02*
Y1646925D01*
G01D02*
X1190900D01*
G01D02*
Y1653125D01*
G01X1198231Y1674872D02*
Y1664378D01*
G01D02*
X1189569D01*
G01D02*
Y1667725D01*
G01X1187561Y1674562D02*
Y1664068D01*
G01X1195800Y1653125D02*
X1199000D01*
G01X1185230Y1652815D02*
X1188430D01*
G01X1190900Y1656325D02*
Y1662525D01*
G01D02*
X1194100D01*
G01D02*
Y1656325D01*
G01D02*
X1190900D01*
G01X1195800D02*
Y1662525D01*
G01D02*
X1199000D01*
G01D02*
Y1656325D01*
G01D02*
X1195800D01*
G01X1185230Y1656015D02*
Y1662215D01*
G01D02*
X1188430D01*
G01D02*
Y1656015D01*
G01D02*
X1185230D01*
G01X1190900Y1653125D02*
X1194100D01*
G01X1189569Y1674872D02*
X1198231D01*
G01X1189569Y1667725D02*
X1191769Y1669625D01*
G01D02*
X1189569Y1671525D01*
G01D02*
Y1674872D01*
G01X1197746Y1682459D02*
Y1676259D01*
G01D02*
X1194546D01*
G01D02*
Y1682459D01*
G01X1187176Y1682149D02*
Y1675949D01*
G01X1189443Y1687310D02*
X1189391Y1687003D01*
X1189185Y1686735D01*
X1188875Y1686505D01*
X1188513Y1686352D01*
X1188100Y1686275D01*
X1187686D01*
X1187273Y1686352D01*
X1186911Y1686505D01*
X1186601Y1686735D01*
X1186395Y1687003D01*
X1186343Y1687310D01*
X1186395Y1687617D01*
X1186601Y1687885D01*
X1186911Y1688115D01*
X1187273Y1688268D01*
X1187686Y1688345D01*
X1188100D01*
X1188513Y1688268D01*
X1188875Y1688115D01*
X1189185Y1687885D01*
X1189391Y1687617D01*
X1189443Y1687310D01*
G01X1188616Y1687617D02*
X1189443Y1688077D01*
G01Y1690410D02*
X1186343D01*
X1186963Y1689950D01*
G01X1189443D02*
Y1690870D01*
G01X1188823Y1692667D02*
X1189185Y1692897D01*
X1189391Y1693203D01*
X1189443Y1693548D01*
X1189391Y1693855D01*
X1189133Y1694162D01*
X1188823Y1694353D01*
X1188513Y1694392D01*
X1188151Y1694315D01*
X1187893Y1694047D01*
X1187790Y1693778D01*
Y1693433D01*
G01Y1693778D02*
X1187635Y1694008D01*
X1187376Y1694200D01*
X1187066Y1694277D01*
X1186756Y1694200D01*
X1186498Y1694008D01*
X1186343Y1693663D01*
X1186395Y1693318D01*
X1186601Y1692973D01*
G01X1188823Y1695767D02*
X1189185Y1695997D01*
X1189391Y1696303D01*
X1189443Y1696648D01*
X1189391Y1696955D01*
X1189133Y1697262D01*
X1188823Y1697453D01*
X1188513Y1697492D01*
X1188151Y1697415D01*
X1187893Y1697147D01*
X1187790Y1696878D01*
Y1696533D01*
G01Y1696878D02*
X1187635Y1697108D01*
X1187376Y1697300D01*
X1187066Y1697377D01*
X1186756Y1697300D01*
X1186498Y1697108D01*
X1186343Y1696763D01*
X1186395Y1696418D01*
X1186601Y1696073D01*
G01X1198840Y1698605D02*
Y1692405D01*
G01D02*
X1195640D01*
G01D02*
Y1698605D01*
G01X1194546Y1682459D02*
X1197746D01*
G01X1191735Y1689990D02*
X1197935D01*
Y1686790D01*
X1191735D01*
Y1689990D01*
G01X1193940Y1698605D02*
Y1692405D01*
G01D02*
X1190740D01*
G01D02*
Y1698605D01*
G01X1189309Y1709858D02*
Y1713205D01*
G01X1197971Y1720352D02*
Y1709858D01*
G01D02*
X1189309D01*
G01Y1713205D02*
X1191509Y1715105D01*
G01X1208741Y1709903D02*
X1200079D01*
G01D02*
Y1713250D01*
G01D02*
X1202279Y1715150D01*
G01X1195640Y1698605D02*
X1198840D01*
G01X1190740D02*
X1193940D01*
G01X1195640Y1701805D02*
Y1708005D01*
G01D02*
X1198840D01*
G01D02*
Y1701805D01*
G01D02*
X1195640D01*
G01X1190740D02*
Y1708005D01*
G01D02*
X1193940D01*
G01D02*
Y1701805D01*
G01D02*
X1190740D01*
G01X1191509Y1715105D02*
X1189309Y1717005D01*
G01D02*
Y1720352D01*
G01D02*
X1197971D01*
G01X1200079Y1720397D02*
X1208741D01*
G01X1202279Y1715150D02*
X1200079Y1717050D01*
G01D02*
Y1720397D01*
G01X1197586Y1727939D02*
Y1721739D01*
G01D02*
X1194386D01*
G01Y1727939D02*
X1197586D01*
G01X1194386Y1721739D02*
Y1727939D01*
G01X1211501Y52260D02*
Y55460D01*
G01X1217701Y52260D02*
X1211501D01*
G01Y55460D02*
X1217701D01*
G01X1208861Y62660D02*
Y59460D01*
G01X1202661Y62660D02*
X1208861D01*
G01X1202661Y59460D02*
Y62660D01*
G01X1208861Y59460D02*
X1202661D01*
G01Y55530D02*
Y58730D01*
G01X1208861Y55530D02*
X1202661D01*
G01X1208861Y58730D02*
Y55530D01*
G01X1202661Y58730D02*
X1208861D01*
G01X1207044Y89384D02*
Y77416D01*
X1221756D01*
Y89384D01*
X1207044D01*
G01X1213300Y92000D02*
X1207100D01*
Y95200D01*
X1213300D01*
Y92000D01*
G01X1221100D02*
X1214900D01*
Y95200D01*
X1221100D01*
Y92000D01*
G01X1222200Y109902D02*
Y97698D01*
X1206200D01*
Y109902D01*
X1212200D01*
X1214200Y106800D01*
X1216200Y109902D01*
X1222200D01*
G01X1200619Y107927D02*
Y120401D01*
G01X1214500Y111600D02*
X1208300D01*
Y114800D01*
X1214500D01*
Y111600D01*
G01X1210602Y116017D02*
Y122217D01*
G01X1213802Y116017D02*
X1210602D01*
G01X1213802Y122217D02*
Y116017D01*
G01X1215493Y117862D02*
Y121062D01*
G01X1221693Y117862D02*
X1215493D01*
G01X1210602Y122217D02*
X1213802D01*
G01X1215493Y121062D02*
X1221693D01*
G01X1215493Y134562D02*
X1221693D01*
G01X1215493Y131362D02*
Y134562D01*
G01X1221693Y131362D02*
X1215493D01*
G01X1215497Y150509D02*
X1221697D01*
G01X1215497Y147309D02*
Y150509D01*
G01X1221697Y147309D02*
X1215497D01*
G01Y146509D02*
X1221697D01*
G01X1215497Y143309D02*
Y146509D01*
G01X1221697Y143309D02*
X1215497D01*
G01X1215493Y139362D02*
Y142562D01*
G01X1221693Y139362D02*
X1215493D01*
G01Y142562D02*
X1221693D01*
G01X1215493Y152362D02*
Y155562D01*
G01X1221693Y152362D02*
X1215493D01*
G01Y155562D02*
X1221693D01*
G01X1215493Y159562D02*
X1221693D01*
G01X1215493Y156362D02*
Y159562D01*
G01X1221693Y156362D02*
X1215493D01*
G01Y167362D02*
Y170562D01*
G01X1221693Y167362D02*
X1215493D01*
G01X1213193Y166562D02*
Y163362D01*
G01X1206993Y166562D02*
X1213193D01*
G01X1206993Y163362D02*
Y166562D01*
G01X1213193Y163362D02*
X1206993D01*
G01X1215493Y166562D02*
X1221693D01*
G01X1215493Y163362D02*
Y166562D01*
G01X1221693Y163362D02*
X1215493D01*
G01Y178562D02*
X1221693D01*
G01X1215493Y175362D02*
Y178562D01*
G01X1221693Y175362D02*
X1215493D01*
G01X1213193Y178562D02*
Y175362D01*
G01X1206993Y178562D02*
X1213193D01*
G01X1206993Y175362D02*
Y178562D01*
G01X1213193Y175362D02*
X1206993D01*
G01X1215493Y183862D02*
Y187062D01*
G01X1221693Y183862D02*
X1215493D01*
G01X1215479Y174545D02*
X1221679D01*
G01X1215479Y171345D02*
Y174545D01*
G01X1221679Y171345D02*
X1215479D01*
G01X1215493Y170562D02*
X1221693D01*
G01X1214619Y173211D02*
Y170011D01*
G01X1208419Y173211D02*
X1214619D01*
G01X1208419Y170011D02*
Y173211D01*
G01X1214619Y170011D02*
X1208419D01*
G01X1206120Y187762D02*
Y190962D01*
G01X1212320Y187762D02*
X1206120D01*
G01X1212320Y190962D02*
Y187762D01*
G01X1206120Y190962D02*
X1212320D01*
G01X1215493Y187062D02*
X1221693D01*
G01X1215620Y196462D02*
X1221820D01*
G01X1215620Y193262D02*
Y196462D01*
G01X1221820Y193262D02*
X1215620D01*
G01X1212320Y201909D02*
Y198709D01*
G01X1206120D02*
Y201909D01*
G01X1212320Y198709D02*
X1206120D01*
G01X1212320Y196962D02*
Y193762D01*
G01X1206120Y196962D02*
X1212320D01*
G01X1206120Y193762D02*
Y196962D01*
G01X1212320Y193762D02*
X1206120D01*
G01X1214210Y217552D02*
X1211010D01*
G01X1214210Y223752D02*
Y217552D01*
G01X1211010D02*
Y223752D01*
G01X1213320Y205762D02*
X1210120D01*
G01X1213320Y211962D02*
Y205762D01*
G01X1210120Y211962D02*
X1213320D01*
G01X1210120Y205762D02*
Y211962D01*
G01X1209130Y217452D02*
X1205930D01*
G01X1209130Y223652D02*
Y217452D01*
G01X1205930D02*
Y223652D01*
G01X1206120Y201909D02*
X1212320D01*
G01X1208820Y205762D02*
X1205620D01*
G01X1208820Y211962D02*
Y205762D01*
G01X1205620Y211962D02*
X1208820D01*
G01X1205620Y205762D02*
Y211962D01*
G01X1218210Y217552D02*
X1215010D01*
G01D02*
Y223752D01*
G01X1217320Y205762D02*
X1214120D01*
G01Y211962D02*
X1217320D01*
G01X1214120Y205762D02*
Y211962D01*
G01X1214484Y239232D02*
Y225632D01*
G01X1205684Y231432D02*
Y225632D01*
G01Y239232D02*
Y233432D01*
G01X1214484Y225632D02*
X1205684D01*
G01Y233432D02*
X1207184Y232432D01*
X1205684Y231432D01*
G01X1211010Y223752D02*
X1214210D01*
G01X1205930Y223652D02*
X1209130D01*
G01X1215010Y223752D02*
X1218210D01*
G01X1205684Y239232D02*
X1214484D01*
G01X1211500Y242473D02*
X1208300D01*
G01X1211500Y248673D02*
Y242473D01*
G01X1208300Y248673D02*
X1211500D01*
G01X1208300Y242473D02*
Y248673D01*
G01X1202075Y238192D02*
Y234992D01*
G01Y242272D02*
Y239072D01*
G01Y246292D02*
Y243092D01*
G01X1218256Y242473D02*
X1215056D01*
G01Y248673D02*
X1218256D01*
G01X1215056Y242473D02*
Y248673D01*
G01X1211367Y697211D02*
X1236957D01*
G01X1211367Y1335007D02*
Y697211D01*
G01X1207257D02*
Y1335007D01*
G01X1236957Y732644D02*
X1211367D01*
G01X1236957Y1299574D02*
X1211367D01*
G01X1210045Y1336996D02*
X1210237Y1336686D01*
X1210467Y1336479D01*
X1210735Y1336376D01*
X1211042Y1336479D01*
X1211272Y1336686D01*
X1211502Y1336996D01*
X1211579Y1337409D01*
Y1339476D01*
G01X1213184Y1338959D02*
X1213414Y1339269D01*
X1213682Y1339424D01*
X1213989Y1339476D01*
X1214372Y1339373D01*
X1214640Y1339114D01*
X1214717Y1338804D01*
X1214679Y1338494D01*
X1214525Y1338236D01*
X1213759Y1337719D01*
X1213414Y1337358D01*
X1213184Y1336841D01*
X1213107Y1336376D01*
X1214717D01*
G01X1236957Y1335007D02*
X1211367D01*
G01X1203082Y1439732D02*
Y1433732D01*
G01X1201052Y1456022D02*
Y1450022D01*
G01X1201092Y1449212D02*
Y1443212D01*
G01X1207943Y1441582D02*
Y1444682D01*
X1208863D01*
X1209170Y1444527D01*
X1209400Y1444165D01*
X1209477Y1443752D01*
X1209400Y1443339D01*
X1209208Y1443029D01*
X1208863Y1442874D01*
X1207943D01*
G01X1210967Y1444682D02*
Y1442460D01*
X1211120Y1441995D01*
X1211427Y1441685D01*
X1211810Y1441582D01*
X1212193Y1441685D01*
X1212500Y1441995D01*
X1212653Y1442460D01*
Y1444682D01*
G01X1214833Y1441582D02*
X1214910Y1442254D01*
X1215025Y1442822D01*
X1215178Y1443339D01*
X1215370Y1443907D01*
X1215677Y1444682D01*
X1214143D01*
G01X1218010D02*
X1217703Y1444579D01*
X1217473Y1444320D01*
X1217320Y1444010D01*
X1217205Y1443597D01*
X1217167Y1443132D01*
X1217205Y1442667D01*
X1217320Y1442254D01*
X1217473Y1441944D01*
X1217703Y1441685D01*
X1218010Y1441582D01*
X1218317Y1441685D01*
X1218547Y1441944D01*
X1218700Y1442254D01*
X1218815Y1442667D01*
X1218853Y1443132D01*
X1218815Y1443597D01*
X1218700Y1444010D01*
X1218547Y1444320D01*
X1218317Y1444579D01*
X1218010Y1444682D01*
G01X1219960Y1440549D02*
X1222260D01*
G01X1223443Y1441582D02*
Y1444682D01*
X1224363D01*
X1224670Y1444527D01*
X1224900Y1444165D01*
X1224977Y1443752D01*
X1224900Y1443339D01*
X1224708Y1443029D01*
X1224363Y1442874D01*
X1223443D01*
G01X1227310Y1444682D02*
X1227003Y1444579D01*
X1226773Y1444320D01*
X1226620Y1444010D01*
X1226505Y1443597D01*
X1226467Y1443132D01*
X1226505Y1442667D01*
X1226620Y1442254D01*
X1226773Y1441944D01*
X1227003Y1441685D01*
X1227310Y1441582D01*
X1227617Y1441685D01*
X1227847Y1441944D01*
X1228000Y1442254D01*
X1228115Y1442667D01*
X1228153Y1443132D01*
X1228115Y1443597D01*
X1228000Y1444010D01*
X1227847Y1444320D01*
X1227617Y1444579D01*
X1227310Y1444682D01*
G01X1229260Y1440549D02*
X1231560D01*
G01X1232782Y1444165D02*
X1233012Y1444475D01*
X1233280Y1444630D01*
X1233587Y1444682D01*
X1233970Y1444579D01*
X1234238Y1444320D01*
X1234315Y1444010D01*
X1234277Y1443700D01*
X1234123Y1443442D01*
X1233357Y1442925D01*
X1233012Y1442564D01*
X1232782Y1442047D01*
X1232705Y1441582D01*
X1234315D01*
G01X1218193Y1639755D02*
X1218141Y1639448D01*
X1217935Y1639180D01*
X1217625Y1638950D01*
X1217263Y1638797D01*
X1216850Y1638720D01*
X1216436D01*
X1216023Y1638797D01*
X1215661Y1638950D01*
X1215351Y1639180D01*
X1215145Y1639448D01*
X1215093Y1639755D01*
X1215145Y1640062D01*
X1215351Y1640330D01*
X1215661Y1640560D01*
X1216023Y1640713D01*
X1216436Y1640790D01*
X1216850D01*
X1217263Y1640713D01*
X1217625Y1640560D01*
X1217935Y1640330D01*
X1218141Y1640062D01*
X1218193Y1639755D01*
G01X1217366Y1640062D02*
X1218193Y1640522D01*
G01Y1642855D02*
X1215093D01*
X1215713Y1642395D01*
G01X1218193D02*
Y1643315D01*
G01X1215610Y1645227D02*
X1215300Y1645457D01*
X1215145Y1645725D01*
X1215093Y1646032D01*
X1215196Y1646415D01*
X1215455Y1646683D01*
X1215765Y1646760D01*
X1216075Y1646722D01*
X1216333Y1646568D01*
X1216850Y1645802D01*
X1217211Y1645457D01*
X1217728Y1645227D01*
X1218193Y1645150D01*
Y1646760D01*
G01Y1649055D02*
X1218141Y1649323D01*
X1217986Y1649630D01*
X1217728Y1649822D01*
X1217366Y1649898D01*
X1217005Y1649822D01*
X1216695Y1649592D01*
X1216540Y1649247D01*
Y1648863D01*
X1216436Y1648633D01*
X1216178Y1648442D01*
X1215816Y1648365D01*
X1215455Y1648480D01*
X1215196Y1648748D01*
X1215093Y1649055D01*
X1215196Y1649362D01*
X1215455Y1649630D01*
X1215816Y1649745D01*
X1216178Y1649668D01*
X1216436Y1649477D01*
X1216540Y1649247D01*
Y1648863D01*
X1216695Y1648518D01*
X1217005Y1648288D01*
X1217366Y1648212D01*
X1217728Y1648288D01*
X1217986Y1648480D01*
X1218141Y1648787D01*
X1218193Y1649055D01*
G01X1213693Y1639875D02*
X1213641Y1639568D01*
X1213435Y1639300D01*
X1213125Y1639070D01*
X1212763Y1638917D01*
X1212350Y1638840D01*
X1211936D01*
X1211523Y1638917D01*
X1211161Y1639070D01*
X1210851Y1639300D01*
X1210645Y1639568D01*
X1210593Y1639875D01*
X1210645Y1640182D01*
X1210851Y1640450D01*
X1211161Y1640680D01*
X1211523Y1640833D01*
X1211936Y1640910D01*
X1212350D01*
X1212763Y1640833D01*
X1213125Y1640680D01*
X1213435Y1640450D01*
X1213641Y1640182D01*
X1213693Y1639875D01*
G01X1212866Y1640182D02*
X1213693Y1640642D01*
G01Y1642975D02*
X1210593D01*
X1211213Y1642515D01*
G01X1213693D02*
Y1643435D01*
G01X1213073Y1645232D02*
X1213435Y1645462D01*
X1213641Y1645768D01*
X1213693Y1646113D01*
X1213641Y1646420D01*
X1213383Y1646727D01*
X1213073Y1646918D01*
X1212763Y1646957D01*
X1212401Y1646880D01*
X1212143Y1646612D01*
X1212040Y1646343D01*
Y1645998D01*
G01Y1646343D02*
X1211885Y1646573D01*
X1211626Y1646765D01*
X1211316Y1646842D01*
X1211006Y1646765D01*
X1210748Y1646573D01*
X1210593Y1646228D01*
X1210645Y1645883D01*
X1210851Y1645538D01*
G01X1211110Y1648447D02*
X1210800Y1648677D01*
X1210645Y1648945D01*
X1210593Y1649252D01*
X1210696Y1649635D01*
X1210955Y1649903D01*
X1211265Y1649980D01*
X1211575Y1649942D01*
X1211833Y1649788D01*
X1212350Y1649022D01*
X1212711Y1648677D01*
X1213228Y1648447D01*
X1213693Y1648370D01*
Y1649980D01*
G01X1209253Y1640135D02*
X1209201Y1639828D01*
X1208995Y1639560D01*
X1208685Y1639330D01*
X1208323Y1639177D01*
X1207910Y1639100D01*
X1207496D01*
X1207083Y1639177D01*
X1206721Y1639330D01*
X1206411Y1639560D01*
X1206205Y1639828D01*
X1206153Y1640135D01*
X1206205Y1640442D01*
X1206411Y1640710D01*
X1206721Y1640940D01*
X1207083Y1641093D01*
X1207496Y1641170D01*
X1207910D01*
X1208323Y1641093D01*
X1208685Y1640940D01*
X1208995Y1640710D01*
X1209201Y1640442D01*
X1209253Y1640135D01*
G01X1208426Y1640442D02*
X1209253Y1640902D01*
G01Y1643235D02*
X1206153D01*
X1206773Y1642775D01*
G01X1209253D02*
Y1643695D01*
G01X1206670Y1645607D02*
X1206360Y1645837D01*
X1206205Y1646105D01*
X1206153Y1646412D01*
X1206256Y1646795D01*
X1206515Y1647063D01*
X1206825Y1647140D01*
X1207135Y1647102D01*
X1207393Y1646948D01*
X1207910Y1646182D01*
X1208271Y1645837D01*
X1208788Y1645607D01*
X1209253Y1645530D01*
Y1647140D01*
G01X1208891Y1648783D02*
X1209150Y1649052D01*
X1209253Y1649358D01*
X1209150Y1649665D01*
X1208840Y1649933D01*
X1208375Y1650125D01*
X1207910Y1650202D01*
X1207341D01*
X1206876Y1650125D01*
X1206463Y1649933D01*
X1206256Y1649703D01*
X1206153Y1649435D01*
X1206256Y1649128D01*
X1206463Y1648898D01*
X1206773Y1648745D01*
X1207186Y1648668D01*
X1207548Y1648745D01*
X1207910Y1648937D01*
X1208116Y1649167D01*
X1208168Y1649435D01*
X1208065Y1649742D01*
X1207806Y1649972D01*
X1207341Y1650202D01*
G01X1204943Y1640002D02*
X1204891Y1639695D01*
X1204685Y1639427D01*
X1204375Y1639197D01*
X1204013Y1639044D01*
X1203600Y1638967D01*
X1203186D01*
X1202773Y1639044D01*
X1202411Y1639197D01*
X1202101Y1639427D01*
X1201895Y1639695D01*
X1201843Y1640002D01*
X1201895Y1640309D01*
X1202101Y1640577D01*
X1202411Y1640807D01*
X1202773Y1640960D01*
X1203186Y1641037D01*
X1203600D01*
X1204013Y1640960D01*
X1204375Y1640807D01*
X1204685Y1640577D01*
X1204891Y1640309D01*
X1204943Y1640002D01*
G01X1204116Y1640309D02*
X1204943Y1640769D01*
G01Y1643102D02*
X1201843D01*
X1202463Y1642642D01*
G01X1204943D02*
Y1643562D01*
G01X1204323Y1645359D02*
X1204685Y1645589D01*
X1204891Y1645895D01*
X1204943Y1646240D01*
X1204891Y1646547D01*
X1204633Y1646854D01*
X1204323Y1647045D01*
X1204013Y1647084D01*
X1203651Y1647007D01*
X1203393Y1646739D01*
X1203290Y1646470D01*
Y1646125D01*
G01Y1646470D02*
X1203135Y1646700D01*
X1202876Y1646892D01*
X1202566Y1646969D01*
X1202256Y1646892D01*
X1201998Y1646700D01*
X1201843Y1646355D01*
X1201895Y1646010D01*
X1202101Y1645665D01*
G01X1204943Y1649762D02*
X1201843D01*
X1204065Y1648344D01*
Y1650260D01*
G01X1208200Y1656362D02*
Y1654140D01*
X1208353Y1653675D01*
X1208660Y1653365D01*
X1209043Y1653262D01*
X1209426Y1653365D01*
X1209733Y1653675D01*
X1209886Y1654140D01*
Y1656362D01*
G01X1211300Y1653882D02*
X1211530Y1653520D01*
X1211836Y1653314D01*
X1212181Y1653262D01*
X1212488Y1653314D01*
X1212795Y1653572D01*
X1212986Y1653882D01*
X1213025Y1654192D01*
X1212948Y1654554D01*
X1212680Y1654812D01*
X1212411Y1654915D01*
X1212066D01*
G01X1212411D02*
X1212641Y1655070D01*
X1212833Y1655329D01*
X1212910Y1655639D01*
X1212833Y1655949D01*
X1212641Y1656207D01*
X1212296Y1656362D01*
X1211951Y1656310D01*
X1211606Y1656104D01*
G01X1215243Y1656362D02*
X1214936Y1656259D01*
X1214706Y1656000D01*
X1214553Y1655690D01*
X1214438Y1655277D01*
X1214400Y1654812D01*
X1214438Y1654347D01*
X1214553Y1653934D01*
X1214706Y1653624D01*
X1214936Y1653365D01*
X1215243Y1653262D01*
X1215550Y1653365D01*
X1215780Y1653624D01*
X1215933Y1653934D01*
X1216048Y1654347D01*
X1216086Y1654812D01*
X1216048Y1655277D01*
X1215933Y1655690D01*
X1215780Y1656000D01*
X1215550Y1656259D01*
X1215243Y1656362D01*
G01X1218343Y1653262D02*
X1218611Y1653314D01*
X1218918Y1653469D01*
X1219110Y1653727D01*
X1219186Y1654089D01*
X1219110Y1654450D01*
X1218880Y1654760D01*
X1218535Y1654915D01*
X1218151D01*
X1217921Y1655019D01*
X1217730Y1655277D01*
X1217653Y1655639D01*
X1217768Y1656000D01*
X1218036Y1656259D01*
X1218343Y1656362D01*
X1218650Y1656259D01*
X1218918Y1656000D01*
X1219033Y1655639D01*
X1218956Y1655277D01*
X1218765Y1655019D01*
X1218535Y1654915D01*
X1218151D01*
X1217806Y1654760D01*
X1217576Y1654450D01*
X1217500Y1654089D01*
X1217576Y1653727D01*
X1217768Y1653469D01*
X1218075Y1653314D01*
X1218343Y1653262D01*
G01X1208457Y1664855D02*
X1206126Y1662524D01*
G01D02*
Y1659415D01*
G01D02*
X1214788D01*
G01D02*
Y1670295D01*
G01X1206126Y1667186D02*
X1208457Y1664855D01*
G01X1201667Y1651385D02*
Y1657585D01*
G01D02*
X1204867D01*
G01D02*
Y1651385D01*
G01D02*
X1201667D01*
G01X1206126Y1670295D02*
Y1667186D01*
G01X1214788Y1670295D02*
X1206126D01*
G01X1209305Y1675563D02*
X1215505D01*
G01D02*
Y1672363D01*
G01D02*
X1209305D01*
G01D02*
Y1675563D01*
G01X1208181Y1679473D02*
Y1676273D01*
G01D02*
X1201981D01*
G01D02*
Y1679473D01*
G01D02*
X1208181D01*
G01X1208185Y1680167D02*
X1201985D01*
G01D02*
Y1683367D01*
G01X1208185D02*
Y1680167D01*
G01X1215435Y1683373D02*
Y1680173D01*
G01D02*
X1209235D01*
G01D02*
Y1683373D01*
G01X1209610Y1698650D02*
Y1692450D01*
G01D02*
X1206410D01*
G01D02*
Y1698650D01*
G01X1201985Y1683367D02*
X1208185D01*
G01X1209235Y1683373D02*
X1215435D01*
G01X1202505Y1690035D02*
X1208705D01*
Y1686835D01*
X1202505D01*
Y1690035D01*
G01X1204710Y1698650D02*
Y1692450D01*
G01D02*
X1201510D01*
G01D02*
Y1698650D01*
G01X1213305Y1690300D02*
X1219505D01*
Y1687100D01*
X1213305D01*
Y1690300D01*
G01X1215510Y1698915D02*
Y1692715D01*
G01D02*
X1212310D01*
G01D02*
Y1698915D01*
G01X1219541Y1710168D02*
X1210879D01*
G01D02*
Y1713515D01*
G01D02*
X1213079Y1715415D01*
G01X1208741Y1720397D02*
Y1709903D01*
G01X1206410Y1698650D02*
X1209610D01*
G01X1201510D02*
X1204710D01*
G01X1206410Y1701850D02*
Y1708050D01*
G01D02*
X1209610D01*
G01D02*
Y1701850D01*
G01D02*
X1206410D01*
G01X1201510D02*
Y1708050D01*
G01D02*
X1204710D01*
G01D02*
Y1701850D01*
G01D02*
X1201510D01*
G01X1212310Y1698915D02*
X1215510D01*
G01X1212310Y1702115D02*
Y1708315D01*
G01D02*
X1215510D01*
G01D02*
Y1702115D01*
G01D02*
X1212310D01*
G01X1210879Y1720662D02*
X1219541D01*
G01X1213079Y1715415D02*
X1210879Y1717315D01*
G01D02*
Y1720662D01*
G01X1208356Y1727984D02*
Y1721784D01*
G01D02*
X1205156D01*
G01D02*
Y1727984D01*
G01D02*
X1208356D01*
G01X1219156Y1722049D02*
X1215956D01*
G01D02*
Y1728249D01*
G01D02*
X1219156D01*
G01X1211625Y1731607D02*
X1211318Y1731659D01*
X1211050Y1731865D01*
X1210820Y1732175D01*
X1210667Y1732537D01*
X1210590Y1732950D01*
Y1733364D01*
X1210667Y1733777D01*
X1210820Y1734139D01*
X1211050Y1734449D01*
X1211318Y1734655D01*
X1211625Y1734707D01*
X1211932Y1734655D01*
X1212200Y1734449D01*
X1212430Y1734139D01*
X1212583Y1733777D01*
X1212660Y1733364D01*
Y1732950D01*
X1212583Y1732537D01*
X1212430Y1732175D01*
X1212200Y1731865D01*
X1211932Y1731659D01*
X1211625Y1731607D01*
G01X1211932Y1732434D02*
X1212392Y1731607D01*
G01X1214725D02*
Y1734707D01*
X1214265Y1734087D01*
G01Y1731607D02*
X1215185D01*
G01X1216982Y1732227D02*
X1217212Y1731865D01*
X1217518Y1731659D01*
X1217863Y1731607D01*
X1218170Y1731659D01*
X1218477Y1731917D01*
X1218668Y1732227D01*
X1218707Y1732537D01*
X1218630Y1732899D01*
X1218362Y1733157D01*
X1218093Y1733260D01*
X1217748D01*
G01X1218093D02*
X1218323Y1733415D01*
X1218515Y1733674D01*
X1218592Y1733984D01*
X1218515Y1734294D01*
X1218323Y1734552D01*
X1217978Y1734707D01*
X1217633Y1734655D01*
X1217288Y1734449D01*
G01X1220925Y1731607D02*
Y1734707D01*
X1220465Y1734087D01*
G01Y1731607D02*
X1221385D01*
G01X1225629Y51738D02*
X1228231Y54340D01*
G01X1221407Y51738D02*
X1225629D01*
G01X1221407Y63942D02*
Y51738D01*
G01X1230833D02*
X1235055D01*
G01X1228231Y54340D02*
X1230833Y51738D01*
G01X1217701Y55460D02*
Y52260D01*
G01X1223396Y68831D02*
Y66609D01*
X1223549Y66144D01*
X1223856Y65834D01*
X1224239Y65731D01*
X1224622Y65834D01*
X1224929Y66144D01*
X1225082Y66609D01*
Y68831D01*
G01X1227339Y65731D02*
Y68831D01*
X1226879Y68211D01*
G01Y65731D02*
X1227799D01*
G01X1229596Y66196D02*
X1229826Y65938D01*
X1230094Y65783D01*
X1230439Y65731D01*
X1230784Y65834D01*
X1231052Y66041D01*
X1231244Y66403D01*
X1231282Y66816D01*
X1231206Y67229D01*
X1231014Y67488D01*
X1230746Y67694D01*
X1230477Y67746D01*
X1230209Y67694D01*
X1229864Y67488D01*
X1229979Y68831D01*
X1231014D01*
G01X1233462Y65731D02*
X1233539Y66403D01*
X1233654Y66971D01*
X1233807Y67488D01*
X1233999Y68056D01*
X1234306Y68831D01*
X1232772D01*
G01X1235055Y63942D02*
X1221407D01*
G01X1223207Y85570D02*
Y83348D01*
X1223360Y82883D01*
X1223667Y82573D01*
X1224050Y82470D01*
X1224433Y82573D01*
X1224740Y82883D01*
X1224893Y83348D01*
Y85570D01*
G01X1226307Y83090D02*
X1226537Y82728D01*
X1226843Y82522D01*
X1227188Y82470D01*
X1227495Y82522D01*
X1227802Y82780D01*
X1227993Y83090D01*
X1228032Y83400D01*
X1227955Y83762D01*
X1227687Y84020D01*
X1227418Y84123D01*
X1227073D01*
G01X1227418D02*
X1227648Y84278D01*
X1227840Y84537D01*
X1227917Y84847D01*
X1227840Y85157D01*
X1227648Y85415D01*
X1227303Y85570D01*
X1226958Y85518D01*
X1226613Y85312D01*
G01X1230710Y82470D02*
Y85570D01*
X1229292Y83348D01*
X1231208D01*
G01X1233350Y82470D02*
Y85570D01*
X1232890Y84950D01*
G01Y82470D02*
X1233810D01*
G01X1231290Y101008D02*
Y104208D01*
G01X1237490Y101008D02*
X1231290D01*
G01X1226900Y95800D02*
X1233100D01*
Y92600D01*
X1226900D01*
Y95800D01*
G01Y100000D02*
X1233100D01*
Y96800D01*
X1226900D01*
Y100000D01*
G01X1227594Y115582D02*
Y112382D01*
G01X1221394Y115582D02*
X1227594D01*
G01X1221394Y112382D02*
Y115582D01*
G01X1227594Y112382D02*
X1221394D01*
G01X1221693Y121062D02*
Y117862D01*
G01X1231291Y108209D02*
X1237491D01*
G01X1231291Y105009D02*
Y108209D01*
G01X1237491Y105009D02*
X1231291D01*
G01X1231290Y104208D02*
X1237490D01*
G01X1228757Y112820D02*
Y110598D01*
X1228910Y110133D01*
X1229217Y109823D01*
X1229600Y109720D01*
X1229983Y109823D01*
X1230290Y110133D01*
X1230443Y110598D01*
Y112820D01*
G01X1231857Y110340D02*
X1232087Y109978D01*
X1232393Y109772D01*
X1232738Y109720D01*
X1233045Y109772D01*
X1233352Y110030D01*
X1233543Y110340D01*
X1233582Y110650D01*
X1233505Y111012D01*
X1233237Y111270D01*
X1232968Y111373D01*
X1232623D01*
G01X1232968D02*
X1233198Y111528D01*
X1233390Y111787D01*
X1233467Y112097D01*
X1233390Y112407D01*
X1233198Y112665D01*
X1232853Y112820D01*
X1232508Y112768D01*
X1232163Y112562D01*
G01X1236260Y109720D02*
Y112820D01*
X1234842Y110598D01*
X1236758D01*
G01X1238172Y112303D02*
X1238402Y112613D01*
X1238670Y112768D01*
X1238977Y112820D01*
X1239360Y112717D01*
X1239628Y112458D01*
X1239705Y112148D01*
X1239667Y111838D01*
X1239513Y111580D01*
X1238747Y111063D01*
X1238402Y110702D01*
X1238172Y110185D01*
X1238095Y109720D01*
X1239705D01*
G01X1227011Y131009D02*
X1233211D01*
G01X1227011Y127809D02*
Y131009D01*
G01X1233211Y127809D02*
X1227011D01*
G01X1221693Y134562D02*
Y131362D01*
G01X1226993Y135862D02*
X1233193D01*
G01X1226993Y132662D02*
Y135862D01*
G01X1233193Y132662D02*
X1226993D01*
G01Y151515D02*
Y154715D01*
G01X1233193Y151515D02*
X1226993D01*
G01X1221697Y150509D02*
Y147309D01*
G01Y146509D02*
Y143309D01*
G01X1221693Y142562D02*
Y139362D01*
G01Y155562D02*
Y152362D01*
G01X1226993Y142710D02*
X1233193D01*
G01X1226993Y139510D02*
Y142710D01*
G01X1233193Y139510D02*
X1226993D01*
G01Y154715D02*
X1233193D01*
G01X1221693Y159562D02*
Y156362D01*
G01Y170562D02*
Y167362D01*
G01Y166562D02*
Y163362D01*
G01X1226993Y165062D02*
X1233193D01*
G01X1226993Y161862D02*
Y165062D01*
G01X1233193Y161862D02*
X1226993D01*
G01Y158562D02*
X1233193D01*
G01X1226993Y155362D02*
Y158562D01*
G01X1233193Y155362D02*
X1226993D01*
G01Y166562D02*
Y169762D01*
G01X1233193Y166562D02*
X1226993D01*
G01X1221693Y178562D02*
Y175362D01*
G01Y187062D02*
Y183862D01*
G01X1226993Y179562D02*
X1233193D01*
G01X1226993Y176362D02*
Y179562D01*
G01X1233193Y176362D02*
X1226993D01*
G01X1221679Y174545D02*
Y171345D01*
G01X1226993Y169762D02*
X1233193D01*
G01X1226993Y171362D02*
Y174562D01*
G01X1233193Y171362D02*
X1226993D01*
G01Y174562D02*
X1233193D01*
G01X1221820Y196462D02*
Y193262D01*
G01X1222100Y211962D02*
Y205762D01*
G01D02*
X1218900D01*
G01D02*
Y211962D01*
G01D02*
X1222100D01*
G01X1218210Y223752D02*
Y217552D01*
G01X1217320Y211962D02*
Y205762D01*
G01X1217157Y233778D02*
Y231556D01*
X1217310Y231091D01*
X1217617Y230781D01*
X1218000Y230678D01*
X1218383Y230781D01*
X1218690Y231091D01*
X1218843Y231556D01*
Y233778D01*
G01X1221100Y230678D02*
Y233778D01*
X1220640Y233158D01*
G01Y230678D02*
X1221560D01*
G01X1224660D02*
Y233778D01*
X1223242Y231556D01*
X1225158D01*
G01X1226572Y233261D02*
X1226802Y233571D01*
X1227070Y233726D01*
X1227377Y233778D01*
X1227760Y233675D01*
X1228028Y233416D01*
X1228105Y233106D01*
X1228067Y232796D01*
X1227913Y232538D01*
X1227147Y232021D01*
X1226802Y231660D01*
X1226572Y231143D01*
X1226495Y230678D01*
X1228105D01*
G01X1218256Y248673D02*
Y242473D01*
G01X1222173Y1636262D02*
Y1643762D01*
X1224413D01*
X1225160Y1643387D01*
X1225720Y1642512D01*
X1225907Y1641512D01*
X1225720Y1640512D01*
X1225253Y1639762D01*
X1224413Y1639387D01*
X1222173D01*
G01X1229673Y1636262D02*
Y1643762D01*
X1232007D01*
X1232753Y1643387D01*
X1233220Y1642887D01*
X1233407Y1641887D01*
X1233220Y1640887D01*
X1232660Y1640262D01*
X1232007Y1639887D01*
X1229673D01*
G01X1232007D02*
X1233407Y1636262D01*
G01X1240907D02*
X1237173D01*
Y1643762D01*
X1240907D01*
G01X1239413Y1640137D02*
X1237173D01*
G01X1244580Y1637262D02*
X1245327Y1636637D01*
X1246167Y1636262D01*
X1246913D01*
X1247660Y1636637D01*
X1248220Y1637262D01*
X1248500Y1638137D01*
X1248313Y1639012D01*
X1247847Y1639762D01*
X1247007Y1640262D01*
X1245887Y1640512D01*
X1245233Y1641012D01*
X1244953Y1641887D01*
X1245140Y1642762D01*
X1245607Y1643387D01*
X1246260Y1643762D01*
X1246913D01*
X1247567Y1643512D01*
X1248127Y1642887D01*
G01X1252080Y1637262D02*
X1252827Y1636637D01*
X1253667Y1636262D01*
X1254413D01*
X1255160Y1636637D01*
X1255720Y1637262D01*
X1256000Y1638137D01*
X1255813Y1639012D01*
X1255347Y1639762D01*
X1254507Y1640262D01*
X1253387Y1640512D01*
X1252733Y1641012D01*
X1252453Y1641887D01*
X1252640Y1642762D01*
X1253107Y1643387D01*
X1253760Y1643762D01*
X1254413D01*
X1255067Y1643512D01*
X1255627Y1642887D01*
G01X1260327Y1638762D02*
X1262753D01*
G01X1267267Y1636262D02*
Y1643762D01*
X1270813D01*
G01X1269507Y1640137D02*
X1267267D01*
G01X1275420Y1643762D02*
X1277660D01*
G01X1276540D02*
Y1636262D01*
G01X1275420D02*
X1277660D01*
G01X1284040Y1643762D02*
Y1636262D01*
G01X1281893Y1643762D02*
X1286187D01*
G01X1222048Y1646023D02*
Y1781456D01*
G01X1312205Y1646023D02*
X1222048D01*
G01X1228735Y1683223D02*
Y1680123D01*
X1230269D01*
G01X1228505Y1675399D02*
Y1678499D01*
X1229502Y1675916D01*
X1230499Y1678499D01*
Y1675399D01*
G01X1228620Y1670675D02*
Y1673775D01*
X1230384Y1670675D01*
Y1673775D01*
G01X1228735Y1690192D02*
X1228927Y1689882D01*
X1229157Y1689675D01*
X1229425Y1689572D01*
X1229732Y1689675D01*
X1229962Y1689882D01*
X1230192Y1690192D01*
X1230269Y1690605D01*
Y1692672D01*
G01X1228659Y1684848D02*
Y1687948D01*
G01X1230115D02*
X1228659Y1686036D01*
G01X1230345Y1684848D02*
X1229310Y1686915D01*
G01X1229042Y1697397D02*
X1229962D01*
G01X1229502D02*
Y1694297D01*
G01X1229042D02*
X1229962D01*
G01X1220410Y1698915D02*
Y1692715D01*
G01D02*
X1217210D01*
G01D02*
Y1698915D01*
G01X1219541Y1720662D02*
Y1710168D01*
G01X1230269Y1713194D02*
X1228735D01*
Y1716294D01*
X1230269D01*
G01X1229655Y1714796D02*
X1228735D01*
G01X1228774Y1708470D02*
Y1711570D01*
X1230230D01*
G01X1229694Y1710072D02*
X1228774D01*
G01X1229732Y1705296D02*
X1230499D01*
Y1704366D01*
X1230269Y1704056D01*
X1230000Y1703849D01*
X1229617Y1703746D01*
X1229234Y1703849D01*
X1228965Y1704056D01*
X1228735Y1704366D01*
X1228582Y1704728D01*
X1228505Y1705141D01*
Y1705503D01*
X1228582Y1705813D01*
X1228735Y1706174D01*
X1228965Y1706484D01*
X1229195Y1706691D01*
X1229502Y1706846D01*
X1229770D01*
X1230077Y1706743D01*
X1230307Y1706536D01*
G01X1228697Y1699021D02*
Y1702121D01*
G01X1230307D02*
Y1699021D01*
G01Y1700571D02*
X1228697D01*
G01X1217210Y1698915D02*
X1220410D01*
G01X1217210Y1708315D02*
X1220410D01*
G01D02*
Y1702115D01*
G01D02*
X1217210D01*
G01D02*
Y1708315D01*
G01X1228659Y1717919D02*
Y1721019D01*
X1229425D01*
X1229732Y1720864D01*
X1229962Y1720657D01*
X1230154Y1720347D01*
X1230307Y1719986D01*
X1230345Y1719469D01*
X1230307Y1718952D01*
X1230154Y1718591D01*
X1229962Y1718281D01*
X1229732Y1718074D01*
X1229425Y1717919D01*
X1228659D01*
G01X1229809Y1729021D02*
X1229962Y1729176D01*
X1230077Y1729435D01*
X1230154Y1729796D01*
X1230077Y1730106D01*
X1229924Y1730313D01*
X1229655Y1730468D01*
X1228620D01*
Y1727368D01*
X1229885D01*
X1230154Y1727575D01*
X1230307Y1727885D01*
X1230384Y1728246D01*
X1230307Y1728608D01*
X1230077Y1728918D01*
X1229809Y1729021D01*
X1228620D01*
G01X1230345Y1725485D02*
X1230115Y1725640D01*
X1229847Y1725743D01*
X1229540D01*
X1229195Y1725588D01*
X1228927Y1725330D01*
X1228735Y1725020D01*
X1228582Y1724503D01*
X1228544Y1724038D01*
X1228620Y1723573D01*
X1228735Y1723263D01*
X1228965Y1722953D01*
X1229234Y1722746D01*
X1229502Y1722643D01*
X1229770D01*
X1230039Y1722746D01*
X1230269Y1722901D01*
X1230460Y1723108D01*
G01X1219156Y1728249D02*
Y1722049D01*
G01X1222048Y1781456D02*
X1312205D01*
G01X1235055Y51738D02*
Y63942D01*
G01X1246982Y96608D02*
Y93408D01*
G01X1240782Y96608D02*
X1246982D01*
G01X1240782Y93408D02*
Y96608D01*
G01X1246982Y93408D02*
X1240782D01*
G01X1237490Y104208D02*
Y101008D01*
G01X1240782Y97185D02*
Y100385D01*
G01X1246982Y97185D02*
X1240782D01*
G01X1246982Y100385D02*
Y97185D01*
G01X1240782Y100385D02*
X1246982D01*
G01X1237491Y108209D02*
Y105009D01*
G01X1233211Y131009D02*
Y127809D01*
G01X1233193Y135862D02*
Y132662D01*
G01Y154715D02*
Y151515D01*
G01Y142710D02*
Y139510D01*
G01Y165062D02*
Y161862D01*
G01Y158562D02*
Y155362D01*
G01Y169762D02*
Y166562D01*
G01Y179562D02*
Y176362D01*
G01Y174562D02*
Y171362D01*
G01X1237460Y189679D02*
Y192879D01*
G01X1243660Y189679D02*
X1237460D01*
G01X1243660Y192879D02*
Y189679D01*
G01X1237460Y192879D02*
X1243660D01*
G01X1246493Y199962D02*
Y203162D01*
G01X1252693Y199962D02*
X1246493D01*
G01X1237493Y195862D02*
Y199062D01*
G01X1243693Y195862D02*
X1237493D01*
G01X1243693Y199062D02*
Y195862D01*
G01X1237493Y199062D02*
X1243693D01*
G01Y211062D02*
Y207862D01*
G01X1237493Y211062D02*
X1243693D01*
G01X1237493Y207862D02*
Y211062D01*
G01X1243693Y207862D02*
X1237493D01*
G01X1246493Y210162D02*
Y213362D01*
G01X1252693Y210162D02*
X1246493D01*
G01Y213362D02*
X1252693D01*
G01X1243693Y207462D02*
Y204262D01*
G01X1237493Y207462D02*
X1243693D01*
G01X1237493Y204262D02*
Y207462D01*
G01X1243693Y204262D02*
X1237493D01*
G01X1246493Y203762D02*
Y206962D01*
G01X1252693Y203762D02*
X1246493D01*
G01Y206962D02*
X1252693D01*
G01X1243693Y215062D02*
Y211862D01*
G01X1237493Y215062D02*
X1243693D01*
G01X1237493Y211862D02*
Y215062D01*
G01X1243693Y211862D02*
X1237493D01*
G01X1243693Y219062D02*
Y215862D01*
G01X1237493D02*
Y219062D01*
G01X1243693Y215862D02*
X1237493D01*
G01X1246493Y214162D02*
Y217362D01*
G01X1252693Y214162D02*
X1246493D01*
G01Y217362D02*
X1252693D01*
G01X1246493Y203162D02*
X1252693D01*
G01X1246493Y231862D02*
Y235062D01*
G01X1252693Y231862D02*
X1246493D01*
G01X1237493Y219062D02*
X1243693D01*
G01X1246493Y218062D02*
Y221262D01*
G01X1252693Y218062D02*
X1246493D01*
G01Y221262D02*
X1252693D01*
G01X1246493Y225062D02*
X1252693D01*
G01X1246493Y221862D02*
Y225062D01*
G01X1252693Y221862D02*
X1246493D01*
G01Y229062D02*
X1252693D01*
G01X1246493Y225862D02*
Y229062D01*
G01X1252693Y225862D02*
X1246493D01*
G01Y235062D02*
X1252693D01*
G01X1246493Y239062D02*
X1252693D01*
G01X1246493Y235862D02*
Y239062D01*
G01X1252693Y235862D02*
X1246493D01*
G01Y243062D02*
X1252693D01*
G01X1246493Y239862D02*
Y243062D01*
G01X1252693Y239862D02*
X1246493D01*
G01X1246578Y243842D02*
Y247042D01*
G01X1252778Y243842D02*
X1246578D01*
G01Y247042D02*
X1252778D01*
G01X1239460Y242732D02*
X1233260D01*
Y245932D01*
X1239460D01*
Y242732D01*
G01Y246732D02*
X1233260D01*
Y249932D01*
X1239460D01*
Y246732D01*
G01X1256938Y269488D02*
G03I-9300J0D01*
G01X1234973Y283708D02*
Y286808D01*
G01X1236583D02*
Y283708D01*
G01Y285258D02*
X1234973D01*
G01X1238035Y284328D02*
X1238265Y283966D01*
X1238571Y283760D01*
X1238916Y283708D01*
X1239223Y283760D01*
X1239530Y284018D01*
X1239721Y284328D01*
X1239760Y284638D01*
X1239683Y285000D01*
X1239415Y285258D01*
X1239146Y285361D01*
X1238801D01*
G01X1239146D02*
X1239376Y285516D01*
X1239568Y285775D01*
X1239645Y286085D01*
X1239568Y286395D01*
X1239376Y286653D01*
X1239031Y286808D01*
X1238686Y286756D01*
X1238341Y286550D01*
G01X1241978Y283708D02*
X1242246Y283760D01*
X1242553Y283915D01*
X1242745Y284173D01*
X1242821Y284535D01*
X1242745Y284896D01*
X1242515Y285206D01*
X1242170Y285361D01*
X1241786D01*
X1241556Y285465D01*
X1241365Y285723D01*
X1241288Y286085D01*
X1241403Y286446D01*
X1241671Y286705D01*
X1241978Y286808D01*
X1242285Y286705D01*
X1242553Y286446D01*
X1242668Y286085D01*
X1242591Y285723D01*
X1242400Y285465D01*
X1242170Y285361D01*
X1241786D01*
X1241441Y285206D01*
X1241211Y284896D01*
X1241135Y284535D01*
X1241211Y284173D01*
X1241403Y283915D01*
X1241710Y283760D01*
X1241978Y283708D01*
G01X1246125Y646760D02*
Y649860D01*
G01X1247735D02*
Y646760D01*
G01Y648310D02*
X1246125D01*
G01X1250030Y646760D02*
X1250298Y646812D01*
X1250605Y646967D01*
X1250797Y647225D01*
X1250873Y647587D01*
X1250797Y647948D01*
X1250567Y648258D01*
X1250222Y648413D01*
X1249838D01*
X1249608Y648517D01*
X1249417Y648775D01*
X1249340Y649137D01*
X1249455Y649498D01*
X1249723Y649757D01*
X1250030Y649860D01*
X1250337Y649757D01*
X1250605Y649498D01*
X1250720Y649137D01*
X1250643Y648775D01*
X1250452Y648517D01*
X1250222Y648413D01*
X1249838D01*
X1249493Y648258D01*
X1249263Y647948D01*
X1249187Y647587D01*
X1249263Y647225D01*
X1249455Y646967D01*
X1249762Y646812D01*
X1250030Y646760D01*
G01X1253130D02*
X1253398Y646812D01*
X1253705Y646967D01*
X1253897Y647225D01*
X1253973Y647587D01*
X1253897Y647948D01*
X1253667Y648258D01*
X1253322Y648413D01*
X1252938D01*
X1252708Y648517D01*
X1252517Y648775D01*
X1252440Y649137D01*
X1252555Y649498D01*
X1252823Y649757D01*
X1253130Y649860D01*
X1253437Y649757D01*
X1253705Y649498D01*
X1253820Y649137D01*
X1253743Y648775D01*
X1253552Y648517D01*
X1253322Y648413D01*
X1252938D01*
X1252593Y648258D01*
X1252363Y647948D01*
X1252287Y647587D01*
X1252363Y647225D01*
X1252555Y646967D01*
X1252862Y646812D01*
X1253130Y646760D01*
G01X1236957Y697211D02*
Y1335007D01*
G01X1242287Y701708D02*
Y697193D01*
X1242600Y696248D01*
X1243227Y695618D01*
X1244010Y695408D01*
X1244793Y695618D01*
X1245420Y696248D01*
X1245733Y697193D01*
Y701708D01*
G01X1248822Y700658D02*
X1249292Y701288D01*
X1249840Y701603D01*
X1250467Y701708D01*
X1251250Y701498D01*
X1251798Y700973D01*
X1251955Y700343D01*
X1251877Y699713D01*
X1251563Y699188D01*
X1249997Y698138D01*
X1249292Y697403D01*
X1248822Y696353D01*
X1248665Y695408D01*
X1251955D01*
G01X1246449Y1656305D02*
X1246679Y1656615D01*
X1246947Y1656770D01*
X1247254Y1656822D01*
X1247637Y1656719D01*
X1247905Y1656460D01*
X1247982Y1656150D01*
X1247944Y1655840D01*
X1247790Y1655582D01*
X1247024Y1655065D01*
X1246679Y1654704D01*
X1246449Y1654187D01*
X1246372Y1653722D01*
X1247982D01*
G01X1239303D02*
Y1656822D01*
X1238843Y1656202D01*
G01Y1653722D02*
X1239763D01*
G01X1233859Y1657834D02*
X1300394D01*
G01X1233859Y1769645D02*
Y1657834D01*
G01X1248963Y1736629D02*
X1247897D01*
Y1739129D01*
X1248963D01*
G01X1248537Y1737921D02*
X1247897D01*
G01X1250043Y1736629D02*
Y1739129D01*
X1250577D01*
X1250790Y1739004D01*
X1250950Y1738837D01*
X1251083Y1738587D01*
X1251190Y1738296D01*
X1251217Y1737879D01*
X1251190Y1737462D01*
X1251083Y1737171D01*
X1250950Y1736921D01*
X1250790Y1736754D01*
X1250577Y1736629D01*
X1250043D01*
G01X1252990Y1737879D02*
X1253523D01*
Y1737129D01*
X1253363Y1736879D01*
X1253177Y1736712D01*
X1252910Y1736629D01*
X1252643Y1736712D01*
X1252457Y1736879D01*
X1252297Y1737129D01*
X1252190Y1737421D01*
X1252137Y1737754D01*
Y1738046D01*
X1252190Y1738296D01*
X1252297Y1738587D01*
X1252457Y1738837D01*
X1252617Y1739004D01*
X1252830Y1739129D01*
X1253017D01*
X1253230Y1739046D01*
X1253390Y1738879D01*
G01X1255563Y1736629D02*
X1254497D01*
Y1739129D01*
X1255563D01*
G01X1255137Y1737921D02*
X1254497D01*
G01X1259430Y1736629D02*
X1259217Y1736671D01*
X1259030Y1736837D01*
X1258870Y1737087D01*
X1258763Y1737379D01*
X1258710Y1737712D01*
Y1738046D01*
X1258763Y1738379D01*
X1258870Y1738671D01*
X1259030Y1738921D01*
X1259217Y1739087D01*
X1259430Y1739129D01*
X1259643Y1739087D01*
X1259830Y1738921D01*
X1259990Y1738671D01*
X1260097Y1738379D01*
X1260150Y1738046D01*
Y1737712D01*
X1260097Y1737379D01*
X1259990Y1737087D01*
X1259830Y1736837D01*
X1259643Y1736671D01*
X1259430Y1736629D01*
G01X1261123D02*
Y1739129D01*
X1262137D01*
G01X1261763Y1737921D02*
X1261123D01*
G01X1265443Y1736629D02*
Y1739129D01*
X1265977D01*
X1266190Y1739004D01*
X1266350Y1738837D01*
X1266483Y1738587D01*
X1266590Y1738296D01*
X1266617Y1737879D01*
X1266590Y1737462D01*
X1266483Y1737171D01*
X1266350Y1736921D01*
X1266190Y1736754D01*
X1265977Y1736629D01*
X1265443D01*
G01X1267563D02*
X1268230Y1739129D01*
X1268897Y1736629D01*
G01X1268657Y1737504D02*
X1267803D01*
G01X1269843Y1739129D02*
Y1737337D01*
X1269950Y1736962D01*
X1270163Y1736712D01*
X1270430Y1736629D01*
X1270697Y1736712D01*
X1270910Y1736962D01*
X1271017Y1737337D01*
Y1739129D01*
G01X1272790Y1737879D02*
X1273323D01*
Y1737129D01*
X1273163Y1736879D01*
X1272977Y1736712D01*
X1272710Y1736629D01*
X1272443Y1736712D01*
X1272257Y1736879D01*
X1272097Y1737129D01*
X1271990Y1737421D01*
X1271937Y1737754D01*
Y1738046D01*
X1271990Y1738296D01*
X1272097Y1738587D01*
X1272257Y1738837D01*
X1272417Y1739004D01*
X1272630Y1739129D01*
X1272817D01*
X1273030Y1739046D01*
X1273190Y1738879D01*
G01X1274270Y1736629D02*
Y1739129D01*
G01X1275390D02*
Y1736629D01*
G01Y1737879D02*
X1274270D01*
G01X1277030Y1739129D02*
Y1736629D01*
G01X1276417Y1739129D02*
X1277643D01*
G01X1279763Y1736629D02*
X1278697D01*
Y1739129D01*
X1279763D01*
G01X1279337Y1737921D02*
X1278697D01*
G01X1280897Y1736629D02*
Y1739129D01*
X1281563D01*
X1281777Y1739004D01*
X1281910Y1738837D01*
X1281963Y1738504D01*
X1281910Y1738171D01*
X1281750Y1737962D01*
X1281563Y1737837D01*
X1280897D01*
G01X1281563D02*
X1281963Y1736629D01*
G01X1286417Y1738921D02*
X1286257Y1739046D01*
X1286070Y1739129D01*
X1285857D01*
X1285617Y1739004D01*
X1285430Y1738796D01*
X1285297Y1738546D01*
X1285190Y1738129D01*
X1285163Y1737754D01*
X1285217Y1737379D01*
X1285297Y1737129D01*
X1285457Y1736879D01*
X1285643Y1736712D01*
X1285830Y1736629D01*
X1286017D01*
X1286203Y1736712D01*
X1286363Y1736837D01*
X1286497Y1737004D01*
G01X1287363Y1736629D02*
X1288030Y1739129D01*
X1288697Y1736629D01*
G01X1288457Y1737504D02*
X1287603D01*
G01X1289697Y1736629D02*
Y1739129D01*
X1290363D01*
X1290577Y1739004D01*
X1290710Y1738837D01*
X1290763Y1738504D01*
X1290710Y1738171D01*
X1290550Y1737962D01*
X1290363Y1737837D01*
X1289697D01*
G01X1290363D02*
X1290763Y1736629D01*
G01X1291843D02*
Y1739129D01*
X1292377D01*
X1292590Y1739004D01*
X1292750Y1738837D01*
X1292883Y1738587D01*
X1292990Y1738296D01*
X1293017Y1737879D01*
X1292990Y1737462D01*
X1292883Y1737171D01*
X1292750Y1736921D01*
X1292590Y1736754D01*
X1292377Y1736629D01*
X1291843D01*
G01X1245880Y1736412D02*
X1246780Y1737312D01*
G01X1240880Y1736412D02*
X1245880D01*
G01X1240880Y1739812D02*
Y1736412D01*
G01X1242880Y1737812D02*
X1240880Y1739812D01*
G01X1238880Y1737812D02*
X1242880D01*
G01X1240880Y1739812D02*
X1238880Y1737812D01*
G01X1233859Y1740118D02*
X1300394D01*
G01Y1769645D02*
X1233859D01*
G01X1262347Y50722D02*
Y57322D01*
G01X1275347Y50722D02*
X1262347D01*
G01Y57322D02*
X1275347D01*
G01Y59122D02*
X1262347D01*
G01Y65722D02*
X1275347D01*
G01X1262347Y59122D02*
Y65722D01*
G01X1261440Y102022D02*
Y108222D01*
G01X1264640Y102022D02*
X1261440D01*
G01X1264640Y108222D02*
Y102022D01*
G01X1256939Y101827D02*
Y108027D01*
G01X1260139Y101827D02*
X1256939D01*
G01X1260139Y108027D02*
Y101827D01*
G01X1266227Y112069D02*
Y113464D01*
X1265460Y115169D01*
G01X1266994D02*
X1266227Y113464D01*
G01X1269327Y112069D02*
Y115169D01*
X1268867Y114549D01*
G01Y112069D02*
X1269787D01*
G01X1261440Y108222D02*
X1264640D01*
G01X1256939Y108027D02*
X1260139D01*
G01X1264798Y124704D02*
X1275404Y114098D01*
G01X1270596Y130502D02*
X1264798Y124704D01*
G01X1252693Y203162D02*
Y199962D01*
G01Y213362D02*
Y210162D01*
G01Y206962D02*
Y203762D01*
G01X1257493Y215862D02*
Y219062D01*
G01X1263693Y215862D02*
X1257493D01*
G01X1263693Y219062D02*
Y215862D01*
G01X1252693Y217362D02*
Y214162D01*
G01X1264993Y231862D02*
Y235062D01*
G01X1271193Y231862D02*
X1264993D01*
G01X1257493D02*
Y235062D01*
G01X1263693Y231862D02*
X1257493D01*
G01X1263693Y235062D02*
Y231862D01*
G01X1252693Y235062D02*
Y231862D01*
G01X1257493Y219062D02*
X1263693D01*
G01X1257493Y219862D02*
Y223062D01*
G01X1263693Y219862D02*
X1257493D01*
G01X1263693Y223062D02*
Y219862D01*
G01X1257493Y223062D02*
X1263693D01*
G01X1252693Y221262D02*
Y218062D01*
G01X1257493Y227862D02*
Y231062D01*
G01X1263693Y227862D02*
X1257493D01*
G01X1263693Y231062D02*
Y227862D01*
G01X1257493Y231062D02*
X1263693D01*
G01X1257493Y223862D02*
Y227062D01*
G01X1263693Y223862D02*
X1257493D01*
G01X1263693Y227062D02*
Y223862D01*
G01X1257493Y227062D02*
X1263693D01*
G01X1252693Y225062D02*
Y221862D01*
G01Y229062D02*
Y225862D01*
G01X1264993Y235062D02*
X1271193D01*
G01X1257493D02*
X1263693D01*
G01X1257493Y241962D02*
Y245162D01*
G01X1263693Y241962D02*
X1257493D01*
G01X1263693Y245162D02*
Y241962D01*
G01X1257493Y245162D02*
X1263693D01*
G01X1257493Y237062D02*
Y240262D01*
G01X1263693Y237062D02*
X1257493D01*
G01X1263693Y240262D02*
Y237062D01*
G01X1257493Y240262D02*
X1263693D01*
G01X1257493Y245962D02*
Y249162D01*
G01X1263693Y245962D02*
X1257493D01*
G01X1263693Y249162D02*
Y245962D01*
G01X1257493Y249162D02*
X1263693D01*
G01X1252693Y239062D02*
Y235862D01*
G01Y243062D02*
Y239862D01*
G01X1252778Y247042D02*
Y243842D01*
G01X1257693Y249962D02*
Y253162D01*
G01X1263893Y249962D02*
X1257693D01*
G01X1263893Y253162D02*
Y249962D01*
G01X1257693Y253162D02*
X1263893D01*
G01X1264750Y298416D02*
X1261550D01*
G01X1264750Y304616D02*
Y298416D01*
G01X1261550D02*
Y304616D01*
G01X1257550Y298416D02*
Y304616D01*
G01X1260750Y298416D02*
X1257550D01*
G01X1260750Y304616D02*
Y298416D01*
G01X1253550D02*
Y304616D01*
G01X1256750Y298416D02*
X1253550D01*
G01X1256750Y304616D02*
Y298416D01*
G01X1252750D02*
X1249550D01*
G01X1252750Y304616D02*
Y298416D01*
G01X1249550D02*
Y304616D01*
G01X1261550D02*
X1264750D01*
G01X1257550D02*
X1260750D01*
G01X1253550D02*
X1256750D01*
G01X1249550D02*
X1252750D01*
G01X1261845Y1007862D02*
Y1010962D01*
G01X1263455D02*
Y1007862D01*
G01Y1009412D02*
X1261845D01*
G01X1265022Y1010445D02*
X1265252Y1010755D01*
X1265520Y1010910D01*
X1265827Y1010962D01*
X1266210Y1010859D01*
X1266478Y1010600D01*
X1266555Y1010290D01*
X1266517Y1009980D01*
X1266363Y1009722D01*
X1265597Y1009205D01*
X1265252Y1008844D01*
X1265022Y1008327D01*
X1264945Y1007862D01*
X1266555D01*
G01X1268007Y1008327D02*
X1268237Y1008069D01*
X1268505Y1007914D01*
X1268850Y1007862D01*
X1269195Y1007965D01*
X1269463Y1008172D01*
X1269655Y1008534D01*
X1269693Y1008947D01*
X1269617Y1009360D01*
X1269425Y1009619D01*
X1269157Y1009825D01*
X1268888Y1009877D01*
X1268620Y1009825D01*
X1268275Y1009619D01*
X1268390Y1010962D01*
X1269425D01*
G01X1252373Y1312852D02*
Y1315952D01*
X1253293D01*
X1253600Y1315797D01*
X1253830Y1315435D01*
X1253907Y1315022D01*
X1253830Y1314609D01*
X1253638Y1314299D01*
X1253293Y1314144D01*
X1252373D01*
G01X1255473Y1315952D02*
Y1312852D01*
X1257007D01*
G01X1259340D02*
Y1315952D01*
X1258880Y1315332D01*
G01Y1312852D02*
X1259800D01*
G01X1262440Y1315952D02*
X1262133Y1315849D01*
X1261903Y1315590D01*
X1261750Y1315280D01*
X1261635Y1314867D01*
X1261597Y1314402D01*
X1261635Y1313937D01*
X1261750Y1313524D01*
X1261903Y1313214D01*
X1262133Y1312955D01*
X1262440Y1312852D01*
X1262747Y1312955D01*
X1262977Y1313214D01*
X1263130Y1313524D01*
X1263245Y1313937D01*
X1263283Y1314402D01*
X1263245Y1314867D01*
X1263130Y1315280D01*
X1262977Y1315590D01*
X1262747Y1315849D01*
X1262440Y1315952D01*
G01X1264697Y1313317D02*
X1264927Y1313059D01*
X1265195Y1312904D01*
X1265540Y1312852D01*
X1265885Y1312955D01*
X1266153Y1313162D01*
X1266345Y1313524D01*
X1266383Y1313937D01*
X1266307Y1314350D01*
X1266115Y1314609D01*
X1265847Y1314815D01*
X1265578Y1314867D01*
X1265310Y1314815D01*
X1264965Y1314609D01*
X1265080Y1315952D01*
X1266115D01*
G01X1250810Y1318774D02*
Y1344364D01*
G01X1254805Y1318774D02*
X1250810D01*
G01X1252213Y1353122D02*
Y1356222D01*
X1253133D01*
X1253440Y1356067D01*
X1253670Y1355705D01*
X1253747Y1355292D01*
X1253670Y1354879D01*
X1253478Y1354569D01*
X1253133Y1354414D01*
X1252213D01*
G01X1255237Y1356222D02*
Y1354000D01*
X1255390Y1353535D01*
X1255697Y1353225D01*
X1256080Y1353122D01*
X1256463Y1353225D01*
X1256770Y1353535D01*
X1256923Y1354000D01*
Y1356222D01*
G01X1259103Y1353122D02*
X1259180Y1353794D01*
X1259295Y1354362D01*
X1259448Y1354879D01*
X1259640Y1355447D01*
X1259947Y1356222D01*
X1258413D01*
G01X1261130Y1352089D02*
X1263430D01*
G01X1264613Y1353122D02*
Y1356222D01*
X1265533D01*
X1265840Y1356067D01*
X1266070Y1355705D01*
X1266147Y1355292D01*
X1266070Y1354879D01*
X1265878Y1354569D01*
X1265533Y1354414D01*
X1264613D01*
G01X1268480Y1356222D02*
X1268173Y1356119D01*
X1267943Y1355860D01*
X1267790Y1355550D01*
X1267675Y1355137D01*
X1267637Y1354672D01*
X1267675Y1354207D01*
X1267790Y1353794D01*
X1267943Y1353484D01*
X1268173Y1353225D01*
X1268480Y1353122D01*
X1268787Y1353225D01*
X1269017Y1353484D01*
X1269170Y1353794D01*
X1269285Y1354207D01*
X1269323Y1354672D01*
X1269285Y1355137D01*
X1269170Y1355550D01*
X1269017Y1355860D01*
X1268787Y1356119D01*
X1268480Y1356222D01*
G01X1270430Y1352089D02*
X1272730D01*
G01X1274603Y1353122D02*
X1274680Y1353794D01*
X1274795Y1354362D01*
X1274948Y1354879D01*
X1275140Y1355447D01*
X1275447Y1356222D01*
X1273913D01*
G01X1250810Y1344364D02*
X1254805D01*
G01X1263385Y1653722D02*
Y1656822D01*
X1261967Y1654600D01*
X1263883D01*
G01X1254208Y1654342D02*
X1254438Y1653980D01*
X1254744Y1653774D01*
X1255089Y1653722D01*
X1255396Y1653774D01*
X1255703Y1654032D01*
X1255894Y1654342D01*
X1255933Y1654652D01*
X1255856Y1655014D01*
X1255588Y1655272D01*
X1255319Y1655375D01*
X1254974D01*
G01X1255319D02*
X1255549Y1655530D01*
X1255741Y1655789D01*
X1255818Y1656099D01*
X1255741Y1656409D01*
X1255549Y1656667D01*
X1255204Y1656822D01*
X1254859Y1656770D01*
X1254514Y1656564D01*
G01X1275347Y57322D02*
Y50722D01*
G01Y65722D02*
Y59122D01*
G01X1272920Y85962D02*
X1276120D01*
G01X1272920Y79762D02*
Y85962D01*
G01X1276120Y79762D02*
X1272920D01*
G01X1276120Y85962D02*
Y79762D01*
G01X1265654Y86972D02*
Y90172D01*
G01X1271854Y86972D02*
X1265654D01*
G01X1271854Y90172D02*
Y86972D01*
G01X1280313Y83999D02*
X1283513D01*
G01X1280313Y77799D02*
Y83999D01*
G01X1283513Y77799D02*
X1280313D01*
G01X1283540Y86172D02*
X1280340D01*
G01D02*
Y92372D01*
G01X1277191Y101328D02*
Y104528D01*
G01X1283391Y101328D02*
X1277191D01*
G01X1271854Y94324D02*
Y91124D01*
G01X1265654Y94324D02*
X1271854D01*
G01X1265654Y91124D02*
Y94324D01*
G01X1271854Y91124D02*
X1265654D01*
G01Y90172D02*
X1271854D01*
G01X1268922Y102064D02*
X1265722D01*
G01X1268922Y108264D02*
Y102064D01*
G01X1265722D02*
Y108264D01*
G01X1265654Y95168D02*
Y98368D01*
G01X1271854Y95168D02*
X1265654D01*
G01X1271854Y98368D02*
Y95168D01*
G01X1265654Y98368D02*
X1271854D01*
G01X1277191Y97228D02*
Y100428D01*
G01X1283391Y97228D02*
X1277191D01*
G01Y100428D02*
X1283391D01*
G01X1280340Y92372D02*
X1283540D01*
G01X1281202Y119896D02*
X1270596Y130502D01*
G01X1275404Y114098D02*
X1281202Y119896D01*
G01X1277191Y104528D02*
X1283391D01*
G01X1276464Y105612D02*
X1273264D01*
G01X1276464Y111812D02*
Y105612D01*
G01X1273264Y111812D02*
X1276464D01*
G01X1273264Y105612D02*
Y111812D01*
G01X1265722Y108264D02*
X1268922D01*
G01X1284444Y125467D02*
X1281191Y122214D01*
G01X1277231Y132680D02*
X1284444Y125467D01*
G01X1273978Y129427D02*
X1277231Y132680D01*
G01X1281191Y122214D02*
X1273978Y129427D01*
G01X1281414Y129754D02*
X1283676Y132016D01*
G01X1285798Y125370D02*
X1281414Y129754D01*
G01X1270154Y136585D02*
X1272416Y134323D01*
G01X1265770Y132201D02*
X1270154Y136585D01*
G01X1268032Y129939D02*
X1265770Y132201D01*
G01X1272416Y134323D02*
X1268032Y129939D01*
G01X1282523Y133501D02*
X1280261Y131239D01*
G01X1278139Y137885D02*
X1282523Y133501D01*
G01X1275877Y135623D02*
X1278139Y137885D01*
G01X1280261Y131239D02*
X1275877Y135623D01*
G01X1273617Y237678D02*
Y235456D01*
X1273770Y234991D01*
X1274077Y234681D01*
X1274460Y234578D01*
X1274843Y234681D01*
X1275150Y234991D01*
X1275303Y235456D01*
Y237678D01*
G01X1278020Y234578D02*
Y237678D01*
X1276602Y235456D01*
X1278518D01*
G01X1271193Y235062D02*
Y231862D01*
G01X1268750Y298416D02*
X1265550D01*
G01X1268750Y304616D02*
Y298416D01*
G01X1265550D02*
Y304616D01*
G01X1269550Y298416D02*
Y304616D01*
G01X1272750Y298416D02*
X1269550D01*
G01X1272750Y304616D02*
Y298416D01*
G01X1265550Y304616D02*
X1268750D01*
G01X1269550D02*
X1272750D01*
G01X1292864Y991220D02*
G03I-9950J0D01*
G01X1269363Y1293422D02*
Y1296522D01*
X1270283D01*
X1270590Y1296367D01*
X1270820Y1296005D01*
X1270897Y1295592D01*
X1270820Y1295179D01*
X1270628Y1294869D01*
X1270283Y1294714D01*
X1269363D01*
G01X1272463Y1296522D02*
Y1293422D01*
X1273997D01*
G01X1276330D02*
X1276598Y1293474D01*
X1276905Y1293629D01*
X1277097Y1293887D01*
X1277173Y1294249D01*
X1277097Y1294610D01*
X1276867Y1294920D01*
X1276522Y1295075D01*
X1276138D01*
X1275908Y1295179D01*
X1275717Y1295437D01*
X1275640Y1295799D01*
X1275755Y1296160D01*
X1276023Y1296419D01*
X1276330Y1296522D01*
X1276637Y1296419D01*
X1276905Y1296160D01*
X1277020Y1295799D01*
X1276943Y1295437D01*
X1276752Y1295179D01*
X1276522Y1295075D01*
X1276138D01*
X1275793Y1294920D01*
X1275563Y1294610D01*
X1275487Y1294249D01*
X1275563Y1293887D01*
X1275755Y1293629D01*
X1276062Y1293474D01*
X1276330Y1293422D01*
G01X1279019Y1291806D02*
Y1335114D01*
G01X1284360Y1291806D02*
X1279019D01*
G01X1276400Y1328362D02*
Y1318774D01*
G01D02*
X1272405D01*
G01X1276400Y1332362D02*
Y1328362D01*
G01Y1344364D02*
Y1332362D01*
G01X1279019Y1335114D02*
X1284360D01*
G01X1272405Y1344364D02*
X1276400D01*
G01X1278212Y1352652D02*
X1281412D01*
G01X1278212Y1346452D02*
Y1352652D01*
G01X1281412Y1346452D02*
X1278212D01*
G01X1281412Y1352652D02*
Y1346452D01*
G01X1281680Y1371373D02*
X1284880D01*
G01X1281680Y1365173D02*
Y1371373D01*
G01X1284880Y1365173D02*
X1281680D01*
G01X1281434Y1356989D02*
X1278234D01*
G01X1281434Y1363189D02*
Y1356989D01*
G01X1278234Y1363189D02*
X1281434D01*
G01X1278234Y1356989D02*
Y1363189D01*
G01X1278645Y1623775D02*
X1279565Y1622992D01*
X1280600Y1622522D01*
X1281520D01*
X1282440Y1622992D01*
X1283130Y1623775D01*
X1283475Y1624872D01*
X1283245Y1625969D01*
X1282670Y1626909D01*
X1281635Y1627535D01*
X1280255Y1627849D01*
X1279450Y1628475D01*
X1279105Y1629572D01*
X1279335Y1630669D01*
X1279910Y1631452D01*
X1280715Y1631922D01*
X1281520D01*
X1282325Y1631609D01*
X1283015Y1630825D01*
G01X1286810Y1631922D02*
X1288420Y1622522D01*
X1290260Y1631922D01*
X1292100Y1622522D01*
X1293710Y1631922D01*
G01X1300380Y1627535D02*
X1300840Y1628005D01*
X1301185Y1628788D01*
X1301415Y1629885D01*
X1301185Y1630825D01*
X1300725Y1631452D01*
X1299920Y1631922D01*
X1296815D01*
Y1622522D01*
X1300610D01*
X1301415Y1623149D01*
X1301875Y1624089D01*
X1302105Y1625185D01*
X1301875Y1626282D01*
X1301185Y1627222D01*
X1300380Y1627535D01*
X1296815D01*
G01X1305210Y1619389D02*
X1312110D01*
G01X1320390Y1631139D02*
X1319700Y1631609D01*
X1318895Y1631922D01*
X1317975D01*
X1316940Y1631452D01*
X1316135Y1630669D01*
X1315560Y1629729D01*
X1315100Y1628162D01*
X1314985Y1626752D01*
X1315215Y1625342D01*
X1315560Y1624402D01*
X1316250Y1623462D01*
X1317055Y1622835D01*
X1317860Y1622522D01*
X1318665D01*
X1319470Y1622835D01*
X1320160Y1623305D01*
X1320735Y1623932D01*
G01X1277945Y1655014D02*
X1278213Y1655375D01*
X1278443Y1655582D01*
X1278750Y1655685D01*
X1279018Y1655582D01*
X1279210Y1655375D01*
X1279363Y1655065D01*
X1279401Y1654704D01*
X1279363Y1654394D01*
X1279210Y1654084D01*
X1278980Y1653825D01*
X1278711Y1653722D01*
X1278405Y1653825D01*
X1278136Y1654135D01*
X1277983Y1654600D01*
X1277945Y1655117D01*
X1278021Y1655789D01*
X1278136Y1656150D01*
X1278328Y1656512D01*
X1278596Y1656770D01*
X1278865Y1656822D01*
X1279133Y1656719D01*
X1279325Y1656460D01*
G01X1269956Y1654187D02*
X1270186Y1653929D01*
X1270454Y1653774D01*
X1270799Y1653722D01*
X1271144Y1653825D01*
X1271412Y1654032D01*
X1271604Y1654394D01*
X1271642Y1654807D01*
X1271566Y1655220D01*
X1271374Y1655479D01*
X1271106Y1655685D01*
X1270837Y1655737D01*
X1270569Y1655685D01*
X1270224Y1655479D01*
X1270339Y1656822D01*
X1271374D01*
G01X1291422Y-29811D02*
Y-13211D01*
X1301022D01*
Y-29811D01*
X1291422D01*
G01Y-9811D02*
Y6789D01*
X1301022D01*
Y-9811D01*
X1291422D01*
G01Y10189D02*
Y26789D01*
X1301022D01*
Y10189D01*
X1291422D01*
G01X1282508Y51121D02*
Y57121D01*
G01X1294508Y51121D02*
X1282508D01*
G01X1294508Y57121D02*
Y51121D01*
G01X1297042Y50731D02*
Y59393D01*
G01X1308066Y50731D02*
X1297042D01*
G01X1282508Y57121D02*
X1294508D01*
G01X1282508Y65321D02*
X1294508D01*
G01X1282508Y59321D02*
Y65321D01*
G01X1294508Y59321D02*
X1282508D01*
G01X1294508Y65321D02*
Y59321D01*
G01X1308066Y59393D02*
X1297042D01*
G01X1290223Y86169D02*
Y92369D01*
G01X1293423Y86169D02*
X1290223D01*
G01X1293423Y92369D02*
Y86169D01*
G01X1286313Y86119D02*
Y92319D01*
G01X1289513Y86119D02*
X1286313D01*
G01X1289513Y92319D02*
Y86119D01*
G01X1294565Y79569D02*
Y82769D01*
G01X1300765Y79569D02*
X1294565D01*
G01Y82769D02*
X1300765D01*
G01X1295911Y86738D02*
X1302111D01*
G01X1295911Y83538D02*
Y86738D01*
G01X1302111Y83538D02*
X1295911D01*
G01X1287613Y77799D02*
X1284413D01*
G01X1287613Y83999D02*
Y77799D01*
G01X1284413Y83999D02*
X1287613D01*
G01X1284413Y77799D02*
Y83999D01*
G01X1283513D02*
Y77799D01*
G01X1283540Y92372D02*
Y86172D01*
G01X1283391Y104528D02*
Y101328D01*
G01X1290223Y92369D02*
X1293423D01*
G01X1286313Y92319D02*
X1289513D01*
G01X1283391Y100428D02*
Y97228D01*
G01X1294167Y96816D02*
X1297367D01*
G01X1294167Y90616D02*
Y96816D01*
G01X1297367Y90616D02*
X1294167D01*
G01X1297367Y96816D02*
Y90616D01*
G01X1296807Y103367D02*
Y109567D01*
G01X1300007Y103367D02*
X1296807D01*
G01Y109567D02*
X1300007D01*
G01X1288060Y127632D02*
X1285798Y125370D01*
G01X1283676Y132016D02*
X1288060Y127632D01*
G01X1285247Y133591D02*
X1289631Y137975D01*
G01D02*
X1291893Y135713D01*
G01D02*
X1287509Y131329D01*
G01D02*
X1285247Y133591D01*
G01X1283070Y145473D02*
Y236025D01*
G01X1369684Y145473D02*
X1283070D01*
G01Y236025D02*
X1303120D01*
G01X1298942Y286307D02*
X1295742D01*
G01Y292507D02*
X1298942D01*
G01X1295742Y286307D02*
Y292507D01*
G01X1294998Y286307D02*
X1291798D01*
G01X1294998Y292507D02*
Y286307D01*
G01X1291798Y292507D02*
X1294998D01*
G01X1291798Y286307D02*
Y292507D01*
G01X1293337Y754065D02*
X1296537D01*
G01X1293337Y747865D02*
Y754065D01*
G01X1296537Y747865D02*
X1293337D01*
G01X1296537Y754065D02*
Y747865D01*
G01X1292037D02*
X1288837D01*
G01X1292037Y754065D02*
Y747865D01*
G01X1288837Y754065D02*
X1292037D01*
G01X1288837Y747865D02*
Y754065D01*
G01X1296734Y835708D02*
Y850235D01*
G01X1296733Y835708D02*
Y850236D01*
G01X1302639Y829802D02*
X1296734Y835708D01*
G01X1302639Y829803D02*
X1296733Y835708D01*
G01X1538839Y853424D02*
G03X1536891Y851512I18J-1967D01*
G01Y829803D01*
X1302638D01*
X1296733Y835708D01*
Y851475D01*
G01D02*
G03X1294764Y853424I-1968J-19D01*
G01X1289843D01*
Y861299D01*
G01X1296734Y851456D02*
G03X1294765Y853424I-1969J-1D01*
G01X1296734Y850235D02*
Y851456D01*
G01X1296733D02*
G03X1294764Y853425I-1969J0D01*
G01X1296733Y850236D02*
Y851456D01*
G01Y861299D02*
Y1136896D01*
G01X1289844Y853424D02*
X1294765D01*
G01X1289843Y853425D02*
X1294764D01*
G01X1289844Y861298D02*
Y853424D01*
G01X1289843Y869960D02*
Y853425D01*
G01X1300671Y861298D02*
X1296733Y861299D01*
G01Y869960D02*
X1289843D01*
G01X1296734Y1116456D02*
Y1110157D01*
G01X1296733Y1116456D02*
Y1110157D01*
G01X1296734D02*
X1300671D01*
G01X1296733D02*
X1300670D01*
G01X1304804D02*
X1296734D01*
G01X1304804D02*
X1296733D01*
G01X1300671Y1116456D02*
X1296734D01*
G01X1300670D02*
X1296733D01*
G01X1289843Y1139645D02*
Y1145944D01*
G01Y1138857D02*
Y1139645D01*
G01X1289844D02*
Y1145944D01*
G01X1294765Y1138857D02*
X1289844D01*
G01D02*
Y1139645D01*
G01X1294764Y1138857D02*
X1289843D01*
G01X1296733Y1136896D02*
G03X1294764Y1138857I-1968J-7D01*
G01X1289843D01*
Y1146731D01*
X1294781D01*
G01X1296734Y1136889D02*
G03X1294765Y1138857I-1969J-1D01*
G01X1296733Y1136890D02*
G03X1294764Y1138857I-1968J-1D01*
G01X1296734Y1136889D02*
Y1132204D01*
G01X1296733Y1136890D02*
Y1132205D01*
G01X1296734Y1132204D02*
X1300671D01*
G01X1296733Y1132205D02*
X1300670D01*
G01X1294765Y1146731D02*
G03X1296734Y1148700I0J1969D01*
G01X1289844Y1146731D02*
X1294765D01*
G01X1289843Y1145944D02*
Y1146731D01*
G01X1289844Y1145944D02*
Y1146731D01*
G01X1294764D02*
G03X1296733Y1148701I0J1969D01*
G01X1296734Y1152637D02*
Y1148700D01*
G01X1296733Y1152638D02*
Y1148701D01*
G01X1289843Y1146731D02*
X1294764D01*
G01X1367600Y1152637D02*
X1296734D01*
G01X1367600Y1152638D02*
X1296733D01*
G01X1294781Y1146731D02*
G03X1296733Y1148694I-17J1969D01*
G01Y1152637D01*
X1536891D01*
Y1148692D01*
G01X1284043Y1338492D02*
Y1341092D01*
G01X1284836Y1338492D02*
X1284043D01*
G01Y1347703D02*
Y1349401D01*
G01Y1362114D02*
X1285051D01*
G01X1284043Y1360260D02*
Y1362114D01*
G01X1284880Y1371373D02*
Y1365173D01*
G01X1298475Y1365327D02*
X1295275D01*
G01Y1371527D02*
X1298475D01*
G01X1295275Y1365327D02*
Y1371527D01*
G01X1286807Y1368443D02*
Y1371643D01*
G01X1293007Y1368443D02*
X1286807D01*
G01X1293007Y1371643D02*
Y1368443D01*
G01X1286807Y1371643D02*
X1293007D01*
G01X1284627Y1410667D02*
Y1413767D01*
G01X1286237D02*
Y1410667D01*
G01Y1412217D02*
X1284627D01*
G01X1288992Y1410667D02*
Y1413767D01*
X1287574Y1411545D01*
X1289490D01*
G01X1290789Y1411132D02*
X1291019Y1410874D01*
X1291287Y1410719D01*
X1291632Y1410667D01*
X1291977Y1410770D01*
X1292245Y1410977D01*
X1292437Y1411339D01*
X1292475Y1411752D01*
X1292399Y1412165D01*
X1292207Y1412424D01*
X1291939Y1412630D01*
X1291670Y1412682D01*
X1291402Y1412630D01*
X1291057Y1412424D01*
X1291172Y1413767D01*
X1292207D01*
G01X1288863Y1641752D02*
X1289055Y1641442D01*
X1289285Y1641235D01*
X1289553Y1641132D01*
X1289860Y1641235D01*
X1290090Y1641442D01*
X1290320Y1641752D01*
X1290397Y1642165D01*
Y1644232D01*
G01X1292730Y1641132D02*
Y1644232D01*
X1292270Y1643612D01*
G01Y1641132D02*
X1293190D01*
G01X1295830Y1644232D02*
X1295523Y1644129D01*
X1295293Y1643870D01*
X1295140Y1643560D01*
X1295025Y1643147D01*
X1294987Y1642682D01*
X1295025Y1642217D01*
X1295140Y1641804D01*
X1295293Y1641494D01*
X1295523Y1641235D01*
X1295830Y1641132D01*
X1296137Y1641235D01*
X1296367Y1641494D01*
X1296520Y1641804D01*
X1296635Y1642217D01*
X1296673Y1642682D01*
X1296635Y1643147D01*
X1296520Y1643560D01*
X1296367Y1643870D01*
X1296137Y1644129D01*
X1295830Y1644232D01*
G01X1298930Y1641132D02*
X1299198Y1641184D01*
X1299505Y1641339D01*
X1299697Y1641597D01*
X1299773Y1641959D01*
X1299697Y1642320D01*
X1299467Y1642630D01*
X1299122Y1642785D01*
X1298738D01*
X1298508Y1642889D01*
X1298317Y1643147D01*
X1298240Y1643509D01*
X1298355Y1643870D01*
X1298623Y1644129D01*
X1298930Y1644232D01*
X1299237Y1644129D01*
X1299505Y1643870D01*
X1299620Y1643509D01*
X1299543Y1643147D01*
X1299352Y1642889D01*
X1299122Y1642785D01*
X1298738D01*
X1298393Y1642630D01*
X1298163Y1642320D01*
X1298087Y1641959D01*
X1298163Y1641597D01*
X1298355Y1641339D01*
X1298662Y1641184D01*
X1298930Y1641132D01*
G01X1288977Y1646023D02*
Y1781456D01*
G01X1379134Y1646023D02*
X1288977D01*
G01X1286470Y1653722D02*
X1286547Y1654394D01*
X1286662Y1654962D01*
X1286815Y1655479D01*
X1287007Y1656047D01*
X1287314Y1656822D01*
X1285780D01*
G01X1294421Y1653722D02*
X1294689Y1653774D01*
X1294996Y1653929D01*
X1295188Y1654187D01*
X1295264Y1654549D01*
X1295188Y1654910D01*
X1294958Y1655220D01*
X1294613Y1655375D01*
X1294229D01*
X1293999Y1655479D01*
X1293808Y1655737D01*
X1293731Y1656099D01*
X1293846Y1656460D01*
X1294114Y1656719D01*
X1294421Y1656822D01*
X1294728Y1656719D01*
X1294996Y1656460D01*
X1295111Y1656099D01*
X1295034Y1655737D01*
X1294843Y1655479D01*
X1294613Y1655375D01*
X1294229D01*
X1293884Y1655220D01*
X1293654Y1654910D01*
X1293578Y1654549D01*
X1293654Y1654187D01*
X1293846Y1653929D01*
X1294153Y1653774D01*
X1294421Y1653722D01*
G01X1297529Y1670715D02*
Y1673815D01*
X1299293Y1670715D01*
Y1673815D01*
G01X1297414Y1675439D02*
Y1678539D01*
X1298411Y1675956D01*
X1299408Y1678539D01*
Y1675439D01*
G01X1297644Y1683263D02*
Y1680163D01*
X1299178D01*
G01X1297951Y1697437D02*
X1298871D01*
G01X1298411D02*
Y1694337D01*
G01X1297951D02*
X1298871D01*
G01X1297568Y1684888D02*
Y1687988D01*
G01X1299024D02*
X1297568Y1686076D01*
G01X1299254Y1684888D02*
X1298219Y1686955D01*
G01X1297644Y1690232D02*
X1297836Y1689922D01*
X1298066Y1689715D01*
X1298334Y1689612D01*
X1298641Y1689715D01*
X1298871Y1689922D01*
X1299101Y1690232D01*
X1299178Y1690645D01*
Y1692712D01*
G01X1297606Y1699061D02*
Y1702161D01*
G01X1299216D02*
Y1699061D01*
G01Y1700611D02*
X1297606D01*
G01X1298641Y1705336D02*
X1299408D01*
Y1704406D01*
X1299178Y1704096D01*
X1298909Y1703889D01*
X1298526Y1703786D01*
X1298143Y1703889D01*
X1297874Y1704096D01*
X1297644Y1704406D01*
X1297491Y1704768D01*
X1297414Y1705181D01*
Y1705543D01*
X1297491Y1705853D01*
X1297644Y1706214D01*
X1297874Y1706524D01*
X1298104Y1706731D01*
X1298411Y1706886D01*
X1298679D01*
X1298986Y1706783D01*
X1299216Y1706576D01*
G01X1297683Y1708510D02*
Y1711610D01*
X1299139D01*
G01X1298603Y1710112D02*
X1297683D01*
G01X1299178Y1713234D02*
X1297644D01*
Y1716334D01*
X1299178D01*
G01X1298564Y1714836D02*
X1297644D01*
G01X1299254Y1725525D02*
X1299024Y1725680D01*
X1298756Y1725783D01*
X1298449D01*
X1298104Y1725628D01*
X1297836Y1725370D01*
X1297644Y1725060D01*
X1297491Y1724543D01*
X1297453Y1724078D01*
X1297529Y1723613D01*
X1297644Y1723303D01*
X1297874Y1722993D01*
X1298143Y1722786D01*
X1298411Y1722683D01*
X1298679D01*
X1298948Y1722786D01*
X1299178Y1722941D01*
X1299369Y1723148D01*
G01X1298718Y1729061D02*
X1298871Y1729216D01*
X1298986Y1729475D01*
X1299063Y1729836D01*
X1298986Y1730146D01*
X1298833Y1730353D01*
X1298564Y1730508D01*
X1297529D01*
Y1727408D01*
X1298794D01*
X1299063Y1727615D01*
X1299216Y1727925D01*
X1299293Y1728286D01*
X1299216Y1728648D01*
X1298986Y1728958D01*
X1298718Y1729061D01*
X1297529D01*
G01X1297568Y1717959D02*
Y1721059D01*
X1298334D01*
X1298641Y1720904D01*
X1298871Y1720697D01*
X1299063Y1720387D01*
X1299216Y1720026D01*
X1299254Y1719509D01*
X1299216Y1718992D01*
X1299063Y1718631D01*
X1298871Y1718321D01*
X1298641Y1718114D01*
X1298334Y1717959D01*
X1297568D01*
G01X1288977Y1781456D02*
X1379134D01*
G01X1314380Y-25617D02*
X1314690Y-25425D01*
X1314897Y-25195D01*
X1315000Y-24927D01*
X1314897Y-24620D01*
X1314690Y-24390D01*
X1314380Y-24160D01*
X1313967Y-24083D01*
X1311900D01*
G01X1315000Y-21750D02*
X1314948Y-21482D01*
X1314793Y-21175D01*
X1314535Y-20983D01*
X1314173Y-20907D01*
X1313812Y-20983D01*
X1313502Y-21213D01*
X1313347Y-21558D01*
Y-21942D01*
X1313243Y-22172D01*
X1312985Y-22363D01*
X1312623Y-22440D01*
X1312262Y-22325D01*
X1312003Y-22057D01*
X1311900Y-21750D01*
X1312003Y-21443D01*
X1312262Y-21175D01*
X1312623Y-21060D01*
X1312985Y-21137D01*
X1313243Y-21328D01*
X1313347Y-21558D01*
Y-21942D01*
X1313502Y-22287D01*
X1313812Y-22517D01*
X1314173Y-22593D01*
X1314535Y-22517D01*
X1314793Y-22325D01*
X1314948Y-22018D01*
X1315000Y-21750D01*
G01Y-18190D02*
X1311900D01*
X1314122Y-19608D01*
Y-17692D01*
G01X1314380Y-5617D02*
X1314690Y-5425D01*
X1314897Y-5195D01*
X1315000Y-4927D01*
X1314897Y-4620D01*
X1314690Y-4390D01*
X1314380Y-4160D01*
X1313967Y-4083D01*
X1311900D01*
G01X1315000Y-1750D02*
X1314948Y-1482D01*
X1314793Y-1175D01*
X1314535Y-983D01*
X1314173Y-907D01*
X1313812Y-983D01*
X1313502Y-1213D01*
X1313347Y-1558D01*
Y-1942D01*
X1313243Y-2172D01*
X1312985Y-2363D01*
X1312623Y-2440D01*
X1312262Y-2325D01*
X1312003Y-2057D01*
X1311900Y-1750D01*
X1312003Y-1443D01*
X1312262Y-1175D01*
X1312623Y-1060D01*
X1312985Y-1137D01*
X1313243Y-1328D01*
X1313347Y-1558D01*
Y-1942D01*
X1313502Y-2287D01*
X1313812Y-2517D01*
X1314173Y-2593D01*
X1314535Y-2517D01*
X1314793Y-2325D01*
X1314948Y-2018D01*
X1315000Y-1750D01*
G01X1314380Y507D02*
X1314742Y737D01*
X1314948Y1043D01*
X1315000Y1388D01*
X1314948Y1695D01*
X1314690Y2002D01*
X1314380Y2193D01*
X1314070Y2232D01*
X1313708Y2155D01*
X1313450Y1887D01*
X1313347Y1618D01*
Y1273D01*
G01Y1618D02*
X1313192Y1848D01*
X1312933Y2040D01*
X1312623Y2117D01*
X1312313Y2040D01*
X1312055Y1848D01*
X1311900Y1503D01*
X1311952Y1158D01*
X1312158Y813D01*
G01X1314380Y14383D02*
X1314690Y14575D01*
X1314897Y14805D01*
X1315000Y15073D01*
X1314897Y15380D01*
X1314690Y15610D01*
X1314380Y15840D01*
X1313967Y15917D01*
X1311900D01*
G01X1315000Y18250D02*
X1314948Y18518D01*
X1314793Y18825D01*
X1314535Y19017D01*
X1314173Y19093D01*
X1313812Y19017D01*
X1313502Y18787D01*
X1313347Y18442D01*
Y18058D01*
X1313243Y17828D01*
X1312985Y17637D01*
X1312623Y17560D01*
X1312262Y17675D01*
X1312003Y17943D01*
X1311900Y18250D01*
X1312003Y18557D01*
X1312262Y18825D01*
X1312623Y18940D01*
X1312985Y18863D01*
X1313243Y18672D01*
X1313347Y18442D01*
Y18058D01*
X1313502Y17713D01*
X1313812Y17483D01*
X1314173Y17407D01*
X1314535Y17483D01*
X1314793Y17675D01*
X1314948Y17982D01*
X1315000Y18250D01*
G01Y21350D02*
X1311900D01*
X1312520Y20890D01*
G01X1315000D02*
Y21810D01*
G01X1308066Y59393D02*
Y50731D01*
G01X1310360Y50908D02*
Y57108D01*
G01X1313560Y50908D02*
X1310360D01*
G01X1313560Y57108D02*
Y50908D01*
G01X1310360Y57108D02*
X1313560D01*
G01X1314049Y70905D02*
Y77105D01*
G01X1317249Y70905D02*
X1314049D01*
G01X1310036Y70906D02*
Y77106D01*
G01X1313236Y70906D02*
X1310036D01*
G01X1313236Y77106D02*
Y70906D01*
G01X1315388Y60700D02*
X1312188D01*
G01Y66900D02*
X1315388D01*
G01X1312188Y60700D02*
Y66900D01*
G01X1308190D02*
X1311390D01*
G01X1308190Y60700D02*
Y66900D01*
G01X1311390Y60700D02*
X1308190D01*
G01X1311390Y66900D02*
Y60700D01*
G01X1300934Y62972D02*
Y66172D01*
G01X1307134Y62972D02*
X1300934D01*
G01X1307134Y66172D02*
Y62972D01*
G01X1300934Y66172D02*
X1307134D01*
G01X1305978Y70904D02*
Y77104D01*
G01X1309178Y70904D02*
X1305978D01*
G01X1309178Y77104D02*
Y70904D01*
G01X1307134Y70162D02*
Y66962D01*
G01X1300934Y70162D02*
X1307134D01*
G01X1300934Y66962D02*
Y70162D01*
G01X1307134Y66962D02*
X1300934D01*
G01X1312078Y78270D02*
Y91870D01*
G01X1320878Y78270D02*
X1312078D01*
G01X1314049Y77105D02*
X1317249D01*
G01X1310036Y77106D02*
X1313236D01*
G01X1303663Y80175D02*
Y83375D01*
G01X1309863Y80175D02*
X1303663D01*
G01X1309863Y83375D02*
Y80175D01*
G01X1303663Y83375D02*
X1309863D01*
G01X1305978Y77104D02*
X1309178D01*
G01X1304864Y73190D02*
X1301664D01*
G01X1304864Y79390D02*
Y73190D01*
G01X1301664Y79390D02*
X1304864D01*
G01X1301664Y73190D02*
Y79390D01*
G01X1300765Y82769D02*
Y79569D01*
G01X1302111Y86738D02*
Y83538D01*
G01X1312078Y91870D02*
X1320878D01*
G01X1307192Y95901D02*
X1310392D01*
G01X1307192Y89701D02*
Y95901D01*
G01X1310392Y89701D02*
X1307192D01*
G01X1310392Y95901D02*
Y89701D01*
G01X1309306Y99089D02*
Y105289D01*
G01X1312506Y99089D02*
X1309306D01*
G01X1312506Y105289D02*
Y99089D01*
G01X1313306D02*
Y105289D01*
G01X1316506Y99089D02*
X1313306D01*
G01X1300007Y109567D02*
Y103367D01*
G01X1309306Y105289D02*
X1312506D01*
G01X1313306D02*
X1316506D01*
G01X1305510Y236025D02*
X1315100D01*
G01X1313200Y265362D02*
Y277962D01*
G01X1328600Y265362D02*
X1313200D01*
G01Y277962D02*
X1328600D01*
G01X1309142Y296717D02*
X1305942D01*
G01X1309142Y302917D02*
Y296717D01*
G01X1305942D02*
Y302917D01*
G01X1305142Y296717D02*
X1301942D01*
G01X1305142Y302917D02*
Y296717D01*
G01X1301942D02*
Y302917D01*
G01X1298942Y292507D02*
Y286307D01*
G01X1305942Y302917D02*
X1309142D01*
G01X1301942D02*
X1305142D01*
G01X1302600Y838621D02*
G03X1305553Y835668I2953J0D01*
G01X1309293Y835708D02*
Y838464D01*
G01Y835708D02*
Y835668D01*
G01D02*
X1305553D01*
G01X1302600Y838621D02*
G03X1305552Y835668I2953J0D01*
G01X1309292Y835708D02*
Y838464D01*
G01Y835708D02*
Y835668D01*
G01D02*
X1305552D01*
G01X1302639Y829802D02*
X1367600D01*
G01X1302639Y829803D02*
X1367600D01*
G01X1305395Y1143976D02*
Y838464D01*
G01X1309293D02*
X1317167D01*
G01X1302600Y838621D02*
Y842361D01*
G01X1305395D02*
X1302639D01*
G01X1305395Y850235D02*
Y842361D01*
G01X1302639Y850235D02*
X1305395D01*
G01X1309292Y838464D02*
X1317166D01*
G01X1302600Y838621D02*
Y842362D01*
G01X1305394D02*
X1302639D01*
G01X1305394Y850236D02*
Y842362D01*
G01X1302639Y850236D02*
X1305394D01*
G01X1302639Y860511D02*
Y850235D01*
G01Y860512D02*
Y850236D01*
G01X1305395Y838464D02*
X1528229D01*
G01X1300671Y979409D02*
Y861298D01*
G01X1300670Y979410D02*
Y861299D01*
G01X1302639Y861298D02*
Y860511D01*
G01X1300671Y861298D02*
X1302639D01*
G01X1300670Y861299D02*
X1302639D01*
G01D02*
Y860512D01*
G01X1308742Y986102D02*
X1300671Y979409D01*
G01X1308741Y986103D02*
X1300670Y979410D01*
G01X1300671Y1003031D02*
X1308742Y996338D01*
G01X1300670Y1003031D02*
X1308741Y996338D01*
G01X1308742D02*
Y986102D01*
G01X1308741Y996338D02*
Y986103D01*
G01X1300671Y1110157D02*
Y1003031D01*
G01X1300670Y1110157D02*
Y1003031D01*
G01X1304804Y1110157D02*
G03Y1116456I0J3149D01*
G01Y1110157D02*
G03Y1116456I0J3149D01*
G01X1300671Y1132204D02*
Y1116456D01*
G01X1300670Y1132205D02*
Y1116456D01*
G01X1300671D02*
X1304804D01*
G01X1300670D02*
X1304804D01*
G01X1305553Y1146771D02*
G03X1302600Y1143818I0J-2953D01*
G01X1309293Y1143976D02*
Y1146731D01*
G01X1305395Y1140078D02*
X1302600D01*
G01X1302639D02*
X1305395D01*
G01X1317167Y1143976D02*
X1309293D01*
G01X1302600Y1140078D02*
Y1143818D01*
G01X1305552Y1146771D02*
G03X1302600Y1143818I0J-2952D01*
G01X1305394Y1140079D02*
X1302600D01*
G01X1302639D02*
X1305394D01*
G01X1302600D02*
Y1143818D01*
G01X1528229Y1143976D02*
X1305395D01*
G01Y1132204D02*
Y1140078D01*
G01X1299490Y1132204D02*
X1302639D01*
G01X1305395D02*
X1302639D01*
G01X1305394Y1132205D02*
Y1140079D01*
G01X1299489Y1132205D02*
X1302639D01*
G01X1305394D02*
X1302639D01*
G01X1309293Y1146771D02*
Y1146731D01*
G01X1305553Y1146771D02*
X1309293D01*
G01X1305552D02*
X1309292D01*
G01X1300883Y1272512D02*
Y1275612D01*
X1301803D01*
X1302110Y1275457D01*
X1302340Y1275095D01*
X1302417Y1274682D01*
X1302340Y1274269D01*
X1302148Y1273959D01*
X1301803Y1273804D01*
X1300883D01*
G01X1303983Y1275612D02*
Y1272512D01*
X1305517D01*
G01X1307198Y1272874D02*
X1307467Y1272615D01*
X1307773Y1272512D01*
X1308080Y1272615D01*
X1308348Y1272925D01*
X1308540Y1273390D01*
X1308617Y1273855D01*
Y1274424D01*
X1308540Y1274889D01*
X1308348Y1275302D01*
X1308118Y1275509D01*
X1307850Y1275612D01*
X1307543Y1275509D01*
X1307313Y1275302D01*
X1307160Y1274992D01*
X1307083Y1274579D01*
X1307160Y1274217D01*
X1307352Y1273855D01*
X1307582Y1273649D01*
X1307850Y1273597D01*
X1308157Y1273700D01*
X1308387Y1273959D01*
X1308617Y1274424D01*
G01X1311027Y1268772D02*
Y1312080D01*
G01X1316368Y1268772D02*
X1311027D01*
G01X1308547Y1310362D02*
Y1305362D01*
G01Y1291806D02*
Y1305362D01*
G01X1303206Y1291806D02*
X1308547D01*
G01X1311027Y1312080D02*
X1316368D01*
G01X1308547Y1310362D02*
Y1335114D01*
G01X1310220Y1323418D02*
Y1329618D01*
G01X1313420Y1323418D02*
X1310220D01*
G01X1313420Y1329618D02*
Y1323418D01*
G01X1303729Y1338492D02*
X1302936D01*
G01X1303729Y1341092D02*
Y1338492D01*
G01X1308547Y1335114D02*
X1303206D01*
G01X1310220Y1329618D02*
X1313420D01*
G01Y1333918D02*
X1310220D01*
G01X1313420Y1340118D02*
Y1333918D01*
G01X1310220D02*
Y1340118D01*
G01X1310746Y1355447D02*
X1313946D01*
G01X1310746Y1349247D02*
Y1355447D01*
G01X1313946Y1349247D02*
X1310746D01*
G01X1313946Y1355447D02*
Y1349247D01*
G01X1310220Y1340118D02*
X1313420D01*
G01X1306540Y1353514D02*
X1309740D01*
G01X1306540Y1347314D02*
Y1353514D01*
G01X1309740Y1347314D02*
X1306540D01*
G01X1309740Y1353514D02*
Y1347314D01*
G01X1313458Y1348407D02*
X1316658D01*
G01X1313458Y1342207D02*
Y1348407D01*
G01X1316658Y1342207D02*
X1313458D01*
G01X1303729Y1362114D02*
Y1359923D01*
G01X1302996Y1362114D02*
X1303729D01*
G01X1299317Y1371527D02*
X1302517D01*
G01X1299317Y1365327D02*
Y1371527D01*
G01X1302517Y1365327D02*
X1299317D01*
G01X1302517Y1371527D02*
Y1365327D01*
G01X1298475Y1371527D02*
Y1365327D01*
G01X1312205Y1668290D02*
Y1646023D01*
G01X1300394Y1657834D02*
Y1769645D01*
G01X1313378Y1656305D02*
X1313608Y1656615D01*
X1313876Y1656770D01*
X1314183Y1656822D01*
X1314566Y1656719D01*
X1314834Y1656460D01*
X1314911Y1656150D01*
X1314873Y1655840D01*
X1314719Y1655582D01*
X1313953Y1655065D01*
X1313608Y1654704D01*
X1313378Y1654187D01*
X1313301Y1653722D01*
X1314911D01*
G01X1306232D02*
Y1656822D01*
X1305772Y1656202D01*
G01Y1653722D02*
X1306692D01*
G01X1300788Y1657834D02*
X1367323D01*
G01X1300788Y1769645D02*
Y1657834D01*
G01X1312205Y1781456D02*
Y1739150D01*
G01X1312809Y1736412D02*
X1313709Y1737312D01*
G01X1307809Y1736412D02*
X1312809D01*
G01X1307809Y1739812D02*
Y1736412D01*
G01X1309809Y1737812D02*
X1307809Y1739812D01*
G01X1305809Y1737812D02*
X1309809D01*
G01X1307809Y1739812D02*
X1305809Y1737812D01*
G01X1300788Y1740118D02*
X1367323D01*
G01Y1769645D02*
X1300788D01*
G01X1319880Y-25617D02*
X1320190Y-25425D01*
X1320397Y-25195D01*
X1320500Y-24927D01*
X1320397Y-24620D01*
X1320190Y-24390D01*
X1319880Y-24160D01*
X1319467Y-24083D01*
X1317400D01*
G01X1320500Y-21827D02*
X1319828Y-21750D01*
X1319260Y-21635D01*
X1318743Y-21482D01*
X1318175Y-21290D01*
X1317400Y-20983D01*
Y-22517D01*
G01X1317917Y-19378D02*
X1317607Y-19148D01*
X1317452Y-18880D01*
X1317400Y-18573D01*
X1317503Y-18190D01*
X1317762Y-17922D01*
X1318072Y-17845D01*
X1318382Y-17883D01*
X1318640Y-18037D01*
X1319157Y-18803D01*
X1319518Y-19148D01*
X1320035Y-19378D01*
X1320500Y-19455D01*
Y-17845D01*
G01X1319880Y-5117D02*
X1320190Y-4925D01*
X1320397Y-4695D01*
X1320500Y-4427D01*
X1320397Y-4120D01*
X1320190Y-3890D01*
X1319880Y-3660D01*
X1319467Y-3583D01*
X1317400D01*
G01X1320500Y-1327D02*
X1319828Y-1250D01*
X1319260Y-1135D01*
X1318743Y-982D01*
X1318175Y-790D01*
X1317400Y-483D01*
Y-2017D01*
G01X1320500Y1850D02*
X1317400D01*
X1318020Y1390D01*
G01X1320500D02*
Y2310D01*
G01X1319880Y14383D02*
X1320190Y14575D01*
X1320397Y14805D01*
X1320500Y15073D01*
X1320397Y15380D01*
X1320190Y15610D01*
X1319880Y15840D01*
X1319467Y15917D01*
X1317400D01*
G01X1319208Y17522D02*
X1318847Y17790D01*
X1318640Y18020D01*
X1318537Y18327D01*
X1318640Y18595D01*
X1318847Y18787D01*
X1319157Y18940D01*
X1319518Y18978D01*
X1319828Y18940D01*
X1320138Y18787D01*
X1320397Y18557D01*
X1320500Y18288D01*
X1320397Y17982D01*
X1320087Y17713D01*
X1319622Y17560D01*
X1319105Y17522D01*
X1318433Y17598D01*
X1318072Y17713D01*
X1317710Y17905D01*
X1317452Y18173D01*
X1317400Y18442D01*
X1317503Y18710D01*
X1317762Y18902D01*
G01X1320138Y20698D02*
X1320397Y20967D01*
X1320500Y21273D01*
X1320397Y21580D01*
X1320087Y21848D01*
X1319622Y22040D01*
X1319157Y22117D01*
X1318588D01*
X1318123Y22040D01*
X1317710Y21848D01*
X1317503Y21618D01*
X1317400Y21350D01*
X1317503Y21043D01*
X1317710Y20813D01*
X1318020Y20660D01*
X1318433Y20583D01*
X1318795Y20660D01*
X1319157Y20852D01*
X1319363Y21082D01*
X1319415Y21350D01*
X1319312Y21657D01*
X1319053Y21887D01*
X1318588Y22117D01*
G01X1315671Y55979D02*
Y53757D01*
X1315824Y53292D01*
X1316131Y52982D01*
X1316514Y52879D01*
X1316897Y52982D01*
X1317204Y53292D01*
X1317357Y53757D01*
Y55979D01*
G01X1319614Y52879D02*
Y55979D01*
X1319154Y55359D01*
G01Y52879D02*
X1320074D01*
G01X1321871Y53344D02*
X1322101Y53086D01*
X1322369Y52931D01*
X1322714Y52879D01*
X1323059Y52982D01*
X1323327Y53189D01*
X1323519Y53551D01*
X1323557Y53964D01*
X1323481Y54377D01*
X1323289Y54636D01*
X1323021Y54842D01*
X1322752Y54894D01*
X1322484Y54842D01*
X1322139Y54636D01*
X1322254Y55979D01*
X1323289D01*
G01X1326274Y52879D02*
Y55979D01*
X1324856Y53757D01*
X1326772D01*
G01X1322932Y69714D02*
Y83314D01*
G01X1331732Y69714D02*
X1322932D01*
G01X1324302Y66957D02*
X1327502D01*
G01X1324302Y60757D02*
Y66957D01*
G01X1327502Y60757D02*
X1324302D01*
G01X1327502Y66957D02*
Y60757D01*
G01X1328502Y66957D02*
X1331702D01*
G01X1328502Y60757D02*
Y66957D01*
G01X1331702Y60757D02*
X1328502D01*
G01X1317249Y77105D02*
Y70905D01*
G01X1316231Y66900D02*
X1319431D01*
G01X1316231Y60700D02*
Y66900D01*
G01X1319431Y60700D02*
X1316231D01*
G01X1319431Y66900D02*
Y60700D01*
G01X1315388Y66900D02*
Y60700D01*
G01X1320269Y66882D02*
X1323469D01*
G01X1320269Y60682D02*
Y66882D01*
G01X1323469Y60682D02*
X1320269D01*
G01X1323469Y66882D02*
Y60682D01*
G01X1318121Y70905D02*
Y77105D01*
G01X1321321Y70905D02*
X1318121D01*
G01X1321321Y77105D02*
Y70905D01*
G01X1322932Y83314D02*
X1331732D01*
G01X1330232Y76514D02*
X1331732Y77514D01*
G01Y75514D02*
X1330232Y76514D01*
G01X1320878Y86070D02*
Y91870D01*
G01Y78270D02*
Y84070D01*
G01X1319378Y85070D02*
X1320878Y86070D01*
G01Y84070D02*
X1319378Y85070D01*
G01X1318121Y77105D02*
X1321321D01*
G01X1322520Y86808D02*
Y93008D01*
G01X1325720Y86808D02*
X1322520D01*
G01X1325720Y93008D02*
Y86808D01*
G01X1322520Y93008D02*
X1325720D01*
G01X1328291Y98423D02*
X1331491D01*
G01X1328291Y92223D02*
Y98423D01*
G01X1331491Y92223D02*
X1328291D01*
G01X1321306Y101803D02*
X1324506D01*
G01X1321306Y95603D02*
Y101803D01*
G01X1324506Y95603D02*
X1321306D01*
G01X1324506Y101803D02*
Y95603D01*
G01X1321306Y102633D02*
Y108833D01*
G01X1324506Y102633D02*
X1321306D01*
G01X1324506Y108833D02*
Y102633D01*
G01X1316506Y105289D02*
Y99089D01*
G01X1317306Y99083D02*
Y105283D01*
G01X1320506Y99083D02*
X1317306D01*
G01X1320506Y105283D02*
Y99083D01*
G01X1328046Y112069D02*
X1331246D01*
G01X1328046Y105869D02*
Y112069D01*
G01X1331246Y105869D02*
X1328046D01*
G01X1321306Y108833D02*
X1324506D01*
G01X1317306Y105283D02*
X1320506D01*
G01X1317260Y236025D02*
X1322460D01*
G01X1325190D02*
X1330540D01*
G01X1322493Y246362D02*
Y252562D01*
G01X1325693Y246362D02*
X1322493D01*
G01X1325693Y252562D02*
Y246362D01*
G01X1328600Y277962D02*
Y265362D01*
G01X1319337Y253666D02*
Y258266D01*
G01X1329537Y253666D02*
X1319337D01*
G01X1329537Y258266D02*
Y253666D01*
G01X1319337Y258266D02*
X1329537D01*
G01X1320900Y263262D02*
Y260062D01*
G01X1314700Y263262D02*
X1320900D01*
G01X1314700Y260062D02*
Y263262D01*
G01X1320900Y260062D02*
X1314700D01*
G01X1323464Y259914D02*
Y263114D01*
G01X1329664Y259914D02*
X1323464D01*
G01X1329664Y263114D02*
Y259914D01*
G01X1323464Y263114D02*
X1329664D01*
G01X1322493Y252562D02*
X1325693D01*
G01X1315950Y282471D02*
Y283866D01*
X1315183Y285571D01*
G01X1316717D02*
X1315950Y283866D01*
G01X1318973Y282471D02*
X1319050Y283143D01*
X1319165Y283711D01*
X1319318Y284228D01*
X1319510Y284796D01*
X1319817Y285571D01*
X1318283D01*
G01X1320345Y791862D02*
Y794962D01*
G01X1321955D02*
Y791862D01*
G01Y793412D02*
X1320345D01*
G01X1323522Y794445D02*
X1323752Y794755D01*
X1324020Y794910D01*
X1324327Y794962D01*
X1324710Y794859D01*
X1324978Y794600D01*
X1325055Y794290D01*
X1325017Y793980D01*
X1324863Y793722D01*
X1324097Y793205D01*
X1323752Y792844D01*
X1323522Y792327D01*
X1323445Y791862D01*
X1325055D01*
G01X1326507Y792482D02*
X1326737Y792120D01*
X1327043Y791914D01*
X1327388Y791862D01*
X1327695Y791914D01*
X1328002Y792172D01*
X1328193Y792482D01*
X1328232Y792792D01*
X1328155Y793154D01*
X1327887Y793412D01*
X1327618Y793515D01*
X1327273D01*
G01X1327618D02*
X1327848Y793670D01*
X1328040Y793929D01*
X1328117Y794239D01*
X1328040Y794549D01*
X1327848Y794807D01*
X1327503Y794962D01*
X1327158Y794910D01*
X1326813Y794704D01*
G01X1336190Y811121D02*
G03I-9950J0D01*
G01X1317167Y829802D02*
Y833556D01*
G01D02*
Y838464D01*
G01X1317166Y833556D02*
Y838464D01*
G01Y829803D02*
Y833556D01*
G01X1317167Y1143976D02*
Y1148883D01*
G01X1317166Y1143977D02*
Y1148883D01*
G01X1317167D02*
Y1152637D01*
G01X1317166Y1148883D02*
Y1152638D01*
G01X1342155Y1171318D02*
G03I-9950J0D01*
G01X1325345Y1189862D02*
Y1192962D01*
G01X1326955D02*
Y1189862D01*
G01Y1191412D02*
X1325345D01*
G01X1329250Y1189862D02*
Y1192962D01*
X1328790Y1192342D01*
G01Y1189862D02*
X1329710D01*
G01X1331507Y1190327D02*
X1331737Y1190069D01*
X1332005Y1189914D01*
X1332350Y1189862D01*
X1332695Y1189965D01*
X1332963Y1190172D01*
X1333155Y1190534D01*
X1333193Y1190947D01*
X1333117Y1191360D01*
X1332925Y1191619D01*
X1332657Y1191825D01*
X1332388Y1191877D01*
X1332120Y1191825D01*
X1331775Y1191619D01*
X1331890Y1192962D01*
X1332925D01*
G01X1321953Y1255522D02*
Y1258622D01*
X1322873D01*
X1323180Y1258467D01*
X1323410Y1258105D01*
X1323487Y1257692D01*
X1323410Y1257279D01*
X1323218Y1256969D01*
X1322873Y1256814D01*
X1321953D01*
G01X1325053Y1258622D02*
Y1255522D01*
X1326587D01*
G01X1328920D02*
Y1258622D01*
X1328460Y1258002D01*
G01Y1255522D02*
X1329380D01*
G01X1332020D02*
Y1258622D01*
X1331560Y1258002D01*
G01Y1255522D02*
X1332480D01*
G01X1335580D02*
Y1258622D01*
X1334162Y1256400D01*
X1336078D01*
G01X1316051Y1315458D02*
Y1318058D01*
G01X1316844Y1315458D02*
X1316051D01*
G01Y1324669D02*
Y1326367D01*
G01Y1339080D02*
X1317059D01*
G01X1316051Y1337226D02*
Y1339080D01*
G01X1321463Y1352542D02*
Y1355642D01*
X1322383D01*
X1322690Y1355487D01*
X1322920Y1355125D01*
X1322997Y1354712D01*
X1322920Y1354299D01*
X1322728Y1353989D01*
X1322383Y1353834D01*
X1321463D01*
G01X1324487Y1355642D02*
Y1353420D01*
X1324640Y1352955D01*
X1324947Y1352645D01*
X1325330Y1352542D01*
X1325713Y1352645D01*
X1326020Y1352955D01*
X1326173Y1353420D01*
Y1355642D01*
G01X1328430Y1352542D02*
X1328698Y1352594D01*
X1329005Y1352749D01*
X1329197Y1353007D01*
X1329273Y1353369D01*
X1329197Y1353730D01*
X1328967Y1354040D01*
X1328622Y1354195D01*
X1328238D01*
X1328008Y1354299D01*
X1327817Y1354557D01*
X1327740Y1354919D01*
X1327855Y1355280D01*
X1328123Y1355539D01*
X1328430Y1355642D01*
X1328737Y1355539D01*
X1329005Y1355280D01*
X1329120Y1354919D01*
X1329043Y1354557D01*
X1328852Y1354299D01*
X1328622Y1354195D01*
X1328238D01*
X1327893Y1354040D01*
X1327663Y1353730D01*
X1327587Y1353369D01*
X1327663Y1353007D01*
X1327855Y1352749D01*
X1328162Y1352594D01*
X1328430Y1352542D01*
G01X1330380Y1351509D02*
X1332680D01*
G01X1333863Y1352542D02*
Y1355642D01*
X1334783D01*
X1335090Y1355487D01*
X1335320Y1355125D01*
X1335397Y1354712D01*
X1335320Y1354299D01*
X1335128Y1353989D01*
X1334783Y1353834D01*
X1333863D01*
G01X1337730Y1355642D02*
X1337423Y1355539D01*
X1337193Y1355280D01*
X1337040Y1354970D01*
X1336925Y1354557D01*
X1336887Y1354092D01*
X1336925Y1353627D01*
X1337040Y1353214D01*
X1337193Y1352904D01*
X1337423Y1352645D01*
X1337730Y1352542D01*
X1338037Y1352645D01*
X1338267Y1352904D01*
X1338420Y1353214D01*
X1338535Y1353627D01*
X1338573Y1354092D01*
X1338535Y1354557D01*
X1338420Y1354970D01*
X1338267Y1355280D01*
X1338037Y1355539D01*
X1337730Y1355642D01*
G01X1339680Y1351509D02*
X1341980D01*
G01X1343202Y1353834D02*
X1343470Y1354195D01*
X1343700Y1354402D01*
X1344007Y1354505D01*
X1344275Y1354402D01*
X1344467Y1354195D01*
X1344620Y1353885D01*
X1344658Y1353524D01*
X1344620Y1353214D01*
X1344467Y1352904D01*
X1344237Y1352645D01*
X1343968Y1352542D01*
X1343662Y1352645D01*
X1343393Y1352955D01*
X1343240Y1353420D01*
X1343202Y1353937D01*
X1343278Y1354609D01*
X1343393Y1354970D01*
X1343585Y1355332D01*
X1343853Y1355590D01*
X1344122Y1355642D01*
X1344390Y1355539D01*
X1344582Y1355280D01*
G01X1316658Y1348407D02*
Y1342207D01*
G01X1317710Y1345921D02*
Y1349121D01*
G01X1323910Y1345921D02*
X1317710D01*
G01X1323910Y1349121D02*
Y1345921D01*
G01X1317710Y1349121D02*
X1323910D01*
G01X1330483Y1342293D02*
X1327283D01*
G01X1330483Y1348493D02*
Y1342293D01*
G01X1327283Y1348493D02*
X1330483D01*
G01X1327283Y1342293D02*
Y1348493D01*
G01X1322377Y1375323D02*
X1328916D01*
G01X1322377Y1414693D02*
Y1375323D01*
G01X1328916Y1414693D02*
X1322377D01*
G01X1319572Y1642539D02*
X1319764Y1642229D01*
X1319994Y1642022D01*
X1320262Y1641919D01*
X1320569Y1642022D01*
X1320799Y1642229D01*
X1321029Y1642539D01*
X1321106Y1642952D01*
Y1645019D01*
G01X1323439Y1641919D02*
Y1645019D01*
X1322979Y1644399D01*
G01Y1641919D02*
X1323899D01*
G01X1326539Y1645019D02*
X1326232Y1644916D01*
X1326002Y1644657D01*
X1325849Y1644347D01*
X1325734Y1643934D01*
X1325696Y1643469D01*
X1325734Y1643004D01*
X1325849Y1642591D01*
X1326002Y1642281D01*
X1326232Y1642022D01*
X1326539Y1641919D01*
X1326846Y1642022D01*
X1327076Y1642281D01*
X1327229Y1642591D01*
X1327344Y1643004D01*
X1327382Y1643469D01*
X1327344Y1643934D01*
X1327229Y1644347D01*
X1327076Y1644657D01*
X1326846Y1644916D01*
X1326539Y1645019D01*
G01X1329562Y1641919D02*
X1329639Y1642591D01*
X1329754Y1643159D01*
X1329907Y1643676D01*
X1330099Y1644244D01*
X1330406Y1645019D01*
X1328872D01*
G01X1330314Y1653722D02*
Y1656822D01*
X1328896Y1654600D01*
X1330812D01*
G01X1321137Y1654342D02*
X1321367Y1653980D01*
X1321673Y1653774D01*
X1322018Y1653722D01*
X1322325Y1653774D01*
X1322632Y1654032D01*
X1322823Y1654342D01*
X1322862Y1654652D01*
X1322785Y1655014D01*
X1322517Y1655272D01*
X1322248Y1655375D01*
X1321903D01*
G01X1322248D02*
X1322478Y1655530D01*
X1322670Y1655789D01*
X1322747Y1656099D01*
X1322670Y1656409D01*
X1322478Y1656667D01*
X1322133Y1656822D01*
X1321788Y1656770D01*
X1321443Y1656564D01*
G01X1315892Y1736629D02*
X1314826D01*
Y1739129D01*
X1315892D01*
G01X1315466Y1737921D02*
X1314826D01*
G01X1316972Y1736629D02*
Y1739129D01*
X1317506D01*
X1317719Y1739004D01*
X1317879Y1738837D01*
X1318012Y1738587D01*
X1318119Y1738296D01*
X1318146Y1737879D01*
X1318119Y1737462D01*
X1318012Y1737171D01*
X1317879Y1736921D01*
X1317719Y1736754D01*
X1317506Y1736629D01*
X1316972D01*
G01X1319919Y1737879D02*
X1320452D01*
Y1737129D01*
X1320292Y1736879D01*
X1320106Y1736712D01*
X1319839Y1736629D01*
X1319572Y1736712D01*
X1319386Y1736879D01*
X1319226Y1737129D01*
X1319119Y1737421D01*
X1319066Y1737754D01*
Y1738046D01*
X1319119Y1738296D01*
X1319226Y1738587D01*
X1319386Y1738837D01*
X1319546Y1739004D01*
X1319759Y1739129D01*
X1319946D01*
X1320159Y1739046D01*
X1320319Y1738879D01*
G01X1322492Y1736629D02*
X1321426D01*
Y1739129D01*
X1322492D01*
G01X1322066Y1737921D02*
X1321426D01*
G01X1326359Y1736629D02*
X1326146Y1736671D01*
X1325959Y1736837D01*
X1325799Y1737087D01*
X1325692Y1737379D01*
X1325639Y1737712D01*
Y1738046D01*
X1325692Y1738379D01*
X1325799Y1738671D01*
X1325959Y1738921D01*
X1326146Y1739087D01*
X1326359Y1739129D01*
X1326572Y1739087D01*
X1326759Y1738921D01*
X1326919Y1738671D01*
X1327026Y1738379D01*
X1327079Y1738046D01*
Y1737712D01*
X1327026Y1737379D01*
X1326919Y1737087D01*
X1326759Y1736837D01*
X1326572Y1736671D01*
X1326359Y1736629D01*
G01X1328052D02*
Y1739129D01*
X1329066D01*
G01X1328692Y1737921D02*
X1328052D01*
G01X1332372Y1736629D02*
Y1739129D01*
X1332906D01*
X1333119Y1739004D01*
X1333279Y1738837D01*
X1333412Y1738587D01*
X1333519Y1738296D01*
X1333546Y1737879D01*
X1333519Y1737462D01*
X1333412Y1737171D01*
X1333279Y1736921D01*
X1333119Y1736754D01*
X1332906Y1736629D01*
X1332372D01*
G01X1334492D02*
X1335159Y1739129D01*
X1335826Y1736629D01*
G01X1335586Y1737504D02*
X1334732D01*
G01X1336772Y1739129D02*
Y1737337D01*
X1336879Y1736962D01*
X1337092Y1736712D01*
X1337359Y1736629D01*
X1337626Y1736712D01*
X1337839Y1736962D01*
X1337946Y1737337D01*
Y1739129D01*
G01X1339719Y1737879D02*
X1340252D01*
Y1737129D01*
X1340092Y1736879D01*
X1339906Y1736712D01*
X1339639Y1736629D01*
X1339372Y1736712D01*
X1339186Y1736879D01*
X1339026Y1737129D01*
X1338919Y1737421D01*
X1338866Y1737754D01*
Y1738046D01*
X1338919Y1738296D01*
X1339026Y1738587D01*
X1339186Y1738837D01*
X1339346Y1739004D01*
X1339559Y1739129D01*
X1339746D01*
X1339959Y1739046D01*
X1340119Y1738879D01*
G01X1341199Y1736629D02*
Y1739129D01*
G01X1342319D02*
Y1736629D01*
G01Y1737879D02*
X1341199D01*
G01X1343959Y1739129D02*
Y1736629D01*
G01X1343346Y1739129D02*
X1344572D01*
G01X1346692Y1736629D02*
X1345626D01*
Y1739129D01*
X1346692D01*
G01X1346266Y1737921D02*
X1345626D01*
G01X1347826Y1736629D02*
Y1739129D01*
X1348492D01*
X1348706Y1739004D01*
X1348839Y1738837D01*
X1348892Y1738504D01*
X1348839Y1738171D01*
X1348679Y1737962D01*
X1348492Y1737837D01*
X1347826D01*
G01X1348492D02*
X1348892Y1736629D01*
G01X1353346Y1738921D02*
X1353186Y1739046D01*
X1352999Y1739129D01*
X1352786D01*
X1352546Y1739004D01*
X1352359Y1738796D01*
X1352226Y1738546D01*
X1352119Y1738129D01*
X1352092Y1737754D01*
X1352146Y1737379D01*
X1352226Y1737129D01*
X1352386Y1736879D01*
X1352572Y1736712D01*
X1352759Y1736629D01*
X1352946D01*
X1353132Y1736712D01*
X1353292Y1736837D01*
X1353426Y1737004D01*
G01X1354292Y1736629D02*
X1354959Y1739129D01*
X1355626Y1736629D01*
G01X1355386Y1737504D02*
X1354532D01*
G01X1356626Y1736629D02*
Y1739129D01*
X1357292D01*
X1357506Y1739004D01*
X1357639Y1738837D01*
X1357692Y1738504D01*
X1357639Y1738171D01*
X1357479Y1737962D01*
X1357292Y1737837D01*
X1356626D01*
G01X1357292D02*
X1357692Y1736629D01*
G01X1358772D02*
Y1739129D01*
X1359306D01*
X1359519Y1739004D01*
X1359679Y1738837D01*
X1359812Y1738587D01*
X1359919Y1738296D01*
X1359946Y1737879D01*
X1359919Y1737462D01*
X1359812Y1737171D01*
X1359679Y1736921D01*
X1359519Y1736754D01*
X1359306Y1736629D01*
X1358772D01*
G01X1340621Y-13211D02*
Y-29811D01*
X1331021D01*
Y-13211D01*
X1340621D01*
G01Y6789D02*
Y-9811D01*
X1331021D01*
Y6789D01*
X1340621D01*
G01Y26789D02*
Y10189D01*
X1331021D01*
Y26789D01*
X1340621D01*
G01X1333947Y68862D02*
Y66640D01*
X1334100Y66175D01*
X1334407Y65865D01*
X1334790Y65762D01*
X1335173Y65865D01*
X1335480Y66175D01*
X1335633Y66640D01*
Y68862D01*
G01X1337162Y67054D02*
X1337430Y67415D01*
X1337660Y67622D01*
X1337967Y67725D01*
X1338235Y67622D01*
X1338427Y67415D01*
X1338580Y67105D01*
X1338618Y66744D01*
X1338580Y66434D01*
X1338427Y66124D01*
X1338197Y65865D01*
X1337928Y65762D01*
X1337622Y65865D01*
X1337353Y66175D01*
X1337200Y66640D01*
X1337162Y67157D01*
X1337238Y67829D01*
X1337353Y68190D01*
X1337545Y68552D01*
X1337813Y68810D01*
X1338082Y68862D01*
X1338350Y68759D01*
X1338542Y68500D01*
G01X1340990Y68862D02*
X1340683Y68759D01*
X1340453Y68500D01*
X1340300Y68190D01*
X1340185Y67777D01*
X1340147Y67312D01*
X1340185Y66847D01*
X1340300Y66434D01*
X1340453Y66124D01*
X1340683Y65865D01*
X1340990Y65762D01*
X1341297Y65865D01*
X1341527Y66124D01*
X1341680Y66434D01*
X1341795Y66847D01*
X1341833Y67312D01*
X1341795Y67777D01*
X1341680Y68190D01*
X1341527Y68500D01*
X1341297Y68759D01*
X1340990Y68862D01*
G01X1331732Y69714D02*
Y75514D01*
G01X1331702Y66957D02*
Y60757D01*
G01X1331732Y77514D02*
Y83314D01*
G01X1334137Y94522D02*
Y92300D01*
X1334290Y91835D01*
X1334597Y91525D01*
X1334980Y91422D01*
X1335363Y91525D01*
X1335670Y91835D01*
X1335823Y92300D01*
Y94522D01*
G01X1337352Y92714D02*
X1337620Y93075D01*
X1337850Y93282D01*
X1338157Y93385D01*
X1338425Y93282D01*
X1338617Y93075D01*
X1338770Y92765D01*
X1338808Y92404D01*
X1338770Y92094D01*
X1338617Y91784D01*
X1338387Y91525D01*
X1338118Y91422D01*
X1337812Y91525D01*
X1337543Y91835D01*
X1337390Y92300D01*
X1337352Y92817D01*
X1337428Y93489D01*
X1337543Y93850D01*
X1337735Y94212D01*
X1338003Y94470D01*
X1338272Y94522D01*
X1338540Y94419D01*
X1338732Y94160D01*
G01X1341180Y91422D02*
Y94522D01*
X1340720Y93902D01*
G01Y91422D02*
X1341640D01*
G01X1331491Y98423D02*
Y92223D01*
G01X1343483Y98443D02*
X1346683D01*
G01X1343483Y92243D02*
Y98443D01*
G01X1346683Y92243D02*
X1343483D01*
G01X1346683Y98443D02*
Y92243D01*
G01X1331246Y112069D02*
Y105869D01*
G01X1334949Y113045D02*
X1338149D01*
G01X1334949Y106845D02*
Y113045D01*
G01X1338149Y106845D02*
X1334949D01*
G01X1338149Y113045D02*
Y106845D01*
G01X1333480Y236025D02*
X1334660D01*
G01X1339800D02*
X1340270D01*
G01X1342550D02*
X1343730D01*
G01X1341393Y1249322D02*
Y1252422D01*
X1342313D01*
X1342620Y1252267D01*
X1342850Y1251905D01*
X1342927Y1251492D01*
X1342850Y1251079D01*
X1342658Y1250769D01*
X1342313Y1250614D01*
X1341393D01*
G01X1344493Y1252422D02*
Y1249322D01*
X1346027D01*
G01X1348360D02*
Y1252422D01*
X1347900Y1251802D01*
G01Y1249322D02*
X1348820D01*
G01X1350617Y1249942D02*
X1350847Y1249580D01*
X1351153Y1249374D01*
X1351498Y1249322D01*
X1351805Y1249374D01*
X1352112Y1249632D01*
X1352303Y1249942D01*
X1352342Y1250252D01*
X1352265Y1250614D01*
X1351997Y1250872D01*
X1351728Y1250975D01*
X1351383D01*
G01X1351728D02*
X1351958Y1251130D01*
X1352150Y1251389D01*
X1352227Y1251699D01*
X1352150Y1252009D01*
X1351958Y1252267D01*
X1351613Y1252422D01*
X1351268Y1252370D01*
X1350923Y1252164D01*
G01X1343108Y1255690D02*
Y1298998D01*
G01X1348449Y1255690D02*
X1343108D01*
G01X1340555Y1268772D02*
Y1291862D01*
G01X1335214Y1268772D02*
X1340555D01*
G01Y1296362D02*
Y1291862D01*
G01X1343108Y1298998D02*
X1348449D01*
G01X1340555Y1296362D02*
Y1312080D01*
G01X1335737Y1315458D02*
X1334944D01*
G01X1335737Y1318058D02*
Y1315458D01*
G01X1340555Y1312080D02*
X1335214D01*
G01X1342258Y1316192D02*
X1345458D01*
G01X1342258Y1309992D02*
Y1316192D01*
G01X1345458Y1309992D02*
X1342258D01*
G01X1345458Y1316192D02*
Y1309992D01*
G01X1345548Y1320492D02*
X1342348D01*
G01X1345548Y1326692D02*
Y1320492D01*
G01X1342348D02*
Y1326692D01*
G01X1335737Y1339080D02*
Y1336889D01*
G01X1335004Y1339080D02*
X1335737D01*
G01X1338346Y1330717D02*
X1341546D01*
G01X1338346Y1324517D02*
Y1330717D01*
G01X1341546Y1324517D02*
X1338346D01*
G01X1341546Y1330717D02*
Y1324517D01*
G01X1342348Y1326692D02*
X1345548D01*
G01X1341444Y1339775D02*
X1344644D01*
G01X1341444Y1333575D02*
Y1339775D01*
G01X1344644Y1333575D02*
X1341444D01*
G01X1344644Y1339775D02*
Y1333575D01*
G01X1345415Y1334983D02*
X1348615D01*
G01X1345415Y1328783D02*
Y1334983D01*
G01X1348615Y1328783D02*
X1345415D01*
G01X1331325Y1348493D02*
X1334525D01*
G01X1331325Y1342293D02*
Y1348493D01*
G01X1334525Y1342293D02*
X1331325D01*
G01X1334525Y1348493D02*
Y1342293D01*
G01X1331612Y1428263D02*
Y1431363D01*
X1332532D01*
X1332839Y1431208D01*
X1333069Y1430846D01*
X1333146Y1430433D01*
X1333069Y1430020D01*
X1332877Y1429710D01*
X1332532Y1429555D01*
X1331612D01*
G01X1334712Y1431363D02*
Y1428263D01*
X1336246D01*
G01X1338579D02*
Y1431363D01*
X1338119Y1430743D01*
G01Y1428263D02*
X1339039D01*
G01X1340836Y1428728D02*
X1341066Y1428470D01*
X1341334Y1428315D01*
X1341679Y1428263D01*
X1342024Y1428366D01*
X1342292Y1428573D01*
X1342484Y1428935D01*
X1342522Y1429348D01*
X1342446Y1429761D01*
X1342254Y1430020D01*
X1341986Y1430226D01*
X1341717Y1430278D01*
X1341449Y1430226D01*
X1341104Y1430020D01*
X1341219Y1431363D01*
X1342254D01*
G01X1344874Y1655014D02*
X1345142Y1655375D01*
X1345372Y1655582D01*
X1345679Y1655685D01*
X1345947Y1655582D01*
X1346139Y1655375D01*
X1346292Y1655065D01*
X1346330Y1654704D01*
X1346292Y1654394D01*
X1346139Y1654084D01*
X1345909Y1653825D01*
X1345640Y1653722D01*
X1345334Y1653825D01*
X1345065Y1654135D01*
X1344912Y1654600D01*
X1344874Y1655117D01*
X1344950Y1655789D01*
X1345065Y1656150D01*
X1345257Y1656512D01*
X1345525Y1656770D01*
X1345794Y1656822D01*
X1346062Y1656719D01*
X1346254Y1656460D01*
G01X1336885Y1654187D02*
X1337115Y1653929D01*
X1337383Y1653774D01*
X1337728Y1653722D01*
X1338073Y1653825D01*
X1338341Y1654032D01*
X1338533Y1654394D01*
X1338571Y1654807D01*
X1338495Y1655220D01*
X1338303Y1655479D01*
X1338035Y1655685D01*
X1337766Y1655737D01*
X1337498Y1655685D01*
X1337153Y1655479D01*
X1337268Y1656822D01*
X1338303D01*
G01X1348021Y111322D02*
X1351221D01*
G01X1348021Y105122D02*
Y111322D01*
G01X1351221Y105122D02*
X1348021D01*
G01X1351221Y111322D02*
Y105122D01*
G01X1359260Y236025D02*
X1369684D01*
G01X1378802Y1242785D02*
G03I-10827J0D01*
G01X1348179Y1302032D02*
Y1304632D01*
G01X1348972Y1302032D02*
X1348179D01*
G01Y1311243D02*
Y1312941D01*
G01X1347895Y1336883D02*
Y1339983D01*
X1348815D01*
X1349122Y1339828D01*
X1349352Y1339466D01*
X1349429Y1339053D01*
X1349352Y1338640D01*
X1349160Y1338330D01*
X1348815Y1338175D01*
X1347895D01*
G01X1350919Y1339983D02*
Y1337761D01*
X1351072Y1337296D01*
X1351379Y1336986D01*
X1351762Y1336883D01*
X1352145Y1336986D01*
X1352452Y1337296D01*
X1352605Y1337761D01*
Y1339983D01*
G01X1354862Y1336883D02*
Y1339983D01*
X1354402Y1339363D01*
G01Y1336883D02*
X1355322D01*
G01X1357119Y1337503D02*
X1357349Y1337141D01*
X1357655Y1336935D01*
X1358000Y1336883D01*
X1358307Y1336935D01*
X1358614Y1337193D01*
X1358805Y1337503D01*
X1358844Y1337813D01*
X1358767Y1338175D01*
X1358499Y1338433D01*
X1358230Y1338536D01*
X1357885D01*
G01X1358230D02*
X1358460Y1338691D01*
X1358652Y1338950D01*
X1358729Y1339260D01*
X1358652Y1339570D01*
X1358460Y1339828D01*
X1358115Y1339983D01*
X1357770Y1339931D01*
X1357425Y1339725D01*
G01X1359912Y1335850D02*
X1362212D01*
G01X1363395Y1336883D02*
Y1339983D01*
X1364315D01*
X1364622Y1339828D01*
X1364852Y1339466D01*
X1364929Y1339053D01*
X1364852Y1338640D01*
X1364660Y1338330D01*
X1364315Y1338175D01*
X1363395D01*
G01X1367262Y1339983D02*
X1366955Y1339880D01*
X1366725Y1339621D01*
X1366572Y1339311D01*
X1366457Y1338898D01*
X1366419Y1338433D01*
X1366457Y1337968D01*
X1366572Y1337555D01*
X1366725Y1337245D01*
X1366955Y1336986D01*
X1367262Y1336883D01*
X1367569Y1336986D01*
X1367799Y1337245D01*
X1367952Y1337555D01*
X1368067Y1337968D01*
X1368105Y1338433D01*
X1368067Y1338898D01*
X1367952Y1339311D01*
X1367799Y1339621D01*
X1367569Y1339880D01*
X1367262Y1339983D01*
G01X1369212Y1335850D02*
X1371512D01*
G01X1373462Y1336883D02*
Y1339983D01*
X1373002Y1339363D01*
G01Y1336883D02*
X1373922D01*
G01X1348179Y1325654D02*
X1349187D01*
G01X1348179Y1323800D02*
Y1325654D01*
G01X1348615Y1334983D02*
Y1328783D01*
G01X1349838Y1332495D02*
Y1335695D01*
G01X1356038Y1332495D02*
X1349838D01*
G01X1356038Y1335695D02*
Y1332495D01*
G01X1349838Y1335695D02*
X1356038D01*
G01X1363745Y1328318D02*
X1360545D01*
G01Y1334518D02*
X1363745D01*
G01X1360545Y1328318D02*
Y1334518D01*
G01X1377672Y1353946D02*
G03I-13386J0D01*
G01X1355055Y1375323D02*
Y1414693D01*
G01X1348516Y1375323D02*
X1355055D01*
G01X1356677Y1400695D02*
X1359877D01*
G01X1356677Y1394495D02*
Y1400695D01*
G01X1359877Y1394495D02*
X1356677D01*
G01X1359877Y1400695D02*
Y1394495D01*
G01X1355055Y1414693D02*
X1348516D01*
G01X1353399Y1653722D02*
X1353476Y1654394D01*
X1353591Y1654962D01*
X1353744Y1655479D01*
X1353936Y1656047D01*
X1354243Y1656822D01*
X1352709D01*
G01X1361350Y1653722D02*
X1361618Y1653774D01*
X1361925Y1653929D01*
X1362117Y1654187D01*
X1362193Y1654549D01*
X1362117Y1654910D01*
X1361887Y1655220D01*
X1361542Y1655375D01*
X1361158D01*
X1360928Y1655479D01*
X1360737Y1655737D01*
X1360660Y1656099D01*
X1360775Y1656460D01*
X1361043Y1656719D01*
X1361350Y1656822D01*
X1361657Y1656719D01*
X1361925Y1656460D01*
X1362040Y1656099D01*
X1361963Y1655737D01*
X1361772Y1655479D01*
X1361542Y1655375D01*
X1361158D01*
X1360813Y1655220D01*
X1360583Y1654910D01*
X1360507Y1654549D01*
X1360583Y1654187D01*
X1360775Y1653929D01*
X1361082Y1653774D01*
X1361350Y1653722D01*
G01X1367152Y79511D02*
Y82711D01*
G01X1373352Y79511D02*
X1367152D01*
G01X1373352Y82711D02*
Y79511D01*
G01X1367152Y82711D02*
X1373352D01*
G01X1367969Y84970D02*
X1364769D01*
G01X1367969Y91170D02*
Y84970D01*
G01X1364769D02*
Y91170D01*
G01X1367601Y93995D02*
X1364401D01*
G01X1367601Y100195D02*
Y93995D01*
G01X1364401Y100195D02*
X1367601D01*
G01X1364401Y93995D02*
Y100195D01*
G01X1364769Y91170D02*
X1367969D01*
G01X1364524Y102429D02*
Y108629D01*
G01X1367724Y102429D02*
X1364524D01*
G01X1367724Y108629D02*
Y102429D01*
G01X1364524Y108629D02*
X1367724D01*
G01X1376950Y117061D02*
Y123261D01*
G01X1380150Y117061D02*
X1376950D01*
G01Y123261D02*
X1380150D01*
G01X1369684Y161522D02*
Y145473D01*
G01Y169472D02*
Y165142D01*
G01Y187512D02*
Y181622D01*
G01Y236025D02*
Y216622D01*
G01Y210872D02*
Y207792D01*
G01X1367600Y829802D02*
X1385316Y833739D01*
G01X1367600Y829803D02*
X1385315Y833740D01*
G01X1385316Y1148700D02*
X1367600Y1152637D01*
G01X1385315Y1148701D02*
X1367600Y1152638D01*
G01X1367975Y1253612D02*
Y1231958D01*
G01X1375286Y1255690D02*
Y1298998D01*
G01X1380627Y1255690D02*
X1375286D01*
G01X1372636D02*
Y1291862D01*
G01X1367295Y1255690D02*
X1372636D01*
G01Y1295362D02*
Y1291862D01*
G01X1367865Y1302032D02*
X1367072D01*
G01X1367865Y1304632D02*
Y1302032D01*
G01X1375286Y1298998D02*
X1380627D01*
G01X1372636Y1295362D02*
Y1298998D01*
G01D02*
X1367295D01*
G01X1367865Y1325654D02*
Y1323463D01*
G01X1370474Y1317291D02*
X1373674D01*
G01X1370474Y1311091D02*
Y1317291D01*
G01X1373674Y1311091D02*
X1370474D01*
G01X1373674Y1317291D02*
Y1311091D01*
G01X1374476Y1316192D02*
X1377676D01*
G01X1374476Y1309992D02*
Y1316192D01*
G01X1377676Y1309992D02*
X1374476D01*
G01X1377676Y1316192D02*
Y1309992D01*
G01Y1320492D02*
X1374476D01*
G01X1377676Y1326692D02*
Y1320492D01*
G01X1374476D02*
Y1326692D01*
G01X1379213Y1336603D02*
Y1339703D01*
X1380133D01*
X1380440Y1339548D01*
X1380670Y1339186D01*
X1380747Y1338773D01*
X1380670Y1338360D01*
X1380478Y1338050D01*
X1380133Y1337895D01*
X1379213D01*
G01X1382237Y1339703D02*
Y1337481D01*
X1382390Y1337016D01*
X1382697Y1336706D01*
X1383080Y1336603D01*
X1383463Y1336706D01*
X1383770Y1337016D01*
X1383923Y1337481D01*
Y1339703D01*
G01X1386180Y1336603D02*
Y1339703D01*
X1385720Y1339083D01*
G01Y1336603D02*
X1386640D01*
G01X1388552Y1339186D02*
X1388782Y1339496D01*
X1389050Y1339651D01*
X1389357Y1339703D01*
X1389740Y1339600D01*
X1390008Y1339341D01*
X1390085Y1339031D01*
X1390047Y1338721D01*
X1389893Y1338463D01*
X1389127Y1337946D01*
X1388782Y1337585D01*
X1388552Y1337068D01*
X1388475Y1336603D01*
X1390085D01*
G01X1391230Y1335570D02*
X1393530D01*
G01X1394713Y1336603D02*
Y1339703D01*
X1395633D01*
X1395940Y1339548D01*
X1396170Y1339186D01*
X1396247Y1338773D01*
X1396170Y1338360D01*
X1395978Y1338050D01*
X1395633Y1337895D01*
X1394713D01*
G01X1398580Y1339703D02*
X1398273Y1339600D01*
X1398043Y1339341D01*
X1397890Y1339031D01*
X1397775Y1338618D01*
X1397737Y1338153D01*
X1397775Y1337688D01*
X1397890Y1337275D01*
X1398043Y1336965D01*
X1398273Y1336706D01*
X1398580Y1336603D01*
X1398887Y1336706D01*
X1399117Y1336965D01*
X1399270Y1337275D01*
X1399385Y1337688D01*
X1399423Y1338153D01*
X1399385Y1338618D01*
X1399270Y1339031D01*
X1399117Y1339341D01*
X1398887Y1339600D01*
X1398580Y1339703D01*
G01X1400530Y1335570D02*
X1402830D01*
G01X1404052Y1339186D02*
X1404282Y1339496D01*
X1404550Y1339651D01*
X1404857Y1339703D01*
X1405240Y1339600D01*
X1405508Y1339341D01*
X1405585Y1339031D01*
X1405547Y1338721D01*
X1405393Y1338463D01*
X1404627Y1337946D01*
X1404282Y1337585D01*
X1404052Y1337068D01*
X1403975Y1336603D01*
X1405585D01*
G01X1367132Y1325654D02*
X1367865D01*
G01X1374476Y1326692D02*
X1377676D01*
G01X1364570Y1334518D02*
X1367770D01*
G01X1364570Y1328318D02*
Y1334518D01*
G01X1367770Y1328318D02*
X1364570D01*
G01X1367770Y1334518D02*
Y1328318D01*
G01X1370637Y1328542D02*
Y1331742D01*
G01X1376837Y1328542D02*
X1370637D01*
G01X1376837Y1331742D02*
Y1328542D01*
G01X1370637Y1331742D02*
X1376837D01*
G01X1377514Y1334953D02*
X1380714D01*
G01X1377514Y1328753D02*
Y1334953D01*
G01X1380714Y1328753D02*
X1377514D01*
G01X1363745Y1334518D02*
Y1328318D01*
G01X1364286Y1340560D02*
Y1367332D01*
G01X1372117Y1379147D02*
Y1382247D01*
X1373037D01*
X1373344Y1382092D01*
X1373574Y1381730D01*
X1373651Y1381317D01*
X1373574Y1380904D01*
X1373382Y1380594D01*
X1373037Y1380439D01*
X1372117D01*
G01X1375217Y1379767D02*
X1375409Y1379457D01*
X1375639Y1379250D01*
X1375907Y1379147D01*
X1376214Y1379250D01*
X1376444Y1379457D01*
X1376674Y1379767D01*
X1376751Y1380180D01*
Y1382247D01*
G01X1379544Y1379147D02*
Y1382247D01*
X1378126Y1380025D01*
X1380042D01*
G01X1382107Y1379147D02*
X1382184Y1379819D01*
X1382299Y1380387D01*
X1382452Y1380904D01*
X1382644Y1381472D01*
X1382951Y1382247D01*
X1381417D01*
G01X1366412Y1394835D02*
X1366642Y1395145D01*
X1366910Y1395300D01*
X1367217Y1395352D01*
X1367600Y1395249D01*
X1367868Y1394990D01*
X1367945Y1394680D01*
X1367907Y1394370D01*
X1367753Y1394112D01*
X1366987Y1393595D01*
X1366642Y1393234D01*
X1366412Y1392717D01*
X1366335Y1392252D01*
X1367945D01*
G01X1370700D02*
Y1395352D01*
X1369282Y1393130D01*
X1371198D01*
G01X1374716Y1405058D02*
Y1401858D01*
G01X1368516Y1405058D02*
X1374716D01*
G01X1368516Y1401858D02*
Y1405058D01*
G01X1374716Y1401858D02*
X1368516D01*
G01X1374773Y1400653D02*
Y1397453D01*
G01X1368573Y1400653D02*
X1374773D01*
G01X1368573Y1397453D02*
Y1400653D01*
G01X1374773Y1397453D02*
X1368573D01*
G01X1377945Y1399084D02*
Y1402284D01*
G01X1384145Y1399084D02*
X1377945D01*
G01Y1402284D02*
X1384145D01*
G01X1377945Y1402607D02*
Y1405807D01*
G01X1384145Y1402607D02*
X1377945D01*
G01X1377940Y1412831D02*
X1384140D01*
G01X1377940Y1409631D02*
Y1412831D01*
G01X1384140Y1409631D02*
X1377940D01*
G01X1374716Y1409058D02*
Y1405858D01*
G01X1368516Y1409058D02*
X1374716D01*
G01X1368516Y1405858D02*
Y1409058D01*
G01X1374716Y1405858D02*
X1368516D01*
G01X1368526Y1415774D02*
Y1418974D01*
G01X1374726Y1415774D02*
X1368526D01*
G01X1374726Y1418974D02*
Y1415774D01*
G01X1368526Y1418974D02*
X1374726D01*
G01X1369366Y1411419D02*
Y1414619D01*
G01X1375566Y1411419D02*
X1369366D01*
G01X1375566Y1414619D02*
Y1411419D01*
G01X1369366Y1414619D02*
X1375566D01*
G01X1377945Y1405807D02*
X1384145D01*
G01X1377940Y1406127D02*
Y1409327D01*
G01X1384140Y1406127D02*
X1377940D01*
G01Y1409327D02*
X1384140D01*
G01X1375475Y1417881D02*
Y1424081D01*
G01X1378675Y1417881D02*
X1375475D01*
G01X1378675Y1424081D02*
Y1417881D01*
G01X1375475Y1424081D02*
X1378675D01*
G01X1379134Y1781456D02*
Y1646023D01*
G01X1367323Y1657834D02*
Y1769645D01*
G01X1376961Y1670099D02*
X1369461D01*
Y1672339D01*
X1369836Y1673086D01*
X1370711Y1673646D01*
X1371711Y1673833D01*
X1372711Y1673646D01*
X1373461Y1673179D01*
X1373836Y1672339D01*
Y1670099D01*
G01X1376961Y1677599D02*
X1369461D01*
Y1679933D01*
X1369836Y1680679D01*
X1370336Y1681146D01*
X1371336Y1681333D01*
X1372336Y1681146D01*
X1372961Y1680586D01*
X1373336Y1679933D01*
Y1677599D01*
G01Y1679933D02*
X1376961Y1681333D01*
G01Y1688833D02*
Y1685099D01*
X1369461D01*
Y1688833D01*
G01X1373086Y1687339D02*
Y1685099D01*
G01X1375961Y1692506D02*
X1376586Y1693253D01*
X1376961Y1694093D01*
Y1694839D01*
X1376586Y1695586D01*
X1375961Y1696146D01*
X1375086Y1696426D01*
X1374211Y1696239D01*
X1373461Y1695773D01*
X1372961Y1694933D01*
X1372711Y1693813D01*
X1372211Y1693159D01*
X1371336Y1692879D01*
X1370461Y1693066D01*
X1369836Y1693533D01*
X1369461Y1694186D01*
Y1694839D01*
X1369711Y1695493D01*
X1370336Y1696053D01*
G01X1375961Y1700006D02*
X1376586Y1700753D01*
X1376961Y1701593D01*
Y1702339D01*
X1376586Y1703086D01*
X1375961Y1703646D01*
X1375086Y1703926D01*
X1374211Y1703739D01*
X1373461Y1703273D01*
X1372961Y1702433D01*
X1372711Y1701313D01*
X1372211Y1700659D01*
X1371336Y1700379D01*
X1370461Y1700566D01*
X1369836Y1701033D01*
X1369461Y1701686D01*
Y1702339D01*
X1369711Y1702993D01*
X1370336Y1703553D01*
G01X1374461Y1708253D02*
Y1710679D01*
G01X1376961Y1715193D02*
X1369461D01*
Y1718739D01*
G01X1373086Y1717433D02*
Y1715193D01*
G01X1369461Y1723346D02*
Y1725586D01*
G01Y1724466D02*
X1376961D01*
G01Y1723346D02*
Y1725586D01*
G01X1369461Y1731966D02*
X1376961D01*
G01X1369461Y1729819D02*
Y1734113D01*
G01X1380150Y123261D02*
Y117061D01*
G01X1385316Y833739D02*
X1406478D01*
G01X1385315Y833740D02*
X1406477D01*
G01X1383663Y1032021D02*
Y931195D01*
G01X1401860D02*
X1383663D01*
G01X1396357Y940747D02*
Y934547D01*
X1393157D01*
Y940747D01*
X1396357D01*
G01X1393136Y942872D02*
Y949072D01*
X1396336D01*
Y942872D01*
X1393136D01*
G01X1389136D02*
Y949072D01*
X1392336D01*
Y942872D01*
X1389136D01*
G01X1396336Y955764D02*
Y949564D01*
X1393136D01*
Y955764D01*
X1396336D01*
G01X1392336D02*
Y949564D01*
X1389136D01*
Y955764D01*
X1392336D01*
G01X1388536D02*
Y949564D01*
X1385336D01*
Y955764D01*
X1388536D01*
G01X1389119Y934538D02*
Y940738D01*
X1392319D01*
Y934538D01*
X1389119D01*
G01X1385336Y942872D02*
Y949072D01*
X1388536D01*
Y942872D01*
X1385336D01*
G01X1388557Y940747D02*
Y934547D01*
X1385357D01*
Y940747D01*
X1388557D01*
G01X1388567Y957655D02*
X1385367D01*
G01X1388567Y963855D02*
Y957655D01*
G01X1385367Y963855D02*
X1388567D01*
G01X1385367Y957655D02*
Y963855D01*
G01X1389167Y963963D02*
Y970163D01*
G01X1392367Y963963D02*
X1389167D01*
G01X1392367Y970163D02*
Y963963D01*
G01X1393167D02*
Y970163D01*
G01X1396367Y963963D02*
X1393167D01*
G01X1392367Y957655D02*
X1389167D01*
G01X1392367Y963855D02*
Y957655D01*
G01X1389167Y963855D02*
X1392367D01*
G01X1389167Y957655D02*
Y963855D01*
G01X1396367Y957655D02*
X1393167D01*
G01Y963855D02*
X1396367D01*
G01X1393167Y957655D02*
Y963855D01*
G01X1388567Y970163D02*
Y963963D01*
X1385367D01*
Y970163D01*
X1388567D01*
G01X1392412Y972156D02*
X1389212D01*
G01X1392412Y978356D02*
Y972156D01*
G01X1389212Y978356D02*
X1392412D01*
G01X1389212Y972156D02*
Y978356D01*
G01X1396412Y972156D02*
X1393212D01*
G01Y978356D02*
X1396412D01*
G01X1393212Y972156D02*
Y978356D01*
G01X1389167Y970163D02*
X1392367D01*
G01X1393167D02*
X1396367D01*
G01X1396412Y984676D02*
Y978476D01*
X1393212D01*
Y984676D01*
X1396412D01*
G01X1392412D02*
Y978476D01*
X1389212D01*
Y984676D01*
X1392412D01*
G01X1388612D02*
Y978476D01*
X1385412D01*
Y984676D01*
X1388612D01*
G01X1385412Y972156D02*
Y978356D01*
X1388612D01*
Y972156D01*
X1385412D01*
G01X1389141Y992791D02*
Y998991D01*
G01X1392341Y992791D02*
X1389141D01*
G01X1392341Y998991D02*
Y992791D01*
G01X1385341D02*
Y998991D01*
G01X1388541Y992791D02*
X1385341D01*
G01X1388541Y998991D02*
Y992791D01*
G01X1393141Y986567D02*
Y992767D01*
X1396341D01*
Y986567D01*
X1393141D01*
G01X1389141D02*
Y992767D01*
X1392341D01*
Y986567D01*
X1389141D01*
G01X1385341D02*
Y992767D01*
X1388541D01*
Y986567D01*
X1385341D01*
G01X1396341Y998991D02*
Y992791D01*
X1393141D01*
Y998991D01*
X1396341D01*
G01X1393091Y1013549D02*
X1396291D01*
G01X1393091Y1007349D02*
Y1013549D01*
G01X1396291Y1007349D02*
X1393091D01*
G01X1392291Y1001049D02*
X1389091D01*
G01X1392291Y1007249D02*
Y1001049D01*
G01X1389091Y1007249D02*
X1392291D01*
G01X1389091Y1001049D02*
Y1007249D01*
G01X1396291Y1001049D02*
X1393091D01*
G01Y1007249D02*
X1396291D01*
G01X1393091Y1001049D02*
Y1007249D01*
G01X1389141Y998991D02*
X1392341D01*
G01X1388491Y1001049D02*
X1385291D01*
G01X1388491Y1007249D02*
Y1001049D01*
G01X1385291Y1007249D02*
X1388491D01*
G01X1385291Y1001049D02*
Y1007249D01*
G01X1385341Y998991D02*
X1388541D01*
G01X1392291Y1013549D02*
Y1007349D01*
X1389091D01*
Y1013549D01*
X1392291D01*
G01X1388491D02*
Y1007349D01*
X1385291D01*
Y1013549D01*
X1388491D01*
G01X1396332Y1015509D02*
X1393132D01*
G01Y1021709D02*
X1396332D01*
G01X1393132Y1015509D02*
Y1021709D01*
G01X1385269Y1015509D02*
Y1021709D01*
X1388469D01*
Y1015509D01*
X1385269D01*
G01X1389132D02*
Y1021709D01*
X1392332D01*
Y1015509D01*
X1389132D01*
G01X1392332Y1028159D02*
Y1021959D01*
X1389132D01*
Y1028159D01*
X1392332D01*
G01X1388469D02*
Y1021959D01*
X1385269D01*
Y1028159D01*
X1388469D01*
G01X1396332D02*
Y1021959D01*
X1393132D01*
Y1028159D01*
X1396332D01*
G01X1383663Y1032021D02*
X1401860D01*
G01X1397220Y1154520D02*
X1385220D01*
G01Y1160520D02*
X1397220D01*
G01X1385220Y1154520D02*
Y1160520D01*
G01X1406478Y1148700D02*
X1385316D01*
G01X1406477Y1148701D02*
X1385315D01*
G01X1397220Y1162570D02*
X1385220D01*
G01Y1168570D02*
X1397220D01*
G01X1385220Y1162570D02*
Y1168570D01*
G01X1392375Y1253612D02*
Y1231958D01*
G01X1403202Y1242785D02*
G03I-10827J0D01*
G01X1380307Y1302032D02*
Y1304632D01*
G01X1381100Y1302032D02*
X1380307D01*
G01Y1311243D02*
Y1312941D01*
G01Y1325654D02*
X1381315D01*
G01X1380307Y1323800D02*
Y1325654D01*
G01X1380714Y1334953D02*
Y1328753D01*
G01X1383584Y1332495D02*
Y1335695D01*
G01X1389784Y1332495D02*
X1383584D01*
G01X1389784Y1335695D02*
Y1332495D01*
G01X1383584Y1335695D02*
X1389784D01*
G01X1394845Y1328318D02*
X1391645D01*
G01X1394845Y1334518D02*
Y1328318D01*
G01X1391645Y1334518D02*
X1394845D01*
G01X1391645Y1328318D02*
Y1334518D01*
G01X1394052Y1340560D02*
Y1367332D01*
G01X1407438Y1353946D02*
G03I-13386J0D01*
G01X1390018Y1388706D02*
Y1391906D01*
G01X1396218Y1388706D02*
X1390018D01*
G01X1382576Y1388735D02*
Y1391935D01*
G01X1388776Y1388735D02*
X1382576D01*
G01X1388776Y1391935D02*
Y1388735D01*
G01X1394954Y1399489D02*
Y1397489D01*
G01X1393808Y1400978D02*
X1391804D01*
G01D02*
Y1403064D01*
G01X1390018Y1391906D02*
X1396218D01*
G01X1384581Y1398753D02*
X1387781D01*
G01X1384581Y1392553D02*
Y1398753D01*
G01X1387781Y1392553D02*
X1384581D01*
G01X1387781Y1398753D02*
Y1392553D01*
G01X1384145Y1402284D02*
Y1399084D01*
G01Y1405807D02*
Y1402607D01*
G01X1382576Y1391935D02*
X1388776D01*
G01X1383947Y1392503D02*
X1380747D01*
G01X1383947Y1398703D02*
Y1392503D01*
G01X1380747Y1398703D02*
X1383947D01*
G01X1380747Y1392503D02*
Y1398703D01*
G01X1390363Y1410427D02*
X1386863D01*
G01X1388380Y1418301D02*
X1390380D01*
G01X1384140Y1412831D02*
Y1409631D01*
G01X1386666Y1417903D02*
X1383466D01*
G01X1386666Y1424103D02*
Y1417903D01*
G01X1383466D02*
Y1424103D01*
G01X1385737Y1417095D02*
Y1413895D01*
G01X1379537Y1417095D02*
X1385737D01*
G01X1379537Y1413895D02*
Y1417095D01*
G01X1385737Y1413895D02*
X1379537D01*
G01X1379466Y1417903D02*
Y1424103D01*
G01X1382666Y1417903D02*
X1379466D01*
G01X1382666Y1424103D02*
Y1417903D01*
G01X1384140Y1409327D02*
Y1406127D01*
G01X1389610Y1433442D02*
Y1436542D01*
X1389150Y1435922D01*
G01Y1433442D02*
X1390070D01*
G01X1391982Y1436025D02*
X1392212Y1436335D01*
X1392480Y1436490D01*
X1392787Y1436542D01*
X1393170Y1436439D01*
X1393438Y1436180D01*
X1393515Y1435870D01*
X1393477Y1435560D01*
X1393323Y1435302D01*
X1392557Y1434785D01*
X1392212Y1434424D01*
X1391982Y1433907D01*
X1391905Y1433442D01*
X1393515D01*
G01X1386140Y1424862D02*
Y1427962D01*
X1385680Y1427342D01*
G01Y1424862D02*
X1386600D01*
G01X1388397Y1425482D02*
X1388627Y1425120D01*
X1388933Y1424914D01*
X1389278Y1424862D01*
X1389585Y1424914D01*
X1389892Y1425172D01*
X1390083Y1425482D01*
X1390122Y1425792D01*
X1390045Y1426154D01*
X1389777Y1426412D01*
X1389508Y1426515D01*
X1389163D01*
G01X1389508D02*
X1389738Y1426670D01*
X1389930Y1426929D01*
X1390007Y1427239D01*
X1389930Y1427549D01*
X1389738Y1427807D01*
X1389393Y1427962D01*
X1389048Y1427910D01*
X1388703Y1427704D01*
G01X1391804Y1422703D02*
Y1424600D01*
G01D02*
X1393808D01*
G01X1383466Y1424103D02*
X1386666D01*
G01X1379466D02*
X1382666D01*
G01X1384120Y1434962D02*
X1387320D01*
G01X1384120Y1428762D02*
Y1434962D01*
G01X1387320Y1428762D02*
X1384120D01*
G01X1387320Y1434962D02*
Y1428762D01*
G01X1389393Y1440022D02*
Y1443122D01*
X1390313D01*
X1390620Y1442967D01*
X1390850Y1442605D01*
X1390927Y1442192D01*
X1390850Y1441779D01*
X1390658Y1441469D01*
X1390313Y1441314D01*
X1389393D01*
G01X1392417Y1443122D02*
Y1440900D01*
X1392570Y1440435D01*
X1392877Y1440125D01*
X1393260Y1440022D01*
X1393643Y1440125D01*
X1393950Y1440435D01*
X1394103Y1440900D01*
Y1443122D01*
G01X1396360Y1440022D02*
Y1443122D01*
X1395900Y1442502D01*
G01Y1440022D02*
X1396820D01*
G01X1399920D02*
Y1443122D01*
X1398502Y1440900D01*
X1400418D01*
G01X1401700Y1519762D02*
X1395500D01*
Y1522962D01*
X1401700D01*
Y1519762D01*
G01X1401600Y1535562D02*
X1395400D01*
Y1538762D01*
X1401600D01*
Y1535562D01*
G01Y1546762D02*
X1395400D01*
Y1549962D01*
X1401600D01*
Y1546762D01*
G01X1393308Y1566637D02*
X1399508D01*
G01X1393308Y1563437D02*
Y1566637D01*
G01X1399508Y1563437D02*
X1393308D01*
G01X1393482Y1577697D02*
X1399682D01*
G01X1393482Y1574497D02*
Y1577697D01*
G01X1399682Y1574497D02*
X1393482D01*
G01X1393308Y1571637D02*
X1399508D01*
G01X1393308Y1568437D02*
Y1571637D01*
G01X1399508Y1568437D02*
X1393308D01*
G01X1393800Y1611122D02*
X1400000D01*
G01X1393800Y1607922D02*
Y1611122D01*
G01X1400000Y1607922D02*
X1393800D01*
G01X1414418Y112008D02*
G03I-9300J0D01*
G01X1407283Y226348D02*
Y229548D01*
G01X1413483Y226348D02*
X1407283D01*
G01Y229548D02*
X1413483D01*
G01X1406478Y833739D02*
X1410710Y841613D01*
G01X1406477Y833740D02*
X1410709Y841614D01*
G01X1410710Y841613D02*
X1422915D01*
G01X1410709Y841614D02*
X1422914D01*
G01X1401860Y931195D02*
Y1032021D01*
G01X1400157Y940747D02*
Y934547D01*
X1396957D01*
Y940747D01*
X1400157D01*
G01X1396936Y942872D02*
Y949072D01*
X1400136D01*
Y942872D01*
X1396936D01*
G01X1400136Y955764D02*
Y949564D01*
X1396936D01*
Y955764D01*
X1400136D01*
G01X1396967Y963963D02*
Y970163D01*
G01X1400167Y963963D02*
X1396967D01*
G01X1400167Y970163D02*
Y963963D01*
G01X1396367Y970163D02*
Y963963D01*
G01Y963855D02*
Y957655D01*
G01X1396967D02*
Y963855D01*
X1400167D01*
Y957655D01*
X1396967D01*
G01X1397012Y978476D02*
Y984676D01*
G01X1400212Y978476D02*
X1397012D01*
G01X1400212Y984676D02*
Y978476D01*
G01Y972156D02*
X1397012D01*
G01X1400212Y978356D02*
Y972156D01*
G01X1397012Y978356D02*
X1400212D01*
G01X1397012Y972156D02*
Y978356D01*
G01X1396967Y970163D02*
X1400167D01*
G01X1396412Y978356D02*
Y972156D01*
G01X1397012Y984676D02*
X1400212D01*
G01X1396941Y986567D02*
Y992767D01*
X1400141D01*
Y986567D01*
X1396941D01*
G01X1400141Y998991D02*
Y992791D01*
X1396941D01*
Y998991D01*
X1400141D01*
G01X1396891Y1013549D02*
X1400091D01*
G01X1396891Y1007349D02*
Y1013549D01*
G01X1400091Y1007349D02*
X1396891D01*
G01X1400091Y1013549D02*
Y1007349D01*
G01Y1001049D02*
X1396891D01*
G01X1400091Y1007249D02*
Y1001049D01*
G01X1396891Y1007249D02*
X1400091D01*
G01X1396891Y1001049D02*
Y1007249D01*
G01X1396291Y1013549D02*
Y1007349D01*
G01Y1007249D02*
Y1001049D01*
G01X1400132Y1015509D02*
X1396932D01*
G01X1400132Y1021709D02*
Y1015509D01*
G01X1396932Y1021709D02*
X1400132D01*
G01X1396932Y1015509D02*
Y1021709D01*
G01X1396332D02*
Y1015509D01*
G01X1400132Y1028159D02*
Y1021959D01*
X1396932D01*
Y1028159D01*
X1400132D01*
G01X1410710Y1140826D02*
X1406478Y1148700D01*
G01X1410709Y1140827D02*
X1406477Y1148701D01*
G01X1422915Y1140826D02*
X1410710D01*
G01X1422914Y1140827D02*
X1410709D01*
G01X1397220Y1160520D02*
Y1154520D01*
G01X1397720Y1160520D02*
X1409720D01*
G01X1397720Y1154520D02*
Y1160520D01*
G01X1409720Y1154520D02*
X1397720D01*
G01X1409720Y1160520D02*
Y1154520D01*
G01X1422220D02*
X1410220D01*
G01Y1160520D02*
X1422220D01*
G01X1410220Y1154520D02*
Y1160520D01*
G01X1397720Y1168570D02*
X1409720D01*
G01X1397720Y1162570D02*
Y1168570D01*
G01X1409720Y1162570D02*
X1397720D01*
G01X1409720Y1168570D02*
Y1162570D01*
G01X1422220D02*
X1410220D01*
G01Y1168570D02*
X1422220D01*
G01X1410220Y1162570D02*
Y1168570D01*
G01X1397220D02*
Y1162570D01*
G01X1427524Y1242785D02*
G03I-10827J0D01*
G01X1407633Y1255690D02*
Y1298998D01*
G01X1412974Y1255690D02*
X1407633D01*
G01X1404814D02*
Y1291362D01*
G01X1399473Y1255690D02*
X1404814D01*
G01Y1294862D02*
Y1291362D01*
G01X1399993Y1302032D02*
X1399200D01*
G01X1399993Y1304632D02*
Y1302032D01*
G01X1407633Y1298998D02*
X1412974D01*
G01X1404814Y1294862D02*
Y1298998D01*
G01D02*
X1399473D01*
G01X1399993Y1325654D02*
Y1323463D01*
G01X1406604Y1316192D02*
X1409804D01*
G01X1406604Y1309992D02*
Y1316192D01*
G01X1409804Y1309992D02*
X1406604D01*
G01X1409804Y1316192D02*
Y1309992D01*
G01X1402602Y1317291D02*
X1405802D01*
G01X1402602Y1311091D02*
Y1317291D01*
G01X1405802Y1311091D02*
X1402602D01*
G01X1405802Y1317291D02*
Y1311091D01*
G01X1409804Y1320492D02*
X1406604D01*
G01X1409804Y1326692D02*
Y1320492D01*
G01X1406604D02*
Y1326692D01*
G01X1399260Y1325654D02*
X1399993D01*
G01X1406604Y1326692D02*
X1409804D01*
G01X1409524Y1334982D02*
X1412724D01*
G01X1409524Y1328782D02*
Y1334982D01*
G01X1412724Y1328782D02*
X1409524D01*
G01X1402196Y1328442D02*
Y1331642D01*
G01X1408396Y1328442D02*
X1402196D01*
G01X1408396Y1331642D02*
Y1328442D01*
G01X1402196Y1331642D02*
X1408396D01*
G01X1395765Y1334518D02*
X1398965D01*
G01X1395765Y1328318D02*
Y1334518D01*
G01X1398965Y1328318D02*
X1395765D01*
G01X1398965Y1334518D02*
Y1328318D01*
G01X1437774Y1353946D02*
G03I-13386J0D01*
G01X1396218Y1391906D02*
Y1388706D01*
G01X1411837Y1393592D02*
X1412067Y1393230D01*
X1412373Y1393024D01*
X1412718Y1392972D01*
X1413025Y1393024D01*
X1413332Y1393282D01*
X1413523Y1393592D01*
X1413562Y1393902D01*
X1413485Y1394264D01*
X1413217Y1394522D01*
X1412948Y1394625D01*
X1412603D01*
G01X1412948D02*
X1413178Y1394780D01*
X1413370Y1395039D01*
X1413447Y1395349D01*
X1413370Y1395659D01*
X1413178Y1395917D01*
X1412833Y1396072D01*
X1412488Y1396020D01*
X1412143Y1395814D01*
G01X1415052Y1394264D02*
X1415320Y1394625D01*
X1415550Y1394832D01*
X1415857Y1394935D01*
X1416125Y1394832D01*
X1416317Y1394625D01*
X1416470Y1394315D01*
X1416508Y1393954D01*
X1416470Y1393644D01*
X1416317Y1393334D01*
X1416087Y1393075D01*
X1415818Y1392972D01*
X1415512Y1393075D01*
X1415243Y1393385D01*
X1415090Y1393850D01*
X1415052Y1394367D01*
X1415128Y1395039D01*
X1415243Y1395400D01*
X1415435Y1395762D01*
X1415703Y1396020D01*
X1415972Y1396072D01*
X1416240Y1395969D01*
X1416432Y1395710D01*
G01X1396322Y1398665D02*
X1396552Y1398975D01*
X1396820Y1399130D01*
X1397127Y1399182D01*
X1397510Y1399079D01*
X1397778Y1398820D01*
X1397855Y1398510D01*
X1397817Y1398200D01*
X1397663Y1397942D01*
X1396897Y1397425D01*
X1396552Y1397064D01*
X1396322Y1396547D01*
X1396245Y1396082D01*
X1397855D01*
G01X1399307Y1396547D02*
X1399537Y1396289D01*
X1399805Y1396134D01*
X1400150Y1396082D01*
X1400495Y1396185D01*
X1400763Y1396392D01*
X1400955Y1396754D01*
X1400993Y1397167D01*
X1400917Y1397580D01*
X1400725Y1397839D01*
X1400457Y1398045D01*
X1400188Y1398097D01*
X1399920Y1398045D01*
X1399575Y1397839D01*
X1399690Y1399182D01*
X1400725D01*
G01X1410702Y1399589D02*
Y1397589D01*
G01X1402828Y1399589D02*
Y1396089D01*
G01X1410260Y1428212D02*
Y1431312D01*
X1408842Y1429090D01*
X1410758D01*
G01X1412900Y1428212D02*
X1413168Y1428264D01*
X1413475Y1428419D01*
X1413667Y1428677D01*
X1413743Y1429039D01*
X1413667Y1429400D01*
X1413437Y1429710D01*
X1413092Y1429865D01*
X1412708D01*
X1412478Y1429969D01*
X1412287Y1430227D01*
X1412210Y1430589D01*
X1412325Y1430950D01*
X1412593Y1431209D01*
X1412900Y1431312D01*
X1413207Y1431209D01*
X1413475Y1430950D01*
X1413590Y1430589D01*
X1413513Y1430227D01*
X1413322Y1429969D01*
X1413092Y1429865D01*
X1412708D01*
X1412363Y1429710D01*
X1412133Y1429400D01*
X1412057Y1429039D01*
X1412133Y1428677D01*
X1412325Y1428419D01*
X1412632Y1428264D01*
X1412900Y1428212D01*
G01X1398103Y1426089D02*
Y1429589D01*
G01X1405977Y1426089D02*
Y1427589D01*
G01X1410533Y1518035D02*
Y1514835D01*
G01X1404333Y1518035D02*
X1410533D01*
G01X1404333Y1514835D02*
Y1518035D01*
G01X1410533Y1514835D02*
X1404333D01*
G01X1410773Y1533855D02*
Y1530655D01*
G01X1404573Y1533855D02*
X1410773D01*
G01X1404573Y1530655D02*
Y1533855D01*
G01X1410773Y1530655D02*
X1404573D01*
G01X1410533Y1522935D02*
Y1519735D01*
G01X1404333Y1522935D02*
X1410533D01*
G01X1404333Y1519735D02*
Y1522935D01*
G01X1410533Y1519735D02*
X1404333D01*
G01X1410923Y1545075D02*
Y1541875D01*
G01X1404723Y1545075D02*
X1410923D01*
G01X1404723Y1541875D02*
Y1545075D01*
G01X1410923Y1541875D02*
X1404723D01*
G01X1410773Y1538755D02*
Y1535555D01*
G01X1404573Y1538755D02*
X1410773D01*
G01X1404573Y1535555D02*
Y1538755D01*
G01X1410773Y1535555D02*
X1404573D01*
G01X1410923Y1549975D02*
Y1546775D01*
G01X1404723Y1549975D02*
X1410923D01*
G01X1404723Y1546775D02*
Y1549975D01*
G01X1410923Y1546775D02*
X1404723D01*
G01X1405308Y1563437D02*
Y1566637D01*
G01X1411508Y1563437D02*
X1405308D01*
G01X1411508Y1566637D02*
Y1563437D01*
G01X1405308Y1566637D02*
X1411508D01*
G01X1399508D02*
Y1563437D01*
G01X1406753Y1590331D02*
X1410100D01*
X1412000Y1588131D01*
X1413900Y1590331D01*
X1417247D01*
Y1581669D01*
X1406753D01*
Y1590331D01*
G01X1404000Y1580900D02*
X1397800D01*
Y1584100D01*
X1404000D01*
Y1580900D01*
G01X1399682Y1577697D02*
Y1574497D01*
G01X1405248Y1574597D02*
Y1577797D01*
G01X1411448Y1574597D02*
X1405248D01*
G01X1411448Y1577797D02*
Y1574597D01*
G01X1405248Y1577797D02*
X1411448D01*
G01X1405308Y1568437D02*
Y1571637D01*
G01X1411508Y1568437D02*
X1405308D01*
G01X1411508Y1571637D02*
Y1568437D01*
G01X1405308Y1571637D02*
X1411508D01*
G01X1399508D02*
Y1568437D01*
G01X1406550Y1598951D02*
X1417430D01*
G01X1406550Y1607613D02*
Y1598951D01*
G01X1397100Y1598682D02*
Y1604882D01*
G01X1400300Y1598682D02*
X1397100D01*
G01X1400300Y1604882D02*
Y1598682D01*
G01X1401080Y1598672D02*
Y1604872D01*
G01X1404280Y1598672D02*
X1401080D01*
G01X1404280Y1604872D02*
Y1598672D01*
G01X1404000Y1592400D02*
X1397800D01*
Y1595600D01*
X1404000D01*
Y1592400D01*
G01X1397800Y1588000D02*
X1404000D01*
Y1584800D01*
X1397800D01*
Y1588000D01*
G01Y1591800D02*
X1404000D01*
Y1588600D01*
X1397800D01*
Y1591800D01*
G01X1401077Y1614982D02*
Y1612760D01*
X1401230Y1612295D01*
X1401537Y1611985D01*
X1401920Y1611882D01*
X1402303Y1611985D01*
X1402610Y1612295D01*
X1402763Y1612760D01*
Y1614982D01*
G01X1404177Y1612502D02*
X1404407Y1612140D01*
X1404713Y1611934D01*
X1405058Y1611882D01*
X1405365Y1611934D01*
X1405672Y1612192D01*
X1405863Y1612502D01*
X1405902Y1612812D01*
X1405825Y1613174D01*
X1405557Y1613432D01*
X1405288Y1613535D01*
X1404943D01*
G01X1405288D02*
X1405518Y1613690D01*
X1405710Y1613949D01*
X1405787Y1614259D01*
X1405710Y1614569D01*
X1405518Y1614827D01*
X1405173Y1614982D01*
X1404828Y1614930D01*
X1404483Y1614724D01*
G01X1408120Y1611882D02*
Y1614982D01*
X1407660Y1614362D01*
G01Y1611882D02*
X1408580D01*
G01X1410492Y1613174D02*
X1410760Y1613535D01*
X1410990Y1613742D01*
X1411297Y1613845D01*
X1411565Y1613742D01*
X1411757Y1613535D01*
X1411910Y1613225D01*
X1411948Y1612864D01*
X1411910Y1612554D01*
X1411757Y1612244D01*
X1411527Y1611985D01*
X1411258Y1611882D01*
X1410952Y1611985D01*
X1410683Y1612295D01*
X1410530Y1612760D01*
X1410492Y1613277D01*
X1410568Y1613949D01*
X1410683Y1614310D01*
X1410875Y1614672D01*
X1411143Y1614930D01*
X1411412Y1614982D01*
X1411680Y1614879D01*
X1411872Y1614620D01*
G01X1414321Y1607613D02*
X1411990Y1605282D01*
G01X1409659Y1607613D02*
X1406550D01*
G01X1411990Y1605282D02*
X1409659Y1607613D01*
G01X1400000Y1611122D02*
Y1607922D01*
G01X1397100Y1604882D02*
X1400300D01*
G01X1401080Y1604872D02*
X1404280D01*
G01X1407100Y1628762D02*
X1400900D01*
Y1631962D01*
X1407100D01*
Y1628762D01*
G01X1400900Y1627962D02*
X1407100D01*
Y1624762D01*
X1400900D01*
Y1627962D01*
G01Y1635962D02*
X1407100D01*
Y1632762D01*
X1400900D01*
Y1635962D01*
G01X1409375Y1623800D02*
X1415575D01*
Y1620600D01*
X1409375D01*
Y1623800D01*
G01X1407100Y1640762D02*
X1400900D01*
Y1643962D01*
X1407100D01*
Y1640762D01*
G01X1400900Y1639962D02*
X1407100D01*
Y1636762D01*
X1400900D01*
Y1639962D01*
G01X1402559Y1656968D02*
X1430315D01*
G01X1402559Y1782165D02*
Y1656968D01*
G01X1430315Y1740117D02*
X1402559D01*
G01X1430315Y1782165D02*
X1402559D01*
G01X1418065Y120792D02*
Y123892D01*
G01X1419675D02*
Y120792D01*
G01Y122342D02*
X1418065D01*
G01X1421127Y121412D02*
X1421357Y121050D01*
X1421663Y120844D01*
X1422008Y120792D01*
X1422315Y120844D01*
X1422622Y121102D01*
X1422813Y121412D01*
X1422852Y121722D01*
X1422775Y122084D01*
X1422507Y122342D01*
X1422238Y122445D01*
X1421893D01*
G01X1422238D02*
X1422468Y122600D01*
X1422660Y122859D01*
X1422737Y123169D01*
X1422660Y123479D01*
X1422468Y123737D01*
X1422123Y123892D01*
X1421778Y123840D01*
X1421433Y123634D01*
G01X1424342Y122084D02*
X1424610Y122445D01*
X1424840Y122652D01*
X1425147Y122755D01*
X1425415Y122652D01*
X1425607Y122445D01*
X1425760Y122135D01*
X1425798Y121774D01*
X1425760Y121464D01*
X1425607Y121154D01*
X1425377Y120895D01*
X1425108Y120792D01*
X1424802Y120895D01*
X1424533Y121205D01*
X1424380Y121670D01*
X1424342Y122187D01*
X1424418Y122859D01*
X1424533Y123220D01*
X1424725Y123582D01*
X1424993Y123840D01*
X1425262Y123892D01*
X1425530Y123789D01*
X1425722Y123530D01*
G01X1413483Y229548D02*
Y226348D01*
G01X1425983Y229548D02*
Y226348D01*
G01X1419783Y229548D02*
X1425983D01*
G01X1419783Y226348D02*
Y229548D01*
G01X1425983Y226348D02*
X1419783D01*
G01X1416883Y277500D02*
Y280600D01*
X1417803D01*
X1418110Y280445D01*
X1418340Y280083D01*
X1418417Y279670D01*
X1418340Y279257D01*
X1418148Y278947D01*
X1417803Y278792D01*
X1416883D01*
G01X1420750Y277500D02*
Y280600D01*
X1420290Y279980D01*
G01Y277500D02*
X1421210D01*
G01X1423122Y280083D02*
X1423352Y280393D01*
X1423620Y280548D01*
X1423927Y280600D01*
X1424310Y280497D01*
X1424578Y280238D01*
X1424655Y279928D01*
X1424617Y279618D01*
X1424463Y279360D01*
X1423697Y278843D01*
X1423352Y278482D01*
X1423122Y277965D01*
X1423045Y277500D01*
X1424655D01*
G01X1425992Y280600D02*
X1426950Y277500D01*
X1427908Y280600D01*
G01X1428900Y276467D02*
X1431200D01*
G01X1432192Y277500D02*
X1433150Y280600D01*
X1434108Y277500D01*
G01X1433763Y278585D02*
X1432537D01*
G01X1435407Y280600D02*
Y278378D01*
X1435560Y277913D01*
X1435867Y277603D01*
X1436250Y277500D01*
X1436633Y277603D01*
X1436940Y277913D01*
X1437093Y278378D01*
Y280600D01*
G01X1438545Y277500D02*
X1440155Y280600D01*
G01X1438545D02*
X1440155Y277500D01*
G01X1415500Y289500D02*
X1442500D01*
Y275000D01*
X1414000D01*
Y289500D01*
X1415500D01*
G01X1422915Y841613D02*
X1427147Y833739D01*
G01D02*
X1448308D01*
G01X1422914Y841614D02*
X1427146Y833740D01*
G01D02*
X1448307D01*
G01X1427147Y1148700D02*
X1422915Y1140826D01*
G01X1427146Y1148701D02*
X1422914Y1140827D01*
G01X1422720Y1160520D02*
X1434720D01*
G01X1422720Y1154520D02*
Y1160520D01*
G01X1434720Y1154520D02*
X1422720D01*
G01X1422220Y1160520D02*
Y1154520D01*
G01X1448308Y1148700D02*
X1427147D01*
G01X1448307Y1148701D02*
X1427146D01*
G01X1422220Y1168570D02*
Y1162570D01*
G01X1422720Y1168570D02*
X1434720D01*
G01X1422720Y1162570D02*
Y1168570D01*
G01X1434720Y1162570D02*
X1422720D01*
G01X1416697Y1253612D02*
Y1231958D01*
G01X1412435Y1302032D02*
Y1304632D01*
G01X1413228Y1302032D02*
X1412435D01*
G01Y1311243D02*
Y1312941D01*
G01X1413953Y1337072D02*
Y1340172D01*
X1414873D01*
X1415180Y1340017D01*
X1415410Y1339655D01*
X1415487Y1339242D01*
X1415410Y1338829D01*
X1415218Y1338519D01*
X1414873Y1338364D01*
X1413953D01*
G01X1416977Y1340172D02*
Y1337950D01*
X1417130Y1337485D01*
X1417437Y1337175D01*
X1417820Y1337072D01*
X1418203Y1337175D01*
X1418510Y1337485D01*
X1418663Y1337950D01*
Y1340172D01*
G01X1420920Y1337072D02*
Y1340172D01*
X1420460Y1339552D01*
G01Y1337072D02*
X1421380D01*
G01X1424020D02*
Y1340172D01*
X1423560Y1339552D01*
G01Y1337072D02*
X1424480D01*
G01X1425970Y1336039D02*
X1428270D01*
G01X1429453Y1337072D02*
Y1340172D01*
X1430373D01*
X1430680Y1340017D01*
X1430910Y1339655D01*
X1430987Y1339242D01*
X1430910Y1338829D01*
X1430718Y1338519D01*
X1430373Y1338364D01*
X1429453D01*
G01X1433320Y1340172D02*
X1433013Y1340069D01*
X1432783Y1339810D01*
X1432630Y1339500D01*
X1432515Y1339087D01*
X1432477Y1338622D01*
X1432515Y1338157D01*
X1432630Y1337744D01*
X1432783Y1337434D01*
X1433013Y1337175D01*
X1433320Y1337072D01*
X1433627Y1337175D01*
X1433857Y1337434D01*
X1434010Y1337744D01*
X1434125Y1338157D01*
X1434163Y1338622D01*
X1434125Y1339087D01*
X1434010Y1339500D01*
X1433857Y1339810D01*
X1433627Y1340069D01*
X1433320Y1340172D01*
G01X1435270Y1336039D02*
X1437570D01*
G01X1438677Y1337692D02*
X1438907Y1337330D01*
X1439213Y1337124D01*
X1439558Y1337072D01*
X1439865Y1337124D01*
X1440172Y1337382D01*
X1440363Y1337692D01*
X1440402Y1338002D01*
X1440325Y1338364D01*
X1440057Y1338622D01*
X1439788Y1338725D01*
X1439443D01*
G01X1439788D02*
X1440018Y1338880D01*
X1440210Y1339139D01*
X1440287Y1339449D01*
X1440210Y1339759D01*
X1440018Y1340017D01*
X1439673Y1340172D01*
X1439328Y1340120D01*
X1438983Y1339914D01*
G01X1412435Y1325654D02*
X1413443D01*
G01X1412435Y1323800D02*
Y1325654D01*
G01X1427502Y1334510D02*
X1430702D01*
G01X1427502Y1328310D02*
Y1334510D01*
G01X1430702Y1328310D02*
X1427502D01*
G01X1412724Y1334982D02*
Y1328782D01*
G01X1414094Y1332495D02*
Y1335695D01*
G01X1420294Y1332495D02*
X1414094D01*
G01X1420294Y1335695D02*
Y1332495D01*
G01X1414094Y1335695D02*
X1420294D01*
G01X1426614Y1328318D02*
X1423414D01*
G01X1426614Y1334518D02*
Y1328318D01*
G01X1423414Y1334518D02*
X1426614D01*
G01X1423414Y1328318D02*
Y1334518D01*
G01X1424388Y1340560D02*
Y1367332D01*
G01X1452507Y1379362D02*
G03I-13386J0D01*
G01X1416937Y1401352D02*
X1417167Y1400990D01*
X1417473Y1400784D01*
X1417818Y1400732D01*
X1418125Y1400784D01*
X1418432Y1401042D01*
X1418623Y1401352D01*
X1418662Y1401662D01*
X1418585Y1402024D01*
X1418317Y1402282D01*
X1418048Y1402385D01*
X1417703D01*
G01X1418048D02*
X1418278Y1402540D01*
X1418470Y1402799D01*
X1418547Y1403109D01*
X1418470Y1403419D01*
X1418278Y1403677D01*
X1417933Y1403832D01*
X1417588Y1403780D01*
X1417243Y1403574D01*
G01X1420803Y1400732D02*
X1420880Y1401404D01*
X1420995Y1401972D01*
X1421148Y1402489D01*
X1421340Y1403057D01*
X1421647Y1403832D01*
X1420113D01*
G01X1415426Y1403193D02*
Y1400978D01*
G01D02*
X1413344D01*
G01X1425630Y1392359D02*
Y1395559D01*
G01X1431830Y1392359D02*
X1425630D01*
G01Y1395559D02*
X1431830D01*
G01X1425555Y1402079D02*
X1428755D01*
G01X1425555Y1395879D02*
Y1402079D01*
G01X1428755Y1395879D02*
X1425555D01*
G01X1420365Y1408852D02*
X1416865D01*
G01X1416915Y1416726D02*
X1418915D01*
G01X1424642Y1415525D02*
Y1418725D01*
G01X1430842Y1415525D02*
X1424642D01*
G01Y1418725D02*
X1430842D01*
G01X1424642Y1411525D02*
Y1414725D01*
G01X1430842Y1411525D02*
X1424642D01*
G01Y1414725D02*
X1430842D01*
G01X1424642Y1407525D02*
Y1410725D01*
G01X1430842Y1407525D02*
X1424642D01*
G01Y1410725D02*
X1430842D01*
G01X1424642Y1419025D02*
Y1422225D01*
G01X1430842Y1419025D02*
X1424642D01*
G01X1416150Y1438122D02*
Y1441222D01*
X1414732Y1439000D01*
X1416648D01*
G01X1418790Y1438122D02*
X1419058Y1438174D01*
X1419365Y1438329D01*
X1419557Y1438587D01*
X1419633Y1438949D01*
X1419557Y1439310D01*
X1419327Y1439620D01*
X1418982Y1439775D01*
X1418598D01*
X1418368Y1439879D01*
X1418177Y1440137D01*
X1418100Y1440499D01*
X1418215Y1440860D01*
X1418483Y1441119D01*
X1418790Y1441222D01*
X1419097Y1441119D01*
X1419365Y1440860D01*
X1419480Y1440499D01*
X1419403Y1440137D01*
X1419212Y1439879D01*
X1418982Y1439775D01*
X1418598D01*
X1418253Y1439620D01*
X1418023Y1439310D01*
X1417947Y1438949D01*
X1418023Y1438587D01*
X1418215Y1438329D01*
X1418522Y1438174D01*
X1418790Y1438122D01*
G01X1413216Y1424600D02*
X1415426D01*
G01D02*
Y1422592D01*
G01X1424642Y1426032D02*
Y1429232D01*
G01X1430842Y1426032D02*
X1424642D01*
G01Y1429232D02*
X1430842D01*
G01X1424642Y1422525D02*
Y1425725D01*
G01X1430842Y1422525D02*
X1424642D01*
G01Y1425725D02*
X1430842D01*
G01X1428949Y1435041D02*
X1425749D01*
G01D02*
Y1441241D01*
G01X1425119Y1435051D02*
X1421919D01*
G01X1425119Y1441251D02*
Y1435051D01*
G01X1421919D02*
Y1441251D01*
G01X1424642Y1422225D02*
X1430842D01*
G01X1424670Y1432750D02*
X1430870D01*
Y1429550D01*
X1424670D01*
Y1432750D01*
G01X1425749Y1441241D02*
X1428949D01*
G01X1421919Y1441251D02*
X1425119D01*
G01X1415733Y1514835D02*
Y1518035D01*
G01X1421933Y1514835D02*
X1415733D01*
G01X1421933Y1518035D02*
Y1514835D01*
G01X1415733Y1518035D02*
X1421933D01*
G01X1415973Y1530655D02*
Y1533855D01*
G01X1422173Y1530655D02*
X1415973D01*
G01X1422173Y1533855D02*
Y1530655D01*
G01X1415973Y1533855D02*
X1422173D01*
G01X1415733Y1519735D02*
Y1522935D01*
G01X1421933Y1519735D02*
X1415733D01*
G01X1421933Y1522935D02*
Y1519735D01*
G01X1415733Y1522935D02*
X1421933D01*
G01X1415973Y1535555D02*
Y1538755D01*
G01X1422173Y1535555D02*
X1415973D01*
G01X1422173Y1538755D02*
Y1535555D01*
G01X1415973Y1538755D02*
X1422173D01*
G01X1416123Y1546775D02*
Y1549975D01*
G01X1422323Y1546775D02*
X1416123D01*
G01X1422323Y1549975D02*
Y1546775D01*
G01X1416123Y1549975D02*
X1422323D01*
G01X1416123Y1541875D02*
Y1545075D01*
G01X1422323Y1541875D02*
X1416123D01*
G01X1422323Y1545075D02*
Y1541875D01*
G01X1416123Y1545075D02*
X1422323D01*
G01X1425923Y1560771D02*
Y1572771D01*
G01X1436723Y1560771D02*
X1425923D01*
G01X1414090Y1577657D02*
X1413783Y1577709D01*
X1413515Y1577915D01*
X1413285Y1578225D01*
X1413132Y1578587D01*
X1413055Y1579000D01*
Y1579414D01*
X1413132Y1579827D01*
X1413285Y1580189D01*
X1413515Y1580499D01*
X1413783Y1580705D01*
X1414090Y1580757D01*
X1414397Y1580705D01*
X1414665Y1580499D01*
X1414895Y1580189D01*
X1415048Y1579827D01*
X1415125Y1579414D01*
Y1579000D01*
X1415048Y1578587D01*
X1414895Y1578225D01*
X1414665Y1577915D01*
X1414397Y1577709D01*
X1414090Y1577657D01*
G01X1414397Y1578484D02*
X1414857Y1577657D01*
G01X1417190D02*
Y1580757D01*
X1416730Y1580137D01*
G01Y1577657D02*
X1417650D01*
G01X1419447Y1578122D02*
X1419677Y1577864D01*
X1419945Y1577709D01*
X1420290Y1577657D01*
X1420635Y1577760D01*
X1420903Y1577967D01*
X1421095Y1578329D01*
X1421133Y1578742D01*
X1421057Y1579155D01*
X1420865Y1579414D01*
X1420597Y1579620D01*
X1420328Y1579672D01*
X1420060Y1579620D01*
X1419715Y1579414D01*
X1419830Y1580757D01*
X1420865D01*
G01X1422662Y1580240D02*
X1422892Y1580550D01*
X1423160Y1580705D01*
X1423467Y1580757D01*
X1423850Y1580654D01*
X1424118Y1580395D01*
X1424195Y1580085D01*
X1424157Y1579775D01*
X1424003Y1579517D01*
X1423237Y1579000D01*
X1422892Y1578639D01*
X1422662Y1578122D01*
X1422585Y1577657D01*
X1424195D01*
G01X1426168Y1583551D02*
Y1592213D01*
G01X1437192Y1583551D02*
X1426168D01*
G01X1425923Y1572771D02*
X1429323D01*
G01X1424280Y1583300D02*
X1421080D01*
G01X1424280Y1589500D02*
Y1583300D01*
G01X1421080D02*
Y1589500D01*
G01X1437192Y1592213D02*
X1426168D01*
G01X1417430Y1598951D02*
Y1607613D01*
G01X1421080Y1589500D02*
X1424280D01*
G01X1419500Y1592100D02*
X1413300D01*
Y1595300D01*
X1419500D01*
Y1592100D01*
G01X1417430Y1607613D02*
X1414321D01*
G01X1419170Y1601662D02*
Y1604862D01*
G01X1425370Y1601662D02*
X1419170D01*
G01X1425370Y1604862D02*
Y1601662D01*
G01X1419170Y1604862D02*
X1425370D01*
G01X1422670Y1606842D02*
Y1610042D01*
G01X1428870Y1606842D02*
X1422670D01*
G01Y1610042D02*
X1428870D01*
G01X1422610Y1615332D02*
Y1618532D01*
G01X1428810Y1615332D02*
X1422610D01*
G01X1422650Y1614412D02*
X1428850D01*
G01X1422650Y1611212D02*
Y1614412D01*
G01X1428850Y1611212D02*
X1422650D01*
G01X1428257Y1621619D02*
X1424910D01*
X1423010Y1623819D01*
X1421110Y1621619D01*
X1417763D01*
Y1630281D01*
X1428257D01*
Y1621619D01*
G01X1422610Y1618532D02*
X1428810D01*
G01X1415050Y1642929D02*
X1414743Y1642981D01*
X1414475Y1643187D01*
X1414245Y1643497D01*
X1414092Y1643859D01*
X1414015Y1644272D01*
Y1644686D01*
X1414092Y1645099D01*
X1414245Y1645461D01*
X1414475Y1645771D01*
X1414743Y1645977D01*
X1415050Y1646029D01*
X1415357Y1645977D01*
X1415625Y1645771D01*
X1415855Y1645461D01*
X1416008Y1645099D01*
X1416085Y1644686D01*
Y1644272D01*
X1416008Y1643859D01*
X1415855Y1643497D01*
X1415625Y1643187D01*
X1415357Y1642981D01*
X1415050Y1642929D01*
G01X1415357Y1643756D02*
X1415817Y1642929D01*
G01X1418150D02*
Y1646029D01*
X1417690Y1645409D01*
G01Y1642929D02*
X1418610D01*
G01X1421710D02*
Y1646029D01*
X1420292Y1643807D01*
X1422208D01*
G01X1423622Y1644221D02*
X1423890Y1644582D01*
X1424120Y1644789D01*
X1424427Y1644892D01*
X1424695Y1644789D01*
X1424887Y1644582D01*
X1425040Y1644272D01*
X1425078Y1643911D01*
X1425040Y1643601D01*
X1424887Y1643291D01*
X1424657Y1643032D01*
X1424388Y1642929D01*
X1424082Y1643032D01*
X1423813Y1643342D01*
X1423660Y1643807D01*
X1423622Y1644324D01*
X1423698Y1644996D01*
X1423813Y1645357D01*
X1424005Y1645719D01*
X1424273Y1645977D01*
X1424542Y1646029D01*
X1424810Y1645926D01*
X1425002Y1645667D01*
G01X1414253Y1641693D02*
X1417600D01*
X1419500Y1639493D01*
X1421400Y1641693D01*
X1424747D01*
Y1633031D01*
X1414253D01*
Y1641693D01*
G01X1433100Y1635762D02*
X1426900D01*
Y1638962D01*
X1433100D01*
Y1635762D01*
G01X1418903Y1651672D02*
X1419095Y1651362D01*
X1419325Y1651155D01*
X1419593Y1651052D01*
X1419900Y1651155D01*
X1420130Y1651362D01*
X1420360Y1651672D01*
X1420437Y1652085D01*
Y1654152D01*
G01X1422770Y1651052D02*
Y1654152D01*
X1422310Y1653532D01*
G01Y1651052D02*
X1423230D01*
G01X1425142Y1653635D02*
X1425372Y1653945D01*
X1425640Y1654100D01*
X1425947Y1654152D01*
X1426330Y1654049D01*
X1426598Y1653790D01*
X1426675Y1653480D01*
X1426637Y1653170D01*
X1426483Y1652912D01*
X1425717Y1652395D01*
X1425372Y1652034D01*
X1425142Y1651517D01*
X1425065Y1651052D01*
X1426675D01*
G01X1428127Y1651672D02*
X1428357Y1651310D01*
X1428663Y1651104D01*
X1429008Y1651052D01*
X1429315Y1651104D01*
X1429622Y1651362D01*
X1429813Y1651672D01*
X1429852Y1651982D01*
X1429775Y1652344D01*
X1429507Y1652602D01*
X1429238Y1652705D01*
X1428893D01*
G01X1429238D02*
X1429468Y1652860D01*
X1429660Y1653119D01*
X1429737Y1653429D01*
X1429660Y1653739D01*
X1429468Y1653997D01*
X1429123Y1654152D01*
X1428778Y1654100D01*
X1428433Y1653894D01*
G01X1445800Y58462D02*
X1439600D01*
Y61662D01*
X1445800D01*
Y58462D01*
G01X1443400Y210262D02*
Y213462D01*
G01X1449600Y210262D02*
X1443400D01*
G01Y213462D02*
X1449600D01*
G01X1443400Y214262D02*
Y217462D01*
G01X1449600Y214262D02*
X1443400D01*
G01Y217462D02*
X1449600D01*
G01X1439983Y220398D02*
Y240498D01*
G01X1455783Y220398D02*
X1439983D01*
G01X1440190Y245048D02*
Y242826D01*
X1440343Y242361D01*
X1440650Y242051D01*
X1441033Y241948D01*
X1441416Y242051D01*
X1441723Y242361D01*
X1441876Y242826D01*
Y245048D01*
G01X1444133Y241948D02*
Y245048D01*
X1443673Y244428D01*
G01Y241948D02*
X1444593D01*
G01X1447156D02*
X1447233Y242620D01*
X1447348Y243188D01*
X1447501Y243705D01*
X1447693Y244273D01*
X1448000Y245048D01*
X1446466D01*
G01X1439983Y240498D02*
X1445633D01*
G01X1439480Y248892D02*
Y268992D01*
G01X1455280Y248892D02*
X1439480D01*
G01X1442500Y282250D02*
X1446750D01*
X1445000Y284000D01*
Y280500D01*
X1446750Y282250D01*
G01X1439687Y273542D02*
Y271320D01*
X1439840Y270855D01*
X1440147Y270545D01*
X1440530Y270442D01*
X1440913Y270545D01*
X1441220Y270855D01*
X1441373Y271320D01*
Y273542D01*
G01X1443630Y270442D02*
Y273542D01*
X1443170Y272922D01*
G01Y270442D02*
X1444090D01*
G01X1446730D02*
X1446998Y270494D01*
X1447305Y270649D01*
X1447497Y270907D01*
X1447573Y271269D01*
X1447497Y271630D01*
X1447267Y271940D01*
X1446922Y272095D01*
X1446538D01*
X1446308Y272199D01*
X1446117Y272457D01*
X1446040Y272819D01*
X1446155Y273180D01*
X1446423Y273439D01*
X1446730Y273542D01*
X1447037Y273439D01*
X1447305Y273180D01*
X1447420Y272819D01*
X1447343Y272457D01*
X1447152Y272199D01*
X1446922Y272095D01*
X1446538D01*
X1446193Y271940D01*
X1445963Y271630D01*
X1445887Y271269D01*
X1445963Y270907D01*
X1446155Y270649D01*
X1446462Y270494D01*
X1446730Y270442D01*
G01X1439480Y268992D02*
X1445130D01*
G01X1429307Y283500D02*
Y286600D01*
X1430073D01*
X1430380Y286445D01*
X1430610Y286238D01*
X1430802Y285928D01*
X1430955Y285567D01*
X1430993Y285050D01*
X1430955Y284533D01*
X1430802Y284172D01*
X1430610Y283862D01*
X1430380Y283655D01*
X1430073Y283500D01*
X1429307D01*
G01X1433250D02*
Y286600D01*
X1432790Y285980D01*
G01Y283500D02*
X1433710D01*
G01X1436810D02*
Y286600D01*
X1435392Y284378D01*
X1437308D01*
G01X1438722Y286083D02*
X1438952Y286393D01*
X1439220Y286548D01*
X1439527Y286600D01*
X1439910Y286497D01*
X1440178Y286238D01*
X1440255Y285928D01*
X1440217Y285618D01*
X1440063Y285360D01*
X1439297Y284843D01*
X1438952Y284482D01*
X1438722Y283965D01*
X1438645Y283500D01*
X1440255D01*
G01X1444177Y362896D02*
Y369096D01*
G01X1447377Y362896D02*
X1444177D01*
G01Y369096D02*
X1447377D01*
G01X1442261Y393975D02*
Y391753D01*
X1442414Y391288D01*
X1442721Y390978D01*
X1443104Y390875D01*
X1443487Y390978D01*
X1443794Y391288D01*
X1443947Y391753D01*
Y393975D01*
G01X1446204Y390875D02*
X1446472Y390927D01*
X1446779Y391082D01*
X1446971Y391340D01*
X1447047Y391702D01*
X1446971Y392063D01*
X1446741Y392373D01*
X1446396Y392528D01*
X1446012D01*
X1445782Y392632D01*
X1445591Y392890D01*
X1445514Y393252D01*
X1445629Y393613D01*
X1445897Y393872D01*
X1446204Y393975D01*
X1446511Y393872D01*
X1446779Y393613D01*
X1446894Y393252D01*
X1446817Y392890D01*
X1446626Y392632D01*
X1446396Y392528D01*
X1446012D01*
X1445667Y392373D01*
X1445437Y392063D01*
X1445361Y391702D01*
X1445437Y391340D01*
X1445629Y391082D01*
X1445936Y390927D01*
X1446204Y390875D01*
G01X1449764D02*
Y393975D01*
X1448346Y391753D01*
X1450262D01*
G01X1431763Y1032021D02*
Y931195D01*
G01X1449960D02*
X1431763D01*
G01X1437245Y942872D02*
Y949072D01*
X1440445D01*
Y942872D01*
X1437245D01*
G01X1433445D02*
Y949072D01*
X1436645D01*
Y942872D01*
X1433445D01*
G01X1444445Y955764D02*
Y949564D01*
X1441245D01*
Y955764D01*
X1444445D01*
G01X1440445D02*
Y949564D01*
X1437245D01*
Y955764D01*
X1440445D01*
G01X1436645D02*
Y949564D01*
X1433445D01*
Y955764D01*
X1436645D01*
G01X1437245Y934547D02*
Y940747D01*
X1440445D01*
Y934547D01*
X1437245D01*
G01X1441245Y942872D02*
Y949072D01*
X1444445D01*
Y942872D01*
X1441245D01*
G01Y934547D02*
Y940747D01*
X1444445D01*
Y934547D01*
X1441245D01*
G01X1433445D02*
Y940747D01*
X1436645D01*
Y934547D01*
X1433445D01*
G01X1437245Y963963D02*
Y970163D01*
G01X1440445Y963963D02*
X1437245D01*
G01X1440445Y970163D02*
Y963963D01*
G01X1441245D02*
Y970163D01*
G01X1444445Y963963D02*
X1441245D01*
G01X1433445D02*
Y970163D01*
G01X1436645Y963963D02*
X1433445D01*
G01X1436645Y970163D02*
Y963963D01*
G01X1441245Y957655D02*
Y963855D01*
X1444445D01*
Y957655D01*
X1441245D01*
G01X1437245D02*
Y963855D01*
X1440445D01*
Y957655D01*
X1437245D01*
G01X1433445D02*
Y963855D01*
X1436645D01*
Y957655D01*
X1433445D01*
G01X1437245Y978476D02*
Y984676D01*
G01X1440445Y978476D02*
X1437245D01*
G01X1440445Y984676D02*
Y978476D01*
G01X1441245D02*
Y984676D01*
G01X1444445Y978476D02*
X1441245D01*
G01X1440445Y972156D02*
X1437245D01*
G01X1440445Y978356D02*
Y972156D01*
G01X1437245Y978356D02*
X1440445D01*
G01X1437245Y972156D02*
Y978356D01*
G01X1444445Y972156D02*
X1441245D01*
G01Y978356D02*
X1444445D01*
G01X1441245Y972156D02*
Y978356D01*
G01X1437245Y970163D02*
X1440445D01*
G01X1441245D02*
X1444445D01*
G01X1433445Y978476D02*
Y984676D01*
G01X1436645Y978476D02*
X1433445D01*
G01X1436645Y984676D02*
Y978476D01*
G01Y972156D02*
X1433445D01*
G01X1436645Y978356D02*
Y972156D01*
G01X1433445Y978356D02*
X1436645D01*
G01X1433445Y972156D02*
Y978356D01*
G01Y970163D02*
X1436645D01*
G01X1437245Y984676D02*
X1440445D01*
G01X1441245D02*
X1444445D01*
G01X1433445D02*
X1436645D01*
G01X1441245Y986567D02*
Y992767D01*
X1444445D01*
Y986567D01*
X1441245D01*
G01X1437245D02*
Y992767D01*
X1440445D01*
Y986567D01*
X1437245D01*
G01X1433445D02*
Y992767D01*
X1436645D01*
Y986567D01*
X1433445D01*
G01X1444445Y998991D02*
Y992791D01*
X1441245D01*
Y998991D01*
X1444445D01*
G01X1440445D02*
Y992791D01*
X1437245D01*
Y998991D01*
X1440445D01*
G01X1436645D02*
Y992791D01*
X1433445D01*
Y998991D01*
X1436645D01*
G01X1437245Y1013549D02*
X1440445D01*
G01X1437245Y1007349D02*
Y1013549D01*
G01X1440445Y1007349D02*
X1437245D01*
G01X1440445Y1013549D02*
Y1007349D01*
G01X1441245Y1013549D02*
X1444445D01*
G01X1441245Y1007349D02*
Y1013549D01*
G01X1444445Y1007349D02*
X1441245D01*
G01X1440445Y1001049D02*
X1437245D01*
G01X1440445Y1007249D02*
Y1001049D01*
G01X1437245Y1007249D02*
X1440445D01*
G01X1437245Y1001049D02*
Y1007249D01*
G01X1433445Y1013549D02*
X1436645D01*
G01X1433445Y1007349D02*
Y1013549D01*
G01X1436645Y1007349D02*
X1433445D01*
G01X1436645Y1013549D02*
Y1007349D01*
G01Y1001049D02*
X1433445D01*
G01X1436645Y1007249D02*
Y1001049D01*
G01X1433445Y1007249D02*
X1436645D01*
G01X1433445Y1001049D02*
Y1007249D01*
G01X1441245Y1001049D02*
Y1007249D01*
X1444445D01*
Y1001049D01*
X1441245D01*
G01X1440445Y1015509D02*
X1437245D01*
G01X1440445Y1021709D02*
Y1015509D01*
G01X1437245Y1021709D02*
X1440445D01*
G01X1437245Y1015509D02*
Y1021709D01*
G01X1444445Y1015509D02*
X1441245D01*
G01Y1021709D02*
X1444445D01*
G01X1441245Y1015509D02*
Y1021709D01*
G01X1436645Y1015509D02*
X1433445D01*
G01X1436645Y1021709D02*
Y1015509D01*
G01X1433445Y1021709D02*
X1436645D01*
G01X1433445Y1015509D02*
Y1021709D01*
G01X1440445Y1028159D02*
Y1021959D01*
X1437245D01*
Y1028159D01*
X1440445D01*
G01X1436645D02*
Y1021959D01*
X1433445D01*
Y1028159D01*
X1436645D01*
G01X1444445D02*
Y1021959D01*
X1441245D01*
Y1028159D01*
X1444445D01*
G01X1431763Y1032021D02*
X1449960D01*
G01X1434720Y1160520D02*
Y1154520D01*
G01X1447220D02*
X1435220D01*
G01Y1160520D02*
X1447220D01*
G01X1435220Y1154520D02*
Y1160520D01*
G01X1447220Y1162570D02*
X1435220D01*
G01Y1168570D02*
X1447220D01*
G01X1435220Y1162570D02*
Y1168570D01*
G01X1434720D02*
Y1162570D01*
G01X1441097Y1253612D02*
Y1231958D01*
G01X1451924Y1242785D02*
G03I-10827J0D01*
G01X1439810Y1255690D02*
Y1298998D01*
G01X1445151Y1255690D02*
X1439810D01*
G01X1437161D02*
Y1291862D01*
G01X1431820Y1255690D02*
X1437161D01*
G01Y1294862D02*
Y1291862D01*
G01X1432121Y1302032D02*
X1431328D01*
G01X1432121Y1304632D02*
Y1302032D01*
G01X1439810Y1298998D02*
X1445151D01*
G01X1437161Y1294862D02*
Y1298998D01*
G01D02*
X1431820D01*
G01X1432121Y1325654D02*
Y1323463D01*
G01X1434730Y1317291D02*
X1437930D01*
G01X1434730Y1311091D02*
Y1317291D01*
G01X1437930Y1311091D02*
X1434730D01*
G01X1437930Y1317291D02*
Y1311091D01*
G01X1438732Y1316192D02*
X1441932D01*
G01X1438732Y1309992D02*
Y1316192D01*
G01X1441932Y1309992D02*
X1438732D01*
G01X1441932Y1316192D02*
Y1309992D01*
G01Y1320492D02*
X1438732D01*
G01X1441932Y1326692D02*
Y1320492D01*
G01X1438732D02*
Y1326692D01*
G01X1431388Y1325654D02*
X1432121D01*
G01X1430702Y1334510D02*
Y1328310D01*
G01X1438732Y1326692D02*
X1441932D01*
G01X1435121Y1328933D02*
Y1332133D01*
G01X1441321Y1328933D02*
X1435121D01*
G01X1441321Y1332133D02*
Y1328933D01*
G01X1435121Y1332133D02*
X1441321D01*
G01X1442185Y1335000D02*
X1445385D01*
G01X1442185Y1328800D02*
Y1335000D01*
G01X1445385Y1328800D02*
X1442185D01*
G01X1467540Y1353946D02*
G03I-13386J0D01*
G01X1439121Y1365976D02*
Y1392748D01*
G01X1438000Y1400745D02*
X1434900D01*
Y1401665D01*
X1435055Y1401972D01*
X1435417Y1402202D01*
X1435830Y1402279D01*
X1436243Y1402202D01*
X1436553Y1402010D01*
X1436708Y1401665D01*
Y1400745D01*
G01X1437380Y1403845D02*
X1437690Y1404037D01*
X1437897Y1404267D01*
X1438000Y1404535D01*
X1437897Y1404842D01*
X1437690Y1405072D01*
X1437380Y1405302D01*
X1436967Y1405379D01*
X1434900D01*
G01X1437535Y1406869D02*
X1437793Y1407099D01*
X1437948Y1407367D01*
X1438000Y1407712D01*
X1437897Y1408057D01*
X1437690Y1408325D01*
X1437328Y1408517D01*
X1436915Y1408555D01*
X1436502Y1408479D01*
X1436243Y1408287D01*
X1436037Y1408019D01*
X1435985Y1407750D01*
X1436037Y1407482D01*
X1436243Y1407137D01*
X1434900Y1407252D01*
Y1408287D01*
G01X1437380Y1409969D02*
X1437742Y1410199D01*
X1437948Y1410505D01*
X1438000Y1410850D01*
X1437948Y1411157D01*
X1437690Y1411464D01*
X1437380Y1411655D01*
X1437070Y1411694D01*
X1436708Y1411617D01*
X1436450Y1411349D01*
X1436347Y1411080D01*
Y1410735D01*
G01Y1411080D02*
X1436192Y1411310D01*
X1435933Y1411502D01*
X1435623Y1411579D01*
X1435313Y1411502D01*
X1435055Y1411310D01*
X1434900Y1410965D01*
X1434952Y1410620D01*
X1435158Y1410275D01*
G01X1440322Y1401804D02*
X1446522D01*
G01X1440322Y1398604D02*
Y1401804D01*
G01X1446522Y1398604D02*
X1440322D01*
G01X1431830Y1395559D02*
Y1392359D01*
G01X1440356Y1397869D02*
X1446556D01*
G01X1440356Y1394669D02*
Y1397869D01*
G01X1446556Y1394669D02*
X1440356D01*
G01X1446320Y1402862D02*
X1443120D01*
G01D02*
Y1409062D01*
G01X1428755Y1402079D02*
Y1395879D01*
G01X1449624Y1420616D02*
X1439730D01*
G01X1430842Y1418725D02*
Y1415525D01*
G01Y1414725D02*
Y1411525D01*
G01Y1410725D02*
Y1407525D01*
G01Y1422225D02*
Y1419025D01*
G01X1443120Y1409062D02*
X1446320D01*
G01X1437143Y1435970D02*
X1449821D01*
G01X1437143Y1423940D02*
Y1435970D01*
G01X1430842Y1429232D02*
Y1426032D01*
G01Y1425725D02*
Y1422525D01*
G01X1428949Y1441241D02*
Y1435041D01*
G01X1436332Y1440177D02*
Y1443277D01*
X1437252D01*
X1437559Y1443122D01*
X1437789Y1442760D01*
X1437866Y1442347D01*
X1437789Y1441934D01*
X1437597Y1441624D01*
X1437252Y1441469D01*
X1436332D01*
G01X1439356Y1443277D02*
Y1441055D01*
X1439509Y1440590D01*
X1439816Y1440280D01*
X1440199Y1440177D01*
X1440582Y1440280D01*
X1440889Y1440590D01*
X1441042Y1441055D01*
Y1443277D01*
G01X1443299Y1440177D02*
Y1443277D01*
X1442839Y1442657D01*
G01Y1440177D02*
X1443759D01*
G01X1446322D02*
X1446399Y1440849D01*
X1446514Y1441417D01*
X1446667Y1441934D01*
X1446859Y1442502D01*
X1447166Y1443277D01*
X1445632D01*
G01X1448656Y1440797D02*
X1448886Y1440435D01*
X1449192Y1440229D01*
X1449537Y1440177D01*
X1449844Y1440229D01*
X1450151Y1440487D01*
X1450342Y1440797D01*
X1450381Y1441107D01*
X1450304Y1441469D01*
X1450036Y1441727D01*
X1449767Y1441830D01*
X1449422D01*
G01X1449767D02*
X1449997Y1441985D01*
X1450189Y1442244D01*
X1450266Y1442554D01*
X1450189Y1442864D01*
X1449997Y1443122D01*
X1449652Y1443277D01*
X1449307Y1443225D01*
X1448962Y1443019D01*
G01X1431286Y1517204D02*
Y1525866D01*
G01X1441780Y1517204D02*
X1431286D01*
G01X1441780Y1525866D02*
Y1517204D01*
G01X1431526Y1533024D02*
Y1541686D01*
G01X1442020Y1533024D02*
X1431526D01*
G01X1442020Y1541686D02*
Y1533024D01*
G01X1438433Y1525866D02*
X1441780D01*
G01X1436533Y1523666D02*
X1438433Y1525866D01*
G01X1434633D02*
X1436533Y1523666D01*
G01X1431286Y1525866D02*
X1434633D01*
G01X1431676Y1544244D02*
Y1552906D01*
G01X1442170Y1544244D02*
X1431676D01*
G01X1442170Y1552906D02*
Y1544244D01*
G01X1436923Y1550706D02*
X1438823Y1552906D01*
G01X1435023D02*
X1436923Y1550706D01*
G01X1438673Y1541686D02*
X1442020D01*
G01X1436773Y1539486D02*
X1438673Y1541686D01*
G01X1434873D02*
X1436773Y1539486D01*
G01X1431526Y1541686D02*
X1434873D01*
G01X1432473Y1554142D02*
X1432166Y1554194D01*
X1431898Y1554400D01*
X1431668Y1554710D01*
X1431515Y1555072D01*
X1431438Y1555485D01*
Y1555899D01*
X1431515Y1556312D01*
X1431668Y1556674D01*
X1431898Y1556984D01*
X1432166Y1557190D01*
X1432473Y1557242D01*
X1432780Y1557190D01*
X1433048Y1556984D01*
X1433278Y1556674D01*
X1433431Y1556312D01*
X1433508Y1555899D01*
Y1555485D01*
X1433431Y1555072D01*
X1433278Y1554710D01*
X1433048Y1554400D01*
X1432780Y1554194D01*
X1432473Y1554142D01*
G01X1432780Y1554969D02*
X1433240Y1554142D01*
G01X1435573D02*
Y1557242D01*
X1435113Y1556622D01*
G01Y1554142D02*
X1436033D01*
G01X1437830Y1554762D02*
X1438060Y1554400D01*
X1438366Y1554194D01*
X1438711Y1554142D01*
X1439018Y1554194D01*
X1439325Y1554452D01*
X1439516Y1554762D01*
X1439555Y1555072D01*
X1439478Y1555434D01*
X1439210Y1555692D01*
X1438941Y1555795D01*
X1438596D01*
G01X1438941D02*
X1439171Y1555950D01*
X1439363Y1556209D01*
X1439440Y1556519D01*
X1439363Y1556829D01*
X1439171Y1557087D01*
X1438826Y1557242D01*
X1438481Y1557190D01*
X1438136Y1556984D01*
G01X1441045Y1555434D02*
X1441313Y1555795D01*
X1441543Y1556002D01*
X1441850Y1556105D01*
X1442118Y1556002D01*
X1442310Y1555795D01*
X1442463Y1555485D01*
X1442501Y1555124D01*
X1442463Y1554814D01*
X1442310Y1554504D01*
X1442080Y1554245D01*
X1441811Y1554142D01*
X1441505Y1554245D01*
X1441236Y1554555D01*
X1441083Y1555020D01*
X1441045Y1555537D01*
X1441121Y1556209D01*
X1441236Y1556570D01*
X1441428Y1556932D01*
X1441696Y1557190D01*
X1441965Y1557242D01*
X1442233Y1557139D01*
X1442425Y1556880D01*
G01X1438823Y1552906D02*
X1442170D01*
G01X1431676D02*
X1435023D01*
G01X1436723Y1572771D02*
Y1560771D01*
G01X1431467Y1582372D02*
Y1580150D01*
X1431620Y1579685D01*
X1431927Y1579375D01*
X1432310Y1579272D01*
X1432693Y1579375D01*
X1433000Y1579685D01*
X1433153Y1580150D01*
Y1582372D01*
G01X1434682Y1581855D02*
X1434912Y1582165D01*
X1435180Y1582320D01*
X1435487Y1582372D01*
X1435870Y1582269D01*
X1436138Y1582010D01*
X1436215Y1581700D01*
X1436177Y1581390D01*
X1436023Y1581132D01*
X1435257Y1580615D01*
X1434912Y1580254D01*
X1434682Y1579737D01*
X1434605Y1579272D01*
X1436215D01*
G01X1438510Y1582372D02*
X1438203Y1582269D01*
X1437973Y1582010D01*
X1437820Y1581700D01*
X1437705Y1581287D01*
X1437667Y1580822D01*
X1437705Y1580357D01*
X1437820Y1579944D01*
X1437973Y1579634D01*
X1438203Y1579375D01*
X1438510Y1579272D01*
X1438817Y1579375D01*
X1439047Y1579634D01*
X1439200Y1579944D01*
X1439315Y1580357D01*
X1439353Y1580822D01*
X1439315Y1581287D01*
X1439200Y1581700D01*
X1439047Y1582010D01*
X1438817Y1582269D01*
X1438510Y1582372D01*
G01X1442070Y1579272D02*
Y1582372D01*
X1440652Y1580150D01*
X1442568D01*
G01X1437192Y1592213D02*
Y1583551D01*
G01X1431187Y1577282D02*
Y1575060D01*
X1431340Y1574595D01*
X1431647Y1574285D01*
X1432030Y1574182D01*
X1432413Y1574285D01*
X1432720Y1574595D01*
X1432873Y1575060D01*
Y1577282D01*
G01X1435130Y1574182D02*
Y1577282D01*
X1434670Y1576662D01*
G01Y1574182D02*
X1435590D01*
G01X1438153D02*
X1438230Y1574854D01*
X1438345Y1575422D01*
X1438498Y1575939D01*
X1438690Y1576507D01*
X1438997Y1577282D01*
X1437463D01*
G01X1440602Y1575474D02*
X1440870Y1575835D01*
X1441100Y1576042D01*
X1441407Y1576145D01*
X1441675Y1576042D01*
X1441867Y1575835D01*
X1442020Y1575525D01*
X1442058Y1575164D01*
X1442020Y1574854D01*
X1441867Y1574544D01*
X1441637Y1574285D01*
X1441368Y1574182D01*
X1441062Y1574285D01*
X1440793Y1574595D01*
X1440640Y1575060D01*
X1440602Y1575577D01*
X1440678Y1576249D01*
X1440793Y1576610D01*
X1440985Y1576972D01*
X1441253Y1577230D01*
X1441522Y1577282D01*
X1441790Y1577179D01*
X1441982Y1576920D01*
G01X1433323Y1572771D02*
X1436723D01*
G01X1431323Y1570771D02*
X1433323Y1572771D01*
G01X1429323D02*
X1431323Y1570771D01*
G01X1438580Y1588782D02*
Y1591982D01*
G01X1444780Y1588782D02*
X1438580D01*
G01Y1591982D02*
X1444780D01*
G01X1445500Y1596800D02*
X1439300D01*
Y1600000D01*
X1445500D01*
Y1596800D01*
G01X1431610Y1614827D02*
X1431303Y1614879D01*
X1431035Y1615085D01*
X1430805Y1615395D01*
X1430652Y1615757D01*
X1430575Y1616170D01*
Y1616584D01*
X1430652Y1616997D01*
X1430805Y1617359D01*
X1431035Y1617669D01*
X1431303Y1617875D01*
X1431610Y1617927D01*
X1431917Y1617875D01*
X1432185Y1617669D01*
X1432415Y1617359D01*
X1432568Y1616997D01*
X1432645Y1616584D01*
Y1616170D01*
X1432568Y1615757D01*
X1432415Y1615395D01*
X1432185Y1615085D01*
X1431917Y1614879D01*
X1431610Y1614827D01*
G01X1431917Y1615654D02*
X1432377Y1614827D01*
G01X1434710D02*
Y1617927D01*
X1434250Y1617307D01*
G01Y1614827D02*
X1435170D01*
G01X1436967Y1615292D02*
X1437197Y1615034D01*
X1437465Y1614879D01*
X1437810Y1614827D01*
X1438155Y1614930D01*
X1438423Y1615137D01*
X1438615Y1615499D01*
X1438653Y1615912D01*
X1438577Y1616325D01*
X1438385Y1616584D01*
X1438117Y1616790D01*
X1437848Y1616842D01*
X1437580Y1616790D01*
X1437235Y1616584D01*
X1437350Y1617927D01*
X1438385D01*
G01X1441370Y1614827D02*
Y1617927D01*
X1439952Y1615705D01*
X1441868D01*
G01X1428870Y1610042D02*
Y1606842D01*
G01X1428810Y1618532D02*
Y1615332D01*
G01X1428850Y1614412D02*
Y1611212D01*
G01X1439300Y1608400D02*
X1445500D01*
Y1605200D01*
X1439300D01*
Y1608400D01*
G01X1445500Y1609400D02*
X1439300D01*
Y1612600D01*
X1445500D01*
Y1609400D01*
G01X1439300Y1604200D02*
X1445500D01*
Y1601000D01*
X1439300D01*
Y1604200D01*
G01X1434700Y1634500D02*
X1440900D01*
Y1631300D01*
X1434700D01*
Y1634500D01*
G01X1440900Y1622900D02*
X1434700D01*
Y1626100D01*
X1440900D01*
Y1622900D01*
G01Y1627100D02*
X1434700D01*
Y1630300D01*
X1440900D01*
Y1627100D01*
G01X1434700Y1621900D02*
X1440900D01*
Y1618700D01*
X1434700D01*
Y1621900D01*
G01X1440147Y1639235D02*
X1436947D01*
G01X1440147Y1645435D02*
Y1639235D01*
G01X1436947Y1645435D02*
X1440147D01*
G01X1436947Y1639235D02*
Y1645435D01*
G01X1445217Y1639215D02*
X1442017D01*
G01Y1645415D02*
X1445217D01*
G01X1442017Y1639215D02*
Y1645415D01*
G01X1439633Y1663895D02*
Y1667095D01*
G01X1445833Y1663895D02*
X1439633D01*
G01X1440973Y1657069D02*
X1444173D01*
G01X1440973Y1650869D02*
Y1657069D01*
G01X1444173Y1650869D02*
X1440973D01*
G01X1444173Y1657069D02*
Y1650869D01*
G01X1430315Y1656968D02*
Y1782165D01*
G01X1439633Y1667095D02*
X1445833D01*
G01X1439543Y1672355D02*
Y1675555D01*
G01X1445743Y1672355D02*
X1439543D01*
G01Y1675555D02*
X1445743D01*
G01X1439547Y1668029D02*
Y1671229D01*
G01X1445747Y1668029D02*
X1439547D01*
G01Y1671229D02*
X1445747D01*
G01X1436555Y1730810D02*
Y1733910D01*
G01X1438165D02*
Y1730810D01*
G01Y1732360D02*
X1436555D01*
G01X1439808Y1731172D02*
X1440077Y1730913D01*
X1440383Y1730810D01*
X1440690Y1730913D01*
X1440958Y1731223D01*
X1441150Y1731688D01*
X1441227Y1732153D01*
Y1732722D01*
X1441150Y1733187D01*
X1440958Y1733600D01*
X1440728Y1733807D01*
X1440460Y1733910D01*
X1440153Y1733807D01*
X1439923Y1733600D01*
X1439770Y1733290D01*
X1439693Y1732877D01*
X1439770Y1732515D01*
X1439962Y1732153D01*
X1440192Y1731947D01*
X1440460Y1731895D01*
X1440767Y1731998D01*
X1440997Y1732257D01*
X1441227Y1732722D01*
G01X1442717Y1731430D02*
X1442947Y1731068D01*
X1443253Y1730862D01*
X1443598Y1730810D01*
X1443905Y1730862D01*
X1444212Y1731120D01*
X1444403Y1731430D01*
X1444442Y1731740D01*
X1444365Y1732102D01*
X1444097Y1732360D01*
X1443828Y1732463D01*
X1443483D01*
G01X1443828D02*
X1444058Y1732618D01*
X1444250Y1732877D01*
X1444327Y1733187D01*
X1444250Y1733497D01*
X1444058Y1733755D01*
X1443713Y1733910D01*
X1443368Y1733858D01*
X1443023Y1733652D01*
G01X1449037Y56075D02*
Y53853D01*
X1449190Y53388D01*
X1449497Y53078D01*
X1449880Y52975D01*
X1450263Y53078D01*
X1450570Y53388D01*
X1450723Y53853D01*
Y56075D01*
G01X1452137Y53595D02*
X1452367Y53233D01*
X1452673Y53027D01*
X1453018Y52975D01*
X1453325Y53027D01*
X1453632Y53285D01*
X1453823Y53595D01*
X1453862Y53905D01*
X1453785Y54267D01*
X1453517Y54525D01*
X1453248Y54628D01*
X1452903D01*
G01X1453248D02*
X1453478Y54783D01*
X1453670Y55042D01*
X1453747Y55352D01*
X1453670Y55662D01*
X1453478Y55920D01*
X1453133Y56075D01*
X1452788Y56023D01*
X1452443Y55817D01*
G01X1455352Y55558D02*
X1455582Y55868D01*
X1455850Y56023D01*
X1456157Y56075D01*
X1456540Y55972D01*
X1456808Y55713D01*
X1456885Y55403D01*
X1456847Y55093D01*
X1456693Y54835D01*
X1455927Y54318D01*
X1455582Y53957D01*
X1455352Y53440D01*
X1455275Y52975D01*
X1456885D01*
G01X1459180Y56075D02*
X1458873Y55972D01*
X1458643Y55713D01*
X1458490Y55403D01*
X1458375Y54990D01*
X1458337Y54525D01*
X1458375Y54060D01*
X1458490Y53647D01*
X1458643Y53337D01*
X1458873Y53078D01*
X1459180Y52975D01*
X1459487Y53078D01*
X1459717Y53337D01*
X1459870Y53647D01*
X1459985Y54060D01*
X1460023Y54525D01*
X1459985Y54990D01*
X1459870Y55403D01*
X1459717Y55713D01*
X1459487Y55972D01*
X1459180Y56075D01*
G01X1447200Y57960D02*
Y70164D01*
X1463200D01*
Y57960D01*
X1447200D01*
G01X1449600Y213462D02*
Y210262D01*
G01Y217462D02*
Y214262D01*
G01X1455783Y240498D02*
Y220398D01*
G01X1450133Y240498D02*
X1455783D01*
G01X1447883Y238248D02*
X1450133Y240498D01*
G01X1445633D02*
X1447883Y238248D01*
G01X1455280Y268992D02*
Y248892D01*
G01X1449630Y268992D02*
X1455280D01*
G01X1447380Y266742D02*
X1449630Y268992D01*
G01X1445130D02*
X1447380Y266742D01*
G01X1449280Y283090D02*
X1456370D01*
Y279290D01*
X1449280D01*
G01X1448680Y283090D02*
X1455870D01*
Y279290D01*
X1448680D01*
G01X1448280Y283090D02*
X1455370D01*
Y279290D01*
X1448230D01*
Y283040D01*
G01X1453300Y295800D02*
Y289600D01*
X1450100D01*
Y295800D01*
X1453300D01*
G01X1454000Y289600D02*
Y295800D01*
X1457200D01*
Y289600D01*
X1454000D01*
G01X1446200D02*
Y295800D01*
X1449400D01*
Y289600D01*
X1446200D01*
G01X1451768Y304723D02*
Y307823D01*
X1452688D01*
X1452995Y307668D01*
X1453225Y307306D01*
X1453302Y306893D01*
X1453225Y306480D01*
X1453033Y306170D01*
X1452688Y306015D01*
X1451768D01*
G01X1454868Y307823D02*
Y304723D01*
X1456402D01*
G01X1458735D02*
Y307823D01*
X1458275Y307203D01*
G01Y304723D02*
X1459195D01*
G01X1461758D02*
X1461835Y305395D01*
X1461950Y305963D01*
X1462103Y306480D01*
X1462295Y307048D01*
X1462602Y307823D01*
X1461068D01*
G01X1464935D02*
X1464628Y307720D01*
X1464398Y307461D01*
X1464245Y307151D01*
X1464130Y306738D01*
X1464092Y306273D01*
X1464130Y305808D01*
X1464245Y305395D01*
X1464398Y305085D01*
X1464628Y304826D01*
X1464935Y304723D01*
X1465242Y304826D01*
X1465472Y305085D01*
X1465625Y305395D01*
X1465740Y305808D01*
X1465778Y306273D01*
X1465740Y306738D01*
X1465625Y307151D01*
X1465472Y307461D01*
X1465242Y307720D01*
X1464935Y307823D01*
G01X1459900Y369062D02*
Y362862D01*
G01X1456700D02*
Y369062D01*
G01X1459900Y362862D02*
X1456700D01*
G01X1451377Y362896D02*
X1448177D01*
G01X1451377Y369096D02*
Y362896D01*
G01X1448177D02*
Y369096D01*
G01X1447377D02*
Y362896D01*
G01X1455377D02*
X1452177D01*
G01X1455377Y369096D02*
Y362896D01*
G01X1452177D02*
Y369096D01*
G01X1456700Y369062D02*
X1459900D01*
G01X1448177Y369096D02*
X1451377D01*
G01X1452177D02*
X1455377D01*
G01X1453227Y392746D02*
Y398396D01*
G01X1455477Y390496D02*
X1453227Y392746D01*
G01Y388246D02*
X1455477Y390496D01*
G01X1453227Y382596D02*
Y388246D01*
G01X1473327Y382596D02*
X1453227D01*
G01X1451200Y401412D02*
Y395212D01*
G01D02*
X1448000D01*
G01D02*
Y401412D01*
G01X1453227Y398396D02*
X1473327D01*
G01X1450180Y412022D02*
X1453380D01*
G01Y405822D02*
X1450180D01*
G01X1453380Y412022D02*
Y405822D01*
G01X1450180D02*
Y412022D01*
G01X1448000Y401412D02*
X1451200D01*
G01X1458377Y419471D02*
X1455177D01*
G01Y425671D02*
X1458377D01*
G01X1455177Y419471D02*
Y425671D01*
G01X1458377D02*
Y419471D01*
G01X1448308Y833739D02*
X1466025Y829802D01*
G01X1448307Y833740D02*
X1466024Y829803D01*
G01X1449960Y931195D02*
Y1032021D01*
G01X1448245Y955764D02*
Y949564D01*
X1445045D01*
Y955764D01*
X1448245D01*
G01X1445045Y934547D02*
Y940747D01*
X1448245D01*
Y934547D01*
X1445045D01*
G01Y942872D02*
Y949072D01*
X1448245D01*
Y942872D01*
X1445045D01*
G01X1444445Y970163D02*
Y963963D01*
G01X1445045Y957655D02*
Y963855D01*
X1448245D01*
Y957655D01*
X1445045D01*
G01X1448245Y970163D02*
Y963963D01*
X1445045D01*
Y970163D01*
X1448245D01*
G01X1444445Y984676D02*
Y978476D01*
G01X1445045D02*
Y984676D01*
G01X1448245Y978476D02*
X1445045D01*
G01X1448245Y984676D02*
Y978476D01*
G01X1444445Y978356D02*
Y972156D01*
G01X1445045D02*
Y978356D01*
X1448245D01*
Y972156D01*
X1445045D01*
G01Y984676D02*
X1448245D01*
G01X1445045Y986567D02*
Y992767D01*
X1448245D01*
Y986567D01*
X1445045D01*
G01X1448245Y998991D02*
Y992791D01*
X1445045D01*
Y998991D01*
X1448245D01*
G01X1444445Y1013549D02*
Y1007349D01*
G01X1445045Y1013549D02*
X1448245D01*
G01X1445045Y1007349D02*
Y1013549D01*
G01X1448245Y1007349D02*
X1445045D01*
G01X1448245Y1013549D02*
Y1007349D01*
G01X1445045Y1001049D02*
Y1007249D01*
X1448245D01*
Y1001049D01*
X1445045D01*
G01X1444445Y1021709D02*
Y1015509D01*
G01X1448245D02*
X1445045D01*
G01X1448245Y1021709D02*
Y1015509D01*
G01X1445045Y1021709D02*
X1448245D01*
G01X1445045Y1015509D02*
Y1021709D01*
G01X1448245Y1028159D02*
Y1021959D01*
X1445045D01*
Y1028159D01*
X1448245D01*
G01X1447220Y1160520D02*
Y1154520D01*
G01X1466025Y1152637D02*
X1448308Y1148700D01*
G01X1466024Y1152638D02*
X1448307Y1148701D01*
G01X1447220Y1168570D02*
Y1162570D01*
G01X1476324Y1242785D02*
G03I-10827J0D01*
G01X1444563Y1302032D02*
Y1304632D01*
G01X1445356Y1302032D02*
X1444563D01*
G01Y1311243D02*
Y1312941D01*
G01Y1325654D02*
X1445571D01*
G01X1444563Y1323800D02*
Y1325654D01*
G01X1459837Y1334510D02*
X1463037D01*
G01X1459837Y1328310D02*
Y1334510D01*
G01X1463037Y1328310D02*
X1459837D01*
G01X1445385Y1335000D02*
Y1328800D01*
G01X1446222Y1332495D02*
Y1335695D01*
G01X1452422Y1332495D02*
X1446222D01*
G01X1452422Y1335695D02*
Y1332495D01*
G01X1446222Y1335695D02*
X1452422D01*
G01X1458995Y1328310D02*
X1455795D01*
G01X1458995Y1334510D02*
Y1328310D01*
G01X1455795Y1334510D02*
X1458995D01*
G01X1455795Y1328310D02*
Y1334510D01*
G01X1454154Y1340560D02*
Y1367332D01*
G01X1446522Y1401804D02*
Y1398604D01*
G01X1455109Y1402870D02*
X1451909D01*
G01X1455109Y1409070D02*
Y1402870D01*
G01X1451909D02*
Y1409070D01*
G01X1446556Y1397869D02*
Y1394669D01*
G01X1446320Y1409062D02*
Y1402862D01*
G01X1450442Y1402870D02*
X1447242D01*
G01X1450442Y1409070D02*
Y1402870D01*
G01X1447242D02*
Y1409070D01*
G01X1452507Y1398785D02*
Y1401985D01*
G01X1458707Y1398785D02*
X1452507D01*
G01X1458707Y1401985D02*
Y1398785D01*
G01X1452507Y1401985D02*
X1458707D01*
G01X1459209Y1402870D02*
X1456009D01*
G01X1459209Y1409070D02*
Y1402870D01*
G01X1456009D02*
Y1409070D01*
G01X1449821Y1435970D02*
Y1420616D01*
G01X1451909Y1409070D02*
X1455109D01*
G01X1463403Y1420407D02*
X1460203D01*
G01D02*
Y1426607D01*
G01X1454022Y1414393D02*
X1450822D01*
G01X1454022Y1420593D02*
Y1414393D01*
G01X1450822Y1420593D02*
X1454022D01*
G01X1450822Y1414393D02*
Y1420593D01*
G01X1451112Y1409544D02*
Y1412744D01*
G01X1457312Y1409544D02*
X1451112D01*
G01X1457312Y1412744D02*
Y1409544D01*
G01X1451112Y1412744D02*
X1457312D01*
G01X1447242Y1409070D02*
X1450442D01*
G01X1456009D02*
X1459209D01*
G01X1457993Y1414393D02*
X1454793D01*
G01X1457993Y1420593D02*
Y1414393D01*
G01X1454793Y1420593D02*
X1457993D01*
G01X1454793Y1414393D02*
Y1420593D01*
G01X1464304Y1428866D02*
X1458215D01*
G01Y1428836D02*
Y1457606D01*
G01X1460203Y1426607D02*
X1463403D01*
G01X1453338Y1447053D02*
X1456538D01*
G01X1453338Y1440853D02*
Y1447053D01*
G01X1456538Y1440853D02*
X1453338D01*
G01X1456538Y1447053D02*
Y1440853D01*
G01X1458215Y1457606D02*
X1464304D01*
G01X1446513Y1516982D02*
X1446206Y1517034D01*
X1445938Y1517240D01*
X1445708Y1517550D01*
X1445555Y1517912D01*
X1445478Y1518325D01*
Y1518739D01*
X1445555Y1519152D01*
X1445708Y1519514D01*
X1445938Y1519824D01*
X1446206Y1520030D01*
X1446513Y1520082D01*
X1446820Y1520030D01*
X1447088Y1519824D01*
X1447318Y1519514D01*
X1447471Y1519152D01*
X1447548Y1518739D01*
Y1518325D01*
X1447471Y1517912D01*
X1447318Y1517550D01*
X1447088Y1517240D01*
X1446820Y1517034D01*
X1446513Y1516982D01*
G01X1446820Y1517809D02*
X1447280Y1516982D01*
G01X1449613D02*
Y1520082D01*
X1449153Y1519462D01*
G01Y1516982D02*
X1450073D01*
G01X1451870Y1517602D02*
X1452100Y1517240D01*
X1452406Y1517034D01*
X1452751Y1516982D01*
X1453058Y1517034D01*
X1453365Y1517292D01*
X1453556Y1517602D01*
X1453595Y1517912D01*
X1453518Y1518274D01*
X1453250Y1518532D01*
X1452981Y1518635D01*
X1452636D01*
G01X1452981D02*
X1453211Y1518790D01*
X1453403Y1519049D01*
X1453480Y1519359D01*
X1453403Y1519669D01*
X1453211Y1519927D01*
X1452866Y1520082D01*
X1452521Y1520030D01*
X1452176Y1519824D01*
G01X1454970Y1517447D02*
X1455200Y1517189D01*
X1455468Y1517034D01*
X1455813Y1516982D01*
X1456158Y1517085D01*
X1456426Y1517292D01*
X1456618Y1517654D01*
X1456656Y1518067D01*
X1456580Y1518480D01*
X1456388Y1518739D01*
X1456120Y1518945D01*
X1455851Y1518997D01*
X1455583Y1518945D01*
X1455238Y1518739D01*
X1455353Y1520082D01*
X1456388D01*
G01X1445903Y1533172D02*
X1445596Y1533224D01*
X1445328Y1533430D01*
X1445098Y1533740D01*
X1444945Y1534102D01*
X1444868Y1534515D01*
Y1534929D01*
X1444945Y1535342D01*
X1445098Y1535704D01*
X1445328Y1536014D01*
X1445596Y1536220D01*
X1445903Y1536272D01*
X1446210Y1536220D01*
X1446478Y1536014D01*
X1446708Y1535704D01*
X1446861Y1535342D01*
X1446938Y1534929D01*
Y1534515D01*
X1446861Y1534102D01*
X1446708Y1533740D01*
X1446478Y1533430D01*
X1446210Y1533224D01*
X1445903Y1533172D01*
G01X1446210Y1533999D02*
X1446670Y1533172D01*
G01X1449003D02*
Y1536272D01*
X1448543Y1535652D01*
G01Y1533172D02*
X1449463D01*
G01X1451260Y1533792D02*
X1451490Y1533430D01*
X1451796Y1533224D01*
X1452141Y1533172D01*
X1452448Y1533224D01*
X1452755Y1533482D01*
X1452946Y1533792D01*
X1452985Y1534102D01*
X1452908Y1534464D01*
X1452640Y1534722D01*
X1452371Y1534825D01*
X1452026D01*
G01X1452371D02*
X1452601Y1534980D01*
X1452793Y1535239D01*
X1452870Y1535549D01*
X1452793Y1535859D01*
X1452601Y1536117D01*
X1452256Y1536272D01*
X1451911Y1536220D01*
X1451566Y1536014D01*
G01X1455126Y1533172D02*
X1455203Y1533844D01*
X1455318Y1534412D01*
X1455471Y1534929D01*
X1455663Y1535497D01*
X1455970Y1536272D01*
X1454436D01*
G01X1456367Y1528289D02*
Y1525089D01*
G01X1450167Y1528289D02*
X1456367D01*
G01X1450167Y1525089D02*
Y1528289D01*
G01X1456367Y1525089D02*
X1450167D01*
G01X1456607Y1544109D02*
Y1540909D01*
G01X1450407Y1544109D02*
X1456607D01*
G01X1450407Y1540909D02*
Y1544109D01*
G01X1456607Y1540909D02*
X1450407D01*
G01X1456757Y1555329D02*
Y1552129D01*
G01X1450557Y1555329D02*
X1456757D01*
G01X1450557Y1552129D02*
Y1555329D01*
G01X1456757Y1552129D02*
X1450557D01*
G01X1450808Y1558437D02*
Y1561637D01*
G01X1457008Y1558437D02*
X1450808D01*
G01X1457008Y1561637D02*
Y1558437D01*
G01X1450808Y1561637D02*
X1457008D01*
G01X1450808Y1563437D02*
Y1566637D01*
G01X1457008Y1563437D02*
X1450808D01*
G01X1457008Y1566637D02*
Y1563437D01*
G01X1450808Y1566637D02*
X1457008D01*
G01X1444780Y1591982D02*
Y1588782D01*
G01X1454760Y1591902D02*
Y1588702D01*
G01X1448560Y1591902D02*
X1454760D01*
G01X1448560Y1588702D02*
Y1591902D01*
G01X1454760Y1588702D02*
X1448560D01*
G01X1448530Y1584662D02*
Y1587862D01*
G01X1454730Y1584662D02*
X1448530D01*
G01X1454730Y1587862D02*
Y1584662D01*
G01X1448530Y1587862D02*
X1454730D01*
G01X1447750Y1615757D02*
X1447443Y1615809D01*
X1447175Y1616015D01*
X1446945Y1616325D01*
X1446792Y1616687D01*
X1446715Y1617100D01*
Y1617514D01*
X1446792Y1617927D01*
X1446945Y1618289D01*
X1447175Y1618599D01*
X1447443Y1618805D01*
X1447750Y1618857D01*
X1448057Y1618805D01*
X1448325Y1618599D01*
X1448555Y1618289D01*
X1448708Y1617927D01*
X1448785Y1617514D01*
Y1617100D01*
X1448708Y1616687D01*
X1448555Y1616325D01*
X1448325Y1616015D01*
X1448057Y1615809D01*
X1447750Y1615757D01*
G01X1448057Y1616584D02*
X1448517Y1615757D01*
G01X1450850D02*
Y1618857D01*
X1450390Y1618237D01*
G01Y1615757D02*
X1451310D01*
G01X1453107Y1616222D02*
X1453337Y1615964D01*
X1453605Y1615809D01*
X1453950Y1615757D01*
X1454295Y1615860D01*
X1454563Y1616067D01*
X1454755Y1616429D01*
X1454793Y1616842D01*
X1454717Y1617255D01*
X1454525Y1617514D01*
X1454257Y1617720D01*
X1453988Y1617772D01*
X1453720Y1617720D01*
X1453375Y1617514D01*
X1453490Y1618857D01*
X1454525D01*
G01X1456207Y1616377D02*
X1456437Y1616015D01*
X1456743Y1615809D01*
X1457088Y1615757D01*
X1457395Y1615809D01*
X1457702Y1616067D01*
X1457893Y1616377D01*
X1457932Y1616687D01*
X1457855Y1617049D01*
X1457587Y1617307D01*
X1457318Y1617410D01*
X1456973D01*
G01X1457318D02*
X1457548Y1617565D01*
X1457740Y1617824D01*
X1457817Y1618134D01*
X1457740Y1618444D01*
X1457548Y1618702D01*
X1457203Y1618857D01*
X1456858Y1618805D01*
X1456513Y1618599D01*
G01X1448553Y1609331D02*
X1451900D01*
X1453800Y1607131D01*
X1455700Y1609331D01*
X1459047D01*
Y1600669D01*
X1448553D01*
Y1609331D01*
G01X1452865Y1614400D02*
X1459065D01*
Y1611200D01*
X1452865D01*
Y1614400D01*
G01X1452607Y1632665D02*
X1455807D01*
G01X1452607Y1626465D02*
Y1632665D01*
G01X1455807Y1626465D02*
X1452607D01*
G01X1455807Y1632665D02*
Y1626465D01*
G01X1457517Y1632645D02*
X1460717D01*
G01X1457517Y1626445D02*
Y1632645D01*
G01X1460717Y1626445D02*
X1457517D01*
G01X1455767Y1639315D02*
X1452567D01*
G01X1455767Y1645515D02*
Y1639315D01*
G01X1452567Y1645515D02*
X1455767D01*
G01X1452567Y1639315D02*
Y1645515D01*
G01X1460727Y1639315D02*
X1457527D01*
G01Y1645515D02*
X1460727D01*
G01X1457527Y1639315D02*
Y1645515D01*
G01X1450107Y1639225D02*
X1446907D01*
G01X1450107Y1645425D02*
Y1639225D01*
G01X1446907Y1645425D02*
X1450107D01*
G01X1446907Y1639225D02*
Y1645425D01*
G01X1445217Y1645415D02*
Y1639215D01*
G01X1445833Y1667095D02*
Y1663895D01*
G01X1450414Y1652695D02*
X1470100D01*
G01X1450414Y1679843D02*
Y1652695D01*
G01X1445743Y1675555D02*
Y1672355D01*
G01X1445747Y1671229D02*
Y1668029D01*
G01X1470100Y1679843D02*
X1450414D01*
G01X1475667Y62755D02*
X1469467D01*
Y65955D01*
X1475667D01*
Y62755D01*
G01X1474295Y103640D02*
Y106740D01*
G01X1475905D02*
Y103640D01*
G01Y105190D02*
X1474295D01*
G01X1478200Y103640D02*
Y106740D01*
X1477740Y106120D01*
G01Y103640D02*
X1478660D01*
G01X1481300Y106740D02*
X1480993Y106637D01*
X1480763Y106378D01*
X1480610Y106068D01*
X1480495Y105655D01*
X1480457Y105190D01*
X1480495Y104725D01*
X1480610Y104312D01*
X1480763Y104002D01*
X1480993Y103743D01*
X1481300Y103640D01*
X1481607Y103743D01*
X1481837Y104002D01*
X1481990Y104312D01*
X1482105Y104725D01*
X1482143Y105190D01*
X1482105Y105655D01*
X1481990Y106068D01*
X1481837Y106378D01*
X1481607Y106637D01*
X1481300Y106740D01*
G01X1483557Y104105D02*
X1483787Y103847D01*
X1484055Y103692D01*
X1484400Y103640D01*
X1484745Y103743D01*
X1485013Y103950D01*
X1485205Y104312D01*
X1485243Y104725D01*
X1485167Y105138D01*
X1484975Y105397D01*
X1484707Y105603D01*
X1484438Y105655D01*
X1484170Y105603D01*
X1483825Y105397D01*
X1483940Y106740D01*
X1484975D01*
G01X1464600Y154262D02*
X1461400D01*
G01X1464600Y160462D02*
Y154262D01*
G01X1461400Y160462D02*
X1464600D01*
G01X1461400Y154262D02*
Y160462D01*
G01X1469783Y223848D02*
Y227048D01*
G01X1475983Y223848D02*
X1469783D01*
G01X1475983Y227048D02*
Y223848D01*
G01X1469783Y227048D02*
X1475983D01*
G01X1469783Y231848D02*
Y235048D01*
G01X1475983Y231848D02*
X1469783D01*
G01X1475983Y235048D02*
Y231848D01*
G01X1462283Y240848D02*
Y244048D01*
G01X1468483Y240848D02*
X1462283D01*
G01X1468483Y244048D02*
Y240848D01*
G01X1462283Y244048D02*
X1468483D01*
G01X1469783Y235048D02*
X1475983D01*
G01X1469985Y261778D02*
Y264978D01*
G01X1476185Y261778D02*
X1469985D01*
G01X1476185Y264978D02*
Y261778D01*
G01X1469985Y264978D02*
X1476185D01*
G01X1469985Y253778D02*
Y256978D01*
G01X1476185Y253778D02*
X1469985D01*
G01X1476185Y256978D02*
Y253778D01*
G01X1469985Y256978D02*
X1476185D01*
G01X1461985Y269778D02*
Y272978D01*
G01X1468185Y269778D02*
X1461985D01*
G01X1468185Y272978D02*
Y269778D01*
G01X1461985Y272978D02*
X1468185D01*
G01X1471067Y285031D02*
Y291120D01*
G01X1499837Y285031D02*
X1471067D01*
G01X1476158Y313356D02*
Y319356D01*
G01X1488158Y313356D02*
X1476158D01*
G01X1471067Y311409D02*
X1499807D01*
G01X1471067Y305320D02*
Y311409D01*
G01X1476158Y319356D02*
X1488158D01*
G01X1468377Y362896D02*
X1465177D01*
G01X1468377Y369096D02*
Y362896D01*
G01X1465177D02*
Y369096D01*
G01X1472377Y362896D02*
X1469177D01*
G01X1472377Y369096D02*
Y362896D01*
G01X1469177D02*
Y369096D01*
G01X1461177Y362896D02*
Y369096D01*
G01X1464377Y362896D02*
X1461177D01*
G01X1464377Y369096D02*
Y362896D01*
G01X1465177Y369096D02*
X1468377D01*
G01X1469177D02*
X1472377D01*
G01X1461177D02*
X1464377D01*
G01X1476834Y382388D02*
Y398188D01*
G01X1496934Y382388D02*
X1476834D01*
G01X1473327Y398396D02*
Y382596D01*
G01X1476834Y398188D02*
X1496934D01*
G01X1475784Y412188D02*
Y418388D01*
G01X1478984Y412188D02*
X1475784D01*
G01Y418388D02*
X1478984D01*
G01X1466025Y829802D02*
X1536891D01*
G01X1466024Y829803D02*
X1536890D01*
G01X1536891Y1152637D02*
X1466025D01*
G01X1536890Y1152638D02*
X1466024D01*
G01X1465497Y1253612D02*
Y1231958D01*
G01X1469338Y1255690D02*
Y1298998D01*
G01X1463997Y1255690D02*
X1469338D01*
G01X1471997Y1268871D02*
Y1312179D01*
G01X1477338Y1268871D02*
X1471997D01*
G01X1464249Y1302032D02*
X1463456D01*
G01X1464249Y1304632D02*
Y1302032D01*
G01X1469338Y1298998D02*
X1463997D01*
G01X1476691Y1315458D02*
Y1318058D01*
G01X1477484Y1315458D02*
X1476691D01*
G01X1464249Y1325654D02*
Y1323463D01*
G01X1471997Y1312179D02*
X1477338D01*
G01X1470860Y1323418D02*
Y1329618D01*
G01X1474060Y1323418D02*
X1470860D01*
G01X1474060Y1329618D02*
Y1323418D01*
G01X1466858Y1317291D02*
X1470058D01*
G01X1466858Y1311091D02*
Y1317291D01*
G01X1470058Y1311091D02*
X1466858D01*
G01X1470058Y1317291D02*
Y1311091D01*
G01X1467281Y1317992D02*
Y1321192D01*
G01X1473481Y1317992D02*
X1467281D01*
G01X1473481Y1321192D02*
Y1317992D01*
G01X1467281Y1321192D02*
X1473481D01*
G01X1476691Y1324669D02*
Y1326367D01*
G01Y1339080D02*
X1477699D01*
G01X1476691Y1337226D02*
Y1339080D01*
G01X1463516Y1325654D02*
X1464249D01*
G01X1474060Y1333918D02*
X1470860D01*
G01X1474060Y1340118D02*
Y1333918D01*
G01X1470860D02*
Y1340118D01*
G01X1463037Y1334510D02*
Y1328310D01*
G01X1470860Y1329618D02*
X1474060D01*
G01X1472873Y1354342D02*
Y1357442D01*
X1473793D01*
X1474100Y1357287D01*
X1474330Y1356925D01*
X1474407Y1356512D01*
X1474330Y1356099D01*
X1474138Y1355789D01*
X1473793Y1355634D01*
X1472873D01*
G01X1475897Y1357442D02*
Y1355220D01*
X1476050Y1354755D01*
X1476357Y1354445D01*
X1476740Y1354342D01*
X1477123Y1354445D01*
X1477430Y1354755D01*
X1477583Y1355220D01*
Y1357442D01*
G01X1479188Y1354704D02*
X1479457Y1354445D01*
X1479763Y1354342D01*
X1480070Y1354445D01*
X1480338Y1354755D01*
X1480530Y1355220D01*
X1480607Y1355685D01*
Y1356254D01*
X1480530Y1356719D01*
X1480338Y1357132D01*
X1480108Y1357339D01*
X1479840Y1357442D01*
X1479533Y1357339D01*
X1479303Y1357132D01*
X1479150Y1356822D01*
X1479073Y1356409D01*
X1479150Y1356047D01*
X1479342Y1355685D01*
X1479572Y1355479D01*
X1479840Y1355427D01*
X1480147Y1355530D01*
X1480377Y1355789D01*
X1480607Y1356254D01*
G01X1481790Y1353309D02*
X1484090D01*
G01X1485273Y1354342D02*
Y1357442D01*
X1486193D01*
X1486500Y1357287D01*
X1486730Y1356925D01*
X1486807Y1356512D01*
X1486730Y1356099D01*
X1486538Y1355789D01*
X1486193Y1355634D01*
X1485273D01*
G01X1489140Y1357442D02*
X1488833Y1357339D01*
X1488603Y1357080D01*
X1488450Y1356770D01*
X1488335Y1356357D01*
X1488297Y1355892D01*
X1488335Y1355427D01*
X1488450Y1355014D01*
X1488603Y1354704D01*
X1488833Y1354445D01*
X1489140Y1354342D01*
X1489447Y1354445D01*
X1489677Y1354704D01*
X1489830Y1355014D01*
X1489945Y1355427D01*
X1489983Y1355892D01*
X1489945Y1356357D01*
X1489830Y1356770D01*
X1489677Y1357080D01*
X1489447Y1357339D01*
X1489140Y1357442D01*
G01X1491090Y1353309D02*
X1493390D01*
G01X1494497Y1354807D02*
X1494727Y1354549D01*
X1494995Y1354394D01*
X1495340Y1354342D01*
X1495685Y1354445D01*
X1495953Y1354652D01*
X1496145Y1355014D01*
X1496183Y1355427D01*
X1496107Y1355840D01*
X1495915Y1356099D01*
X1495647Y1356305D01*
X1495378Y1356357D01*
X1495110Y1356305D01*
X1494765Y1356099D01*
X1494880Y1357442D01*
X1495915D01*
G01X1470860Y1340118D02*
X1474060D01*
G01X1473999Y1348439D02*
X1477199D01*
G01X1473999Y1342239D02*
Y1348439D01*
G01X1477199Y1342239D02*
X1473999D01*
G01X1468343Y1361282D02*
Y1364382D01*
X1469263D01*
X1469570Y1364227D01*
X1469800Y1363865D01*
X1469877Y1363452D01*
X1469800Y1363039D01*
X1469608Y1362729D01*
X1469263Y1362574D01*
X1468343D01*
G01X1471367Y1364382D02*
Y1362160D01*
X1471520Y1361695D01*
X1471827Y1361385D01*
X1472210Y1361282D01*
X1472593Y1361385D01*
X1472900Y1361695D01*
X1473053Y1362160D01*
Y1364382D01*
G01X1475310Y1361282D02*
Y1364382D01*
X1474850Y1363762D01*
G01Y1361282D02*
X1475770D01*
G01X1478410Y1364382D02*
X1478103Y1364279D01*
X1477873Y1364020D01*
X1477720Y1363710D01*
X1477605Y1363297D01*
X1477567Y1362832D01*
X1477605Y1362367D01*
X1477720Y1361954D01*
X1477873Y1361644D01*
X1478103Y1361385D01*
X1478410Y1361282D01*
X1478717Y1361385D01*
X1478947Y1361644D01*
X1479100Y1361954D01*
X1479215Y1362367D01*
X1479253Y1362832D01*
X1479215Y1363297D01*
X1479100Y1363710D01*
X1478947Y1364020D01*
X1478717Y1364279D01*
X1478410Y1364382D01*
G01X1480360Y1360249D02*
X1482660D01*
G01X1483843Y1361282D02*
Y1364382D01*
X1484763D01*
X1485070Y1364227D01*
X1485300Y1363865D01*
X1485377Y1363452D01*
X1485300Y1363039D01*
X1485108Y1362729D01*
X1484763Y1362574D01*
X1483843D01*
G01X1487710Y1364382D02*
X1487403Y1364279D01*
X1487173Y1364020D01*
X1487020Y1363710D01*
X1486905Y1363297D01*
X1486867Y1362832D01*
X1486905Y1362367D01*
X1487020Y1361954D01*
X1487173Y1361644D01*
X1487403Y1361385D01*
X1487710Y1361282D01*
X1488017Y1361385D01*
X1488247Y1361644D01*
X1488400Y1361954D01*
X1488515Y1362367D01*
X1488553Y1362832D01*
X1488515Y1363297D01*
X1488400Y1363710D01*
X1488247Y1364020D01*
X1488017Y1364279D01*
X1487710Y1364382D01*
G01X1489660Y1360249D02*
X1491960D01*
G01X1494370Y1361282D02*
Y1364382D01*
X1492952Y1362160D01*
X1494868D01*
G01X1467723Y1384027D02*
X1479723D01*
G01X1467723Y1378027D02*
Y1384027D01*
G01X1479723Y1378027D02*
X1467723D01*
G01X1467764Y1386027D02*
Y1392027D01*
G01X1479764Y1386027D02*
X1467764D01*
G01Y1392027D02*
X1479764D01*
G01X1467764Y1400027D02*
X1479764D01*
G01X1467764Y1394027D02*
Y1400027D01*
G01X1479764Y1394027D02*
X1467764D01*
G01X1471082Y1403191D02*
X1477184D01*
Y1403662D01*
G01X1464980Y1403462D02*
Y1403191D01*
G01D02*
X1468782D01*
G01X1463403Y1426607D02*
Y1420407D01*
G01X1477184Y1419062D02*
Y1419333D01*
X1473382D01*
G01X1468782D02*
X1464980D01*
Y1419062D01*
G01X1471097Y1425633D02*
Y1422433D01*
G01X1464897Y1425633D02*
X1471097D01*
G01X1464897Y1422433D02*
Y1425633D01*
G01X1471097Y1422433D02*
X1464897D01*
G01X1464981Y1460138D02*
Y1463238D01*
X1465901D01*
X1466208Y1463083D01*
X1466438Y1462721D01*
X1466515Y1462308D01*
X1466438Y1461895D01*
X1466246Y1461585D01*
X1465901Y1461430D01*
X1464981D01*
G01X1468081Y1463238D02*
Y1460138D01*
X1469615D01*
G01X1471948D02*
Y1463238D01*
X1471488Y1462618D01*
G01Y1460138D02*
X1472408D01*
G01X1475048D02*
Y1463238D01*
X1474588Y1462618D01*
G01Y1460138D02*
X1475508D01*
G01X1478148D02*
X1478416Y1460190D01*
X1478723Y1460345D01*
X1478915Y1460603D01*
X1478991Y1460965D01*
X1478915Y1461326D01*
X1478685Y1461636D01*
X1478340Y1461791D01*
X1477956D01*
X1477726Y1461895D01*
X1477535Y1462153D01*
X1477458Y1462515D01*
X1477573Y1462876D01*
X1477841Y1463135D01*
X1478148Y1463238D01*
X1478455Y1463135D01*
X1478723Y1462876D01*
X1478838Y1462515D01*
X1478761Y1462153D01*
X1478570Y1461895D01*
X1478340Y1461791D01*
X1477956D01*
X1477611Y1461636D01*
X1477381Y1461326D01*
X1477305Y1460965D01*
X1477381Y1460603D01*
X1477573Y1460345D01*
X1477880Y1460190D01*
X1478148Y1460138D01*
G01X1474165Y1626502D02*
X1470965D01*
G01X1474165Y1632702D02*
Y1626502D01*
G01X1470965Y1632702D02*
X1474165D01*
G01X1470965Y1626502D02*
Y1632702D01*
G01X1462147Y1632645D02*
X1465347D01*
G01X1462147Y1626445D02*
Y1632645D01*
G01X1465347Y1626445D02*
X1462147D01*
G01X1465347Y1632645D02*
Y1626445D01*
G01X1460717Y1632645D02*
Y1626445D01*
G01X1466240Y1632702D02*
X1469440D01*
G01X1466240Y1626502D02*
Y1632702D01*
G01X1469440Y1626502D02*
X1466240D01*
G01X1469440Y1632702D02*
Y1626502D01*
G01X1473853Y1648852D02*
X1474045Y1648542D01*
X1474275Y1648335D01*
X1474543Y1648232D01*
X1474850Y1648335D01*
X1475080Y1648542D01*
X1475310Y1648852D01*
X1475387Y1649265D01*
Y1651332D01*
G01X1477720Y1648232D02*
Y1651332D01*
X1477260Y1650712D01*
G01Y1648232D02*
X1478180D01*
G01X1480820Y1651332D02*
X1480513Y1651229D01*
X1480283Y1650970D01*
X1480130Y1650660D01*
X1480015Y1650247D01*
X1479977Y1649782D01*
X1480015Y1649317D01*
X1480130Y1648904D01*
X1480283Y1648594D01*
X1480513Y1648335D01*
X1480820Y1648232D01*
X1481127Y1648335D01*
X1481357Y1648594D01*
X1481510Y1648904D01*
X1481625Y1649317D01*
X1481663Y1649782D01*
X1481625Y1650247D01*
X1481510Y1650660D01*
X1481357Y1650970D01*
X1481127Y1651229D01*
X1480820Y1651332D01*
G01X1483192Y1649524D02*
X1483460Y1649885D01*
X1483690Y1650092D01*
X1483997Y1650195D01*
X1484265Y1650092D01*
X1484457Y1649885D01*
X1484610Y1649575D01*
X1484648Y1649214D01*
X1484610Y1648904D01*
X1484457Y1648594D01*
X1484227Y1648335D01*
X1483958Y1648232D01*
X1483652Y1648335D01*
X1483383Y1648645D01*
X1483230Y1649110D01*
X1483192Y1649627D01*
X1483268Y1650299D01*
X1483383Y1650660D01*
X1483575Y1651022D01*
X1483843Y1651280D01*
X1484112Y1651332D01*
X1484380Y1651229D01*
X1484572Y1650970D01*
G01X1465367Y1639315D02*
X1462167D01*
G01X1465367Y1645515D02*
Y1639315D01*
G01X1462167Y1645515D02*
X1465367D01*
G01X1462167Y1639315D02*
Y1645515D01*
G01X1460727D02*
Y1639315D01*
G01X1471927Y1662649D02*
X1475127D01*
G01X1471927Y1656449D02*
Y1662649D01*
G01X1475127Y1656449D02*
X1471927D01*
G01X1475127Y1662649D02*
Y1656449D01*
G01X1470100Y1660426D02*
X1464257Y1666269D01*
G01X1470100Y1652695D02*
Y1660426D01*
G01X1471497Y1669602D02*
Y1667380D01*
X1471650Y1666915D01*
X1471957Y1666605D01*
X1472340Y1666502D01*
X1472723Y1666605D01*
X1473030Y1666915D01*
X1473183Y1667380D01*
Y1669602D01*
G01X1474712Y1669085D02*
X1474942Y1669395D01*
X1475210Y1669550D01*
X1475517Y1669602D01*
X1475900Y1669499D01*
X1476168Y1669240D01*
X1476245Y1668930D01*
X1476207Y1668620D01*
X1476053Y1668362D01*
X1475287Y1667845D01*
X1474942Y1667484D01*
X1474712Y1666967D01*
X1474635Y1666502D01*
X1476245D01*
G01X1478463D02*
X1478540Y1667174D01*
X1478655Y1667742D01*
X1478808Y1668259D01*
X1479000Y1668827D01*
X1479307Y1669602D01*
X1477773D01*
G01X1481640D02*
X1481333Y1669499D01*
X1481103Y1669240D01*
X1480950Y1668930D01*
X1480835Y1668517D01*
X1480797Y1668052D01*
X1480835Y1667587D01*
X1480950Y1667174D01*
X1481103Y1666864D01*
X1481333Y1666605D01*
X1481640Y1666502D01*
X1481947Y1666605D01*
X1482177Y1666864D01*
X1482330Y1667174D01*
X1482445Y1667587D01*
X1482483Y1668052D01*
X1482445Y1668517D01*
X1482330Y1668930D01*
X1482177Y1669240D01*
X1481947Y1669499D01*
X1481640Y1669602D01*
G01X1470100Y1672112D02*
Y1679843D01*
G01X1464257Y1666269D02*
X1470100Y1672112D01*
G01X1483781Y-29811D02*
Y-13211D01*
X1493381D01*
Y-29811D01*
X1483781D01*
G01Y-9811D02*
Y6789D01*
X1493381D01*
Y-9811D01*
X1483781D01*
G01Y10189D02*
Y26789D01*
X1493381D01*
Y10189D01*
X1483781D01*
G01X1489483Y235048D02*
Y231848D01*
G01X1483283D02*
Y235048D01*
G01X1489483Y231848D02*
X1483283D01*
G01Y235048D02*
X1489483D01*
G01X1489185Y256978D02*
Y253778D01*
G01X1482985Y256978D02*
X1489185D01*
G01X1482985Y253778D02*
Y256978D01*
G01X1489185Y253778D02*
X1482985D01*
G01X1479808Y279856D02*
Y283056D01*
G01X1486008Y279856D02*
X1479808D01*
G01X1486008Y283056D02*
Y279856D01*
G01X1479808Y283056D02*
X1486008D01*
G01X1488158Y319356D02*
Y313356D01*
G01X1487964Y362598D02*
Y368798D01*
G01X1491164Y362598D02*
X1487964D01*
G01X1491164Y368798D02*
Y362598D01*
G01X1492274D02*
Y368798D01*
G01X1495474Y362598D02*
X1492274D01*
G01X1479884Y362688D02*
Y368888D01*
G01X1483084Y362688D02*
X1479884D01*
G01X1483084Y368888D02*
Y362688D01*
G01X1487964Y368798D02*
X1491164D01*
G01X1492274D02*
X1495474D01*
G01X1479884Y368888D02*
X1483084D01*
G01X1494984Y412188D02*
X1491784D01*
G01D02*
Y418388D01*
G01X1478984D02*
Y412188D01*
G01X1487784D02*
Y418388D01*
G01X1490984Y412188D02*
X1487784D01*
G01X1490984Y418388D02*
Y412188D01*
G01X1482984D02*
X1479784D01*
G01X1482984Y418388D02*
Y412188D01*
G01X1479784D02*
Y418388D01*
G01X1487300Y420382D02*
Y423582D01*
G01X1493500Y420382D02*
X1487300D01*
G01Y423582D02*
X1493500D01*
G01X1491784Y418388D02*
X1494984D01*
G01X1487784D02*
X1490984D01*
G01X1479784D02*
X1482984D01*
G01X1486900Y423582D02*
Y420382D01*
G01X1480700Y423582D02*
X1486900D01*
G01X1480700Y420382D02*
Y423582D01*
G01X1486900Y420382D02*
X1480700D01*
G01X1483280Y430372D02*
Y433572D01*
G01X1489480Y430372D02*
X1483280D01*
G01X1489480Y433572D02*
Y430372D01*
G01X1483280Y433572D02*
X1489480D01*
G01X1511368Y1171318D02*
G03I-9950J0D01*
G01X1484473Y1253072D02*
Y1256172D01*
X1485393D01*
X1485700Y1256017D01*
X1485930Y1255655D01*
X1486007Y1255242D01*
X1485930Y1254829D01*
X1485738Y1254519D01*
X1485393Y1254364D01*
X1484473D01*
G01X1487573Y1256172D02*
Y1253072D01*
X1489107D01*
G01X1491440D02*
Y1256172D01*
X1490980Y1255552D01*
G01Y1253072D02*
X1491900D01*
G01X1494540D02*
Y1256172D01*
X1494080Y1255552D01*
G01Y1253072D02*
X1495000D01*
G01X1496912Y1255655D02*
X1497142Y1255965D01*
X1497410Y1256120D01*
X1497717Y1256172D01*
X1498100Y1256069D01*
X1498368Y1255810D01*
X1498445Y1255500D01*
X1498407Y1255190D01*
X1498253Y1254932D01*
X1497487Y1254415D01*
X1497142Y1254054D01*
X1496912Y1253537D01*
X1496835Y1253072D01*
X1498445D01*
G01X1490023Y1261242D02*
Y1264342D01*
X1490943D01*
X1491250Y1264187D01*
X1491480Y1263825D01*
X1491557Y1263412D01*
X1491480Y1262999D01*
X1491288Y1262689D01*
X1490943Y1262534D01*
X1490023D01*
G01X1493123Y1264342D02*
Y1261242D01*
X1494657D01*
G01X1496990D02*
Y1264342D01*
X1496530Y1263722D01*
G01Y1261242D02*
X1497450D01*
G01X1500090D02*
Y1264342D01*
X1499630Y1263722D01*
G01Y1261242D02*
X1500550D01*
G01X1477199Y1348439D02*
Y1342239D01*
G01X1491965Y1348493D02*
X1495165D01*
G01X1491965Y1342293D02*
Y1348493D01*
G01X1495165Y1342293D02*
X1491965D01*
G01X1478350Y1345921D02*
Y1349121D01*
G01X1484550Y1345921D02*
X1478350D01*
G01X1484550Y1349121D02*
Y1345921D01*
G01X1478350Y1349121D02*
X1484550D01*
G01X1491123Y1342293D02*
X1487923D01*
G01X1491123Y1348493D02*
Y1342293D01*
G01X1487923Y1348493D02*
X1491123D01*
G01X1487923Y1342293D02*
Y1348493D01*
G01X1479723Y1384027D02*
Y1378027D01*
G01X1479764Y1392027D02*
Y1386027D01*
G01Y1400027D02*
Y1394027D01*
G01X1480894Y1400742D02*
Y1403842D01*
X1481814D01*
X1482121Y1403687D01*
X1482351Y1403325D01*
X1482428Y1402912D01*
X1482351Y1402499D01*
X1482159Y1402189D01*
X1481814Y1402034D01*
X1480894D01*
G01X1483918Y1403842D02*
Y1401620D01*
X1484071Y1401155D01*
X1484378Y1400845D01*
X1484761Y1400742D01*
X1485144Y1400845D01*
X1485451Y1401155D01*
X1485604Y1401620D01*
Y1403842D01*
G01X1487784Y1400742D02*
X1487861Y1401414D01*
X1487976Y1401982D01*
X1488129Y1402499D01*
X1488321Y1403067D01*
X1488628Y1403842D01*
X1487094D01*
G01X1490309Y1401104D02*
X1490578Y1400845D01*
X1490884Y1400742D01*
X1491191Y1400845D01*
X1491459Y1401155D01*
X1491651Y1401620D01*
X1491728Y1402085D01*
Y1402654D01*
X1491651Y1403119D01*
X1491459Y1403532D01*
X1491229Y1403739D01*
X1490961Y1403842D01*
X1490654Y1403739D01*
X1490424Y1403532D01*
X1490271Y1403222D01*
X1490194Y1402809D01*
X1490271Y1402447D01*
X1490463Y1402085D01*
X1490693Y1401879D01*
X1490961Y1401827D01*
X1491268Y1401930D01*
X1491498Y1402189D01*
X1491728Y1402654D01*
G01X1480637Y1419917D02*
X1483837D01*
G01X1480637Y1413717D02*
Y1419917D01*
G01X1483837Y1413717D02*
X1480637D01*
G01X1483837Y1419917D02*
Y1413717D01*
G01X1486912Y1424094D02*
Y1420894D01*
G01X1480712D02*
Y1424094D01*
G01X1486912Y1420894D02*
X1480712D01*
G01X1484593Y1457606D02*
Y1428866D01*
G01D02*
X1478604D01*
G01X1480712Y1424094D02*
X1486912D01*
G01X1516342Y1444452D02*
G03I-13386J0D01*
G01X1489570D02*
X1516342D01*
G01X1478504Y1457606D02*
X1484593D01*
G01X1486903Y1635732D02*
Y1643232D01*
X1489143D01*
X1489890Y1642857D01*
X1490450Y1641982D01*
X1490637Y1640982D01*
X1490450Y1639982D01*
X1489983Y1639232D01*
X1489143Y1638857D01*
X1486903D01*
G01X1494403Y1635732D02*
Y1643232D01*
X1496737D01*
X1497483Y1642857D01*
X1497950Y1642357D01*
X1498137Y1641357D01*
X1497950Y1640357D01*
X1497390Y1639732D01*
X1496737Y1639357D01*
X1494403D01*
G01X1496737D02*
X1498137Y1635732D01*
G01X1505637D02*
X1501903D01*
Y1643232D01*
X1505637D01*
G01X1504143Y1639607D02*
X1501903D01*
G01X1509310Y1636732D02*
X1510057Y1636107D01*
X1510897Y1635732D01*
X1511643D01*
X1512390Y1636107D01*
X1512950Y1636732D01*
X1513230Y1637607D01*
X1513043Y1638482D01*
X1512577Y1639232D01*
X1511737Y1639732D01*
X1510617Y1639982D01*
X1509963Y1640482D01*
X1509683Y1641357D01*
X1509870Y1642232D01*
X1510337Y1642857D01*
X1510990Y1643232D01*
X1511643D01*
X1512297Y1642982D01*
X1512857Y1642357D01*
G01X1516810Y1636732D02*
X1517557Y1636107D01*
X1518397Y1635732D01*
X1519143D01*
X1519890Y1636107D01*
X1520450Y1636732D01*
X1520730Y1637607D01*
X1520543Y1638482D01*
X1520077Y1639232D01*
X1519237Y1639732D01*
X1518117Y1639982D01*
X1517463Y1640482D01*
X1517183Y1641357D01*
X1517370Y1642232D01*
X1517837Y1642857D01*
X1518490Y1643232D01*
X1519143D01*
X1519797Y1642982D01*
X1520357Y1642357D01*
G01X1525057Y1638232D02*
X1527483D01*
G01X1531997Y1635732D02*
Y1643232D01*
X1535543D01*
G01X1534237Y1639607D02*
X1531997D01*
G01X1540150Y1643232D02*
X1542390D01*
G01X1541270D02*
Y1635732D01*
G01X1540150D02*
X1542390D01*
G01X1548770Y1643232D02*
Y1635732D01*
G01X1546623Y1643232D02*
X1550917D01*
G01X1486221Y1646023D02*
Y1781456D01*
G01X1576378Y1646023D02*
X1486221D01*
G01Y1781456D02*
X1576378D01*
G01X1506880Y-26617D02*
X1507190Y-26425D01*
X1507397Y-26195D01*
X1507500Y-25927D01*
X1507397Y-25620D01*
X1507190Y-25390D01*
X1506880Y-25160D01*
X1506467Y-25083D01*
X1504400D01*
G01X1506208Y-23478D02*
X1505847Y-23210D01*
X1505640Y-22980D01*
X1505537Y-22673D01*
X1505640Y-22405D01*
X1505847Y-22213D01*
X1506157Y-22060D01*
X1506518Y-22022D01*
X1506828Y-22060D01*
X1507138Y-22213D01*
X1507397Y-22443D01*
X1507500Y-22712D01*
X1507397Y-23018D01*
X1507087Y-23287D01*
X1506622Y-23440D01*
X1506105Y-23478D01*
X1505433Y-23402D01*
X1505072Y-23287D01*
X1504710Y-23095D01*
X1504452Y-22827D01*
X1504400Y-22558D01*
X1504503Y-22290D01*
X1504762Y-22098D01*
G01X1506208Y-20378D02*
X1505847Y-20110D01*
X1505640Y-19880D01*
X1505537Y-19573D01*
X1505640Y-19305D01*
X1505847Y-19113D01*
X1506157Y-18960D01*
X1506518Y-18922D01*
X1506828Y-18960D01*
X1507138Y-19113D01*
X1507397Y-19343D01*
X1507500Y-19612D01*
X1507397Y-19918D01*
X1507087Y-20187D01*
X1506622Y-20340D01*
X1506105Y-20378D01*
X1505433Y-20302D01*
X1505072Y-20187D01*
X1504710Y-19995D01*
X1504452Y-19727D01*
X1504400Y-19458D01*
X1504503Y-19190D01*
X1504762Y-18998D01*
G01X1506880Y-6617D02*
X1507190Y-6425D01*
X1507397Y-6195D01*
X1507500Y-5927D01*
X1507397Y-5620D01*
X1507190Y-5390D01*
X1506880Y-5160D01*
X1506467Y-5083D01*
X1504400D01*
G01X1506208Y-3478D02*
X1505847Y-3210D01*
X1505640Y-2980D01*
X1505537Y-2673D01*
X1505640Y-2405D01*
X1505847Y-2213D01*
X1506157Y-2060D01*
X1506518Y-2022D01*
X1506828Y-2060D01*
X1507138Y-2213D01*
X1507397Y-2443D01*
X1507500Y-2712D01*
X1507397Y-3018D01*
X1507087Y-3287D01*
X1506622Y-3440D01*
X1506105Y-3478D01*
X1505433Y-3402D01*
X1505072Y-3287D01*
X1504710Y-3095D01*
X1504452Y-2827D01*
X1504400Y-2558D01*
X1504503Y-2290D01*
X1504762Y-2098D01*
G01X1507035Y-493D02*
X1507293Y-263D01*
X1507448Y5D01*
X1507500Y350D01*
X1507397Y695D01*
X1507190Y963D01*
X1506828Y1155D01*
X1506415Y1193D01*
X1506002Y1117D01*
X1505743Y925D01*
X1505537Y657D01*
X1505485Y388D01*
X1505537Y120D01*
X1505743Y-225D01*
X1504400Y-110D01*
Y925D01*
G01X1506880Y14383D02*
X1507190Y14575D01*
X1507397Y14805D01*
X1507500Y15073D01*
X1507397Y15380D01*
X1507190Y15610D01*
X1506880Y15840D01*
X1506467Y15917D01*
X1504400D01*
G01X1506208Y17522D02*
X1505847Y17790D01*
X1505640Y18020D01*
X1505537Y18327D01*
X1505640Y18595D01*
X1505847Y18787D01*
X1506157Y18940D01*
X1506518Y18978D01*
X1506828Y18940D01*
X1507138Y18787D01*
X1507397Y18557D01*
X1507500Y18288D01*
X1507397Y17982D01*
X1507087Y17713D01*
X1506622Y17560D01*
X1506105Y17522D01*
X1505433Y17598D01*
X1505072Y17713D01*
X1504710Y17905D01*
X1504452Y18173D01*
X1504400Y18442D01*
X1504503Y18710D01*
X1504762Y18902D01*
G01X1506880Y20507D02*
X1507242Y20737D01*
X1507448Y21043D01*
X1507500Y21388D01*
X1507448Y21695D01*
X1507190Y22002D01*
X1506880Y22193D01*
X1506570Y22232D01*
X1506208Y22155D01*
X1505950Y21887D01*
X1505847Y21618D01*
Y21273D01*
G01Y21618D02*
X1505692Y21848D01*
X1505433Y22040D01*
X1505123Y22117D01*
X1504813Y22040D01*
X1504555Y21848D01*
X1504400Y21503D01*
X1504452Y21158D01*
X1504658Y20813D01*
G01X1499807Y126962D02*
Y124740D01*
X1499960Y124275D01*
X1500267Y123965D01*
X1500650Y123862D01*
X1501033Y123965D01*
X1501340Y124275D01*
X1501493Y124740D01*
Y126962D01*
G01X1502907Y124482D02*
X1503137Y124120D01*
X1503443Y123914D01*
X1503788Y123862D01*
X1504095Y123914D01*
X1504402Y124172D01*
X1504593Y124482D01*
X1504632Y124792D01*
X1504555Y125154D01*
X1504287Y125412D01*
X1504018Y125515D01*
X1503673D01*
G01X1504018D02*
X1504248Y125670D01*
X1504440Y125929D01*
X1504517Y126239D01*
X1504440Y126549D01*
X1504248Y126807D01*
X1503903Y126962D01*
X1503558Y126910D01*
X1503213Y126704D01*
G01X1506122Y126445D02*
X1506352Y126755D01*
X1506620Y126910D01*
X1506927Y126962D01*
X1507310Y126859D01*
X1507578Y126600D01*
X1507655Y126290D01*
X1507617Y125980D01*
X1507463Y125722D01*
X1506697Y125205D01*
X1506352Y124844D01*
X1506122Y124327D01*
X1506045Y123862D01*
X1507655D01*
G01X1509222Y126445D02*
X1509452Y126755D01*
X1509720Y126910D01*
X1510027Y126962D01*
X1510410Y126859D01*
X1510678Y126600D01*
X1510755Y126290D01*
X1510717Y125980D01*
X1510563Y125722D01*
X1509797Y125205D01*
X1509452Y124844D01*
X1509222Y124327D01*
X1509145Y123862D01*
X1510755D01*
G01X1494309Y278427D02*
Y281627D01*
G01X1500509Y278427D02*
X1494309D01*
G01X1500509Y281627D02*
Y278427D01*
G01X1494309Y281627D02*
X1500509D01*
G01X1507058Y281656D02*
Y278456D01*
G01X1500858Y281656D02*
X1507058D01*
G01X1500858Y278456D02*
Y281656D01*
G01X1507058Y278456D02*
X1500858D01*
G01X1499807Y291120D02*
Y285031D01*
G01X1509094Y293678D02*
X1509228D01*
G01X1509094Y296780D02*
Y293678D01*
G01X1506801Y286430D02*
Y289630D01*
G01X1513001Y286430D02*
X1506801D01*
G01Y289630D02*
X1513001D01*
G01X1506202Y293657D02*
X1503002D01*
G01X1506202Y299857D02*
Y293657D01*
G01X1503002D02*
Y299857D01*
G01X1505878Y283355D02*
X1502678D01*
G01X1505878Y289555D02*
Y283355D01*
G01X1502678Y289555D02*
X1505878D01*
G01X1502678Y283355D02*
Y289555D01*
G01X1499807Y311409D02*
Y305420D01*
G01X1509094Y305882D02*
Y302780D01*
G01X1509228Y305882D02*
X1509094D01*
G01X1503002Y299857D02*
X1506202D01*
G01Y305656D02*
X1503002D01*
G01X1506202Y311856D02*
Y305656D01*
G01X1503002Y311856D02*
X1506202D01*
G01X1503002Y305656D02*
Y311856D01*
G01X1495474Y368798D02*
Y362598D01*
G01X1499784D02*
X1496584D01*
G01X1499784Y368798D02*
Y362598D01*
G01X1496584D02*
Y368798D01*
G01D02*
X1499784D01*
G01X1500541Y396056D02*
Y393834D01*
X1500694Y393369D01*
X1501001Y393059D01*
X1501384Y392956D01*
X1501767Y393059D01*
X1502074Y393369D01*
X1502227Y393834D01*
Y396056D01*
G01X1504484Y392956D02*
X1504752Y393008D01*
X1505059Y393163D01*
X1505251Y393421D01*
X1505327Y393783D01*
X1505251Y394144D01*
X1505021Y394454D01*
X1504676Y394609D01*
X1504292D01*
X1504062Y394713D01*
X1503871Y394971D01*
X1503794Y395333D01*
X1503909Y395694D01*
X1504177Y395953D01*
X1504484Y396056D01*
X1504791Y395953D01*
X1505059Y395694D01*
X1505174Y395333D01*
X1505097Y394971D01*
X1504906Y394713D01*
X1504676Y394609D01*
X1504292D01*
X1503947Y394454D01*
X1503717Y394144D01*
X1503641Y393783D01*
X1503717Y393421D01*
X1503909Y393163D01*
X1504216Y393008D01*
X1504484Y392956D01*
G01X1506741Y393576D02*
X1506971Y393214D01*
X1507277Y393008D01*
X1507622Y392956D01*
X1507929Y393008D01*
X1508236Y393266D01*
X1508427Y393576D01*
X1508466Y393886D01*
X1508389Y394248D01*
X1508121Y394506D01*
X1507852Y394609D01*
X1507507D01*
G01X1507852D02*
X1508082Y394764D01*
X1508274Y395023D01*
X1508351Y395333D01*
X1508274Y395643D01*
X1508082Y395901D01*
X1507737Y396056D01*
X1507392Y396004D01*
X1507047Y395798D01*
G01X1496934Y388038D02*
Y382388D01*
G01X1494684Y390288D02*
X1496934Y388038D01*
G01Y392538D02*
X1494684Y390288D01*
G01X1496934Y398188D02*
Y392538D01*
G01X1499304Y387368D02*
X1502504D01*
G01X1499304Y381168D02*
Y387368D01*
G01X1502504Y381168D02*
X1499304D01*
G01X1502504Y387368D02*
Y381168D01*
G01X1494984Y418388D02*
Y412188D01*
G01X1498984D02*
X1495784D01*
G01X1498984Y418388D02*
Y412188D01*
G01X1495784D02*
Y418388D01*
G01X1493500Y423582D02*
Y420382D01*
G01X1495784Y418388D02*
X1498984D01*
G01X1502973Y513157D02*
Y516257D01*
X1503970Y513674D01*
X1504967Y516257D01*
Y513157D01*
G01X1507837D02*
X1506303D01*
Y516257D01*
X1507837D01*
G01X1507223Y514759D02*
X1506303D01*
G01X1510170Y513157D02*
Y516257D01*
X1509710Y515637D01*
G01Y513157D02*
X1510630D01*
G01X1512427Y513777D02*
X1512657Y513415D01*
X1512963Y513209D01*
X1513308Y513157D01*
X1513615Y513209D01*
X1513922Y513467D01*
X1514113Y513777D01*
X1514152Y514087D01*
X1514075Y514449D01*
X1513807Y514707D01*
X1513538Y514810D01*
X1513193D01*
G01X1513538D02*
X1513768Y514965D01*
X1513960Y515224D01*
X1514037Y515534D01*
X1513960Y515844D01*
X1513768Y516102D01*
X1513423Y516257D01*
X1513078Y516205D01*
X1512733Y515999D01*
G01X1498203Y807281D02*
G03X1517332Y811121I9179J3840D01*
G01D02*
G03X1502646Y819872I-9950J0D01*
G01X1497345Y1192862D02*
Y1195962D01*
G01X1498955D02*
Y1192862D01*
G01Y1194412D02*
X1497345D01*
G01X1501250Y1192862D02*
Y1195962D01*
X1500790Y1195342D01*
G01Y1192862D02*
X1501710D01*
G01X1504273D02*
X1504350Y1193534D01*
X1504465Y1194102D01*
X1504618Y1194619D01*
X1504810Y1195187D01*
X1505117Y1195962D01*
X1503583D01*
G01X1506203Y1271202D02*
Y1274302D01*
X1507123D01*
X1507430Y1274147D01*
X1507660Y1273785D01*
X1507737Y1273372D01*
X1507660Y1272959D01*
X1507468Y1272649D01*
X1507123Y1272494D01*
X1506203D01*
G01X1509303Y1274302D02*
Y1271202D01*
X1510837D01*
G01X1513170D02*
Y1274302D01*
X1512710Y1273682D01*
G01Y1271202D02*
X1513630D01*
G01X1516270Y1274302D02*
X1515963Y1274199D01*
X1515733Y1273940D01*
X1515580Y1273630D01*
X1515465Y1273217D01*
X1515427Y1272752D01*
X1515465Y1272287D01*
X1515580Y1271874D01*
X1515733Y1271564D01*
X1515963Y1271305D01*
X1516270Y1271202D01*
X1516577Y1271305D01*
X1516807Y1271564D01*
X1516960Y1271874D01*
X1517075Y1272287D01*
X1517113Y1272752D01*
X1517075Y1273217D01*
X1516960Y1273630D01*
X1516807Y1273940D01*
X1516577Y1274199D01*
X1516270Y1274302D01*
G01X1501525Y1268871D02*
Y1312179D01*
G01X1496184Y1268871D02*
X1501525D01*
G01X1504362Y1291541D02*
Y1334849D01*
G01X1509703Y1291541D02*
X1504362D01*
G01X1496377Y1315458D02*
X1495584D01*
G01X1496377Y1318058D02*
Y1315458D01*
G01X1501525Y1312179D02*
X1496184D01*
G01X1508819Y1338256D02*
Y1340856D01*
G01X1509612Y1338256D02*
X1508819D01*
G01X1496377Y1339080D02*
Y1336889D01*
G01X1495644Y1339080D02*
X1496377D01*
G01X1504362Y1334849D02*
X1509703D01*
G01X1498986Y1330717D02*
X1502186D01*
G01X1498986Y1324517D02*
Y1330717D01*
G01X1502186Y1324517D02*
X1498986D01*
G01X1502186Y1330717D02*
Y1324517D01*
G01X1499879Y1337237D02*
Y1340437D01*
G01X1506079Y1337237D02*
X1499879D01*
G01X1506079Y1340437D02*
Y1337237D01*
G01X1508819Y1347467D02*
Y1349165D01*
G01X1499879Y1340437D02*
X1506079D01*
G01X1502988Y1352416D02*
X1506188D01*
G01X1502988Y1346216D02*
Y1352416D01*
G01X1506188Y1346216D02*
X1502988D01*
G01X1506188Y1352416D02*
Y1346216D01*
G01X1495165Y1348493D02*
Y1342293D01*
G01X1508819Y1361878D02*
X1509827D01*
G01X1508819Y1360024D02*
Y1361878D01*
G01X1506151Y1371249D02*
X1509351D01*
G01X1506151Y1365049D02*
Y1371249D01*
G01X1509351Y1365049D02*
X1506151D01*
G01X1509351Y1371249D02*
Y1365049D01*
G01X1506188Y1356716D02*
X1502988D01*
G01X1506188Y1362916D02*
Y1356716D01*
G01X1502988Y1362916D02*
X1506188D01*
G01X1502988Y1356716D02*
Y1362916D01*
G01X1506035Y1373817D02*
Y1376917D01*
X1506955D01*
X1507262Y1376762D01*
X1507492Y1376400D01*
X1507569Y1375987D01*
X1507492Y1375574D01*
X1507300Y1375264D01*
X1506955Y1375109D01*
X1506035D01*
G01X1509059Y1376917D02*
Y1374695D01*
X1509212Y1374230D01*
X1509519Y1373920D01*
X1509902Y1373817D01*
X1510285Y1373920D01*
X1510592Y1374230D01*
X1510745Y1374695D01*
Y1376917D01*
G01X1512274Y1375109D02*
X1512542Y1375470D01*
X1512772Y1375677D01*
X1513079Y1375780D01*
X1513347Y1375677D01*
X1513539Y1375470D01*
X1513692Y1375160D01*
X1513730Y1374799D01*
X1513692Y1374489D01*
X1513539Y1374179D01*
X1513309Y1373920D01*
X1513040Y1373817D01*
X1512734Y1373920D01*
X1512465Y1374230D01*
X1512312Y1374695D01*
X1512274Y1375212D01*
X1512350Y1375884D01*
X1512465Y1376245D01*
X1512657Y1376607D01*
X1512925Y1376865D01*
X1513194Y1376917D01*
X1513462Y1376814D01*
X1513654Y1376555D01*
G01X1514952Y1372784D02*
X1517252D01*
G01X1518435Y1373817D02*
Y1376917D01*
X1519355D01*
X1519662Y1376762D01*
X1519892Y1376400D01*
X1519969Y1375987D01*
X1519892Y1375574D01*
X1519700Y1375264D01*
X1519355Y1375109D01*
X1518435D01*
G01X1522302Y1376917D02*
X1521995Y1376814D01*
X1521765Y1376555D01*
X1521612Y1376245D01*
X1521497Y1375832D01*
X1521459Y1375367D01*
X1521497Y1374902D01*
X1521612Y1374489D01*
X1521765Y1374179D01*
X1521995Y1373920D01*
X1522302Y1373817D01*
X1522609Y1373920D01*
X1522839Y1374179D01*
X1522992Y1374489D01*
X1523107Y1374902D01*
X1523145Y1375367D01*
X1523107Y1375832D01*
X1522992Y1376245D01*
X1522839Y1376555D01*
X1522609Y1376814D01*
X1522302Y1376917D01*
G01X1524252Y1372784D02*
X1526552D01*
G01X1528502Y1373817D02*
X1528770Y1373869D01*
X1529077Y1374024D01*
X1529269Y1374282D01*
X1529345Y1374644D01*
X1529269Y1375005D01*
X1529039Y1375315D01*
X1528694Y1375470D01*
X1528310D01*
X1528080Y1375574D01*
X1527889Y1375832D01*
X1527812Y1376194D01*
X1527927Y1376555D01*
X1528195Y1376814D01*
X1528502Y1376917D01*
X1528809Y1376814D01*
X1529077Y1376555D01*
X1529192Y1376194D01*
X1529115Y1375832D01*
X1528924Y1375574D01*
X1528694Y1375470D01*
X1528310D01*
X1527965Y1375315D01*
X1527735Y1375005D01*
X1527659Y1374644D01*
X1527735Y1374282D01*
X1527927Y1374024D01*
X1528234Y1373869D01*
X1528502Y1373817D01*
G01X1502023Y1414250D02*
Y1417350D01*
G01X1503633D02*
Y1414250D01*
G01Y1415800D02*
X1502023D01*
G01X1506388Y1414250D02*
Y1417350D01*
X1504970Y1415128D01*
X1506886D01*
G01X1509488Y1414250D02*
Y1417350D01*
X1508070Y1415128D01*
X1509986D01*
G01X1503276Y1653682D02*
Y1656782D01*
X1502816Y1656162D01*
G01Y1653682D02*
X1503736D01*
G01X1498032Y1657834D02*
X1564567D01*
G01X1498032Y1769645D02*
Y1657834D01*
G01X1494443Y1670835D02*
Y1673935D01*
X1496207Y1670835D01*
Y1673935D01*
G01X1494328Y1675559D02*
Y1678659D01*
X1495325Y1676076D01*
X1496322Y1678659D01*
Y1675559D01*
G01X1494558Y1683383D02*
Y1680283D01*
X1496092D01*
G01X1494865Y1697557D02*
X1495785D01*
G01X1495325D02*
Y1694457D01*
G01X1494865D02*
X1495785D01*
G01X1494482Y1685008D02*
Y1688108D01*
G01X1495938D02*
X1494482Y1686196D01*
G01X1496168Y1685008D02*
X1495133Y1687075D01*
G01X1494558Y1690352D02*
X1494750Y1690042D01*
X1494980Y1689835D01*
X1495248Y1689732D01*
X1495555Y1689835D01*
X1495785Y1690042D01*
X1496015Y1690352D01*
X1496092Y1690765D01*
Y1692832D01*
G01X1494520Y1699181D02*
Y1702281D01*
G01X1496130D02*
Y1699181D01*
G01Y1700731D02*
X1494520D01*
G01X1495555Y1705456D02*
X1496322D01*
Y1704526D01*
X1496092Y1704216D01*
X1495823Y1704009D01*
X1495440Y1703906D01*
X1495057Y1704009D01*
X1494788Y1704216D01*
X1494558Y1704526D01*
X1494405Y1704888D01*
X1494328Y1705301D01*
Y1705663D01*
X1494405Y1705973D01*
X1494558Y1706334D01*
X1494788Y1706644D01*
X1495018Y1706851D01*
X1495325Y1707006D01*
X1495593D01*
X1495900Y1706903D01*
X1496130Y1706696D01*
G01X1494597Y1708630D02*
Y1711730D01*
X1496053D01*
G01X1495517Y1710232D02*
X1494597D01*
G01X1496092Y1713354D02*
X1494558D01*
Y1716454D01*
X1496092D01*
G01X1495478Y1714956D02*
X1494558D01*
G01X1496168Y1725645D02*
X1495938Y1725800D01*
X1495670Y1725903D01*
X1495363D01*
X1495018Y1725748D01*
X1494750Y1725490D01*
X1494558Y1725180D01*
X1494405Y1724663D01*
X1494367Y1724198D01*
X1494443Y1723733D01*
X1494558Y1723423D01*
X1494788Y1723113D01*
X1495057Y1722906D01*
X1495325Y1722803D01*
X1495593D01*
X1495862Y1722906D01*
X1496092Y1723061D01*
X1496283Y1723268D01*
G01X1495632Y1729181D02*
X1495785Y1729336D01*
X1495900Y1729595D01*
X1495977Y1729956D01*
X1495900Y1730266D01*
X1495747Y1730473D01*
X1495478Y1730628D01*
X1494443D01*
Y1727528D01*
X1495708D01*
X1495977Y1727735D01*
X1496130Y1728045D01*
X1496207Y1728406D01*
X1496130Y1728768D01*
X1495900Y1729078D01*
X1495632Y1729181D01*
X1494443D01*
G01X1494482Y1718079D02*
Y1721179D01*
X1495248D01*
X1495555Y1721024D01*
X1495785Y1720817D01*
X1495977Y1720507D01*
X1496130Y1720146D01*
X1496168Y1719629D01*
X1496130Y1719112D01*
X1495977Y1718751D01*
X1495785Y1718441D01*
X1495555Y1718234D01*
X1495248Y1718079D01*
X1494482D01*
G01X1505053Y1736412D02*
X1510053D01*
G01X1505053Y1739812D02*
Y1736412D01*
G01X1507053Y1737812D02*
X1505053Y1739812D01*
G01X1503053Y1737812D02*
X1507053D01*
G01X1505053Y1739812D02*
X1503053Y1737812D01*
G01X1498032Y1740118D02*
X1564567D01*
G01Y1769645D02*
X1498032D01*
G01X1525755Y48510D02*
Y-2520D01*
X1796307D01*
Y51142D01*
G01X1526254Y53015D02*
X1523054D01*
G01D02*
Y59215D01*
G01D02*
X1526254D01*
G01X1521500Y122362D02*
X1524102Y119760D01*
X1528324D01*
Y131964D01*
X1514676D01*
Y119760D01*
X1518898D01*
X1521500Y122362D01*
G01X1524518Y117705D02*
X1527718D01*
G01X1524518Y111505D02*
Y117705D01*
G01X1527718Y111505D02*
X1524518D01*
G01X1514900Y118062D02*
X1521100D01*
Y114862D01*
X1514900D01*
Y118062D01*
G01X1536321Y133746D02*
X1524509D01*
G01D02*
Y147602D01*
G01X1513900Y137762D02*
X1520100D01*
Y134562D01*
X1513900D01*
Y137762D01*
G01X1524509Y147602D02*
X1536321D01*
G01X1524558Y152251D02*
X1530758D01*
G01X1524558Y149051D02*
Y152251D01*
G01X1530758Y149051D02*
X1524558D01*
G01X1518863Y191737D02*
X1515663D01*
G01X1518863Y197937D02*
Y191737D01*
G01X1515663Y197937D02*
X1518863D01*
G01X1515663Y191737D02*
Y197937D01*
G01X1515468Y233516D02*
Y236716D01*
G01X1521668Y233516D02*
X1515468D01*
G01X1521668Y236716D02*
Y233516D01*
G01Y232716D02*
Y229516D01*
G01X1515468Y232716D02*
X1521668D01*
G01X1515468Y229516D02*
Y232716D01*
G01X1521668Y229516D02*
X1515468D01*
G01X1521668Y240716D02*
Y237516D01*
G01X1515468Y240716D02*
X1521668D01*
G01X1515468Y237516D02*
Y240716D01*
G01X1521668Y237516D02*
X1515468D01*
G01Y241762D02*
Y244962D01*
G01X1521668Y241762D02*
X1515468D01*
G01X1521668Y244962D02*
Y241762D01*
G01X1515468Y244962D02*
X1521668D01*
G01Y251298D02*
Y248098D01*
G01X1515468D02*
Y251298D01*
G01X1521668Y248098D02*
X1515468D01*
G01Y236716D02*
X1521668D01*
G01Y264216D02*
Y261016D01*
G01X1515468Y264216D02*
X1521668D01*
G01X1515468Y261016D02*
Y264216D01*
G01X1521668Y261016D02*
X1515468D01*
G01Y257016D02*
Y260216D01*
G01X1521668Y257016D02*
X1515468D01*
G01X1521668Y260216D02*
Y257016D01*
G01X1515468Y260216D02*
X1521668D01*
G01X1515468Y253016D02*
Y256216D01*
G01X1521668Y253016D02*
X1515468D01*
G01X1521668Y256216D02*
Y253016D01*
G01X1515468Y256216D02*
X1521668D01*
G01X1515468Y251298D02*
X1521668D01*
G01X1521358Y282556D02*
Y279356D01*
G01X1515158Y282556D02*
X1521358D01*
G01X1515158Y279356D02*
Y282556D01*
G01X1521358Y279356D02*
X1515158D01*
G01X1521600Y273962D02*
Y270762D01*
G01X1515400Y273962D02*
X1521600D01*
G01X1515400Y270762D02*
Y273962D01*
G01X1521600Y270762D02*
X1515400D01*
G01X1521738Y269814D02*
Y266614D01*
G01X1515538Y269814D02*
X1521738D01*
G01X1515538Y266614D02*
Y269814D01*
G01X1521738Y266614D02*
X1515538D01*
G01X1524618Y293886D02*
Y305886D01*
G01X1530618Y293886D02*
X1524618D01*
G01X1524434Y286577D02*
Y289677D01*
X1525354D01*
X1525661Y289522D01*
X1525891Y289160D01*
X1525968Y288747D01*
X1525891Y288334D01*
X1525699Y288024D01*
X1525354Y287869D01*
X1524434D01*
G01X1527458Y289677D02*
Y287455D01*
X1527611Y286990D01*
X1527918Y286680D01*
X1528301Y286577D01*
X1528684Y286680D01*
X1528991Y286990D01*
X1529144Y287455D01*
Y289677D01*
G01X1531324Y286577D02*
X1531401Y287249D01*
X1531516Y287817D01*
X1531669Y288334D01*
X1531861Y288902D01*
X1532168Y289677D01*
X1530634D01*
G01X1534961Y286577D02*
Y289677D01*
X1533543Y287455D01*
X1535459D01*
G01X1517362Y293678D02*
Y296780D01*
G01X1517228Y293678D02*
X1517362D01*
G01Y298880D02*
Y300680D01*
G01X1523428Y297675D02*
X1520228D01*
G01X1523428Y303875D02*
Y297675D01*
G01X1520228D02*
Y303875D01*
G01X1513001Y289630D02*
Y286430D01*
G01X1521358Y290556D02*
Y287356D01*
G01X1515158Y290556D02*
X1521358D01*
G01X1515158Y287356D02*
Y290556D01*
G01X1521358Y287356D02*
X1515158D01*
G01Y283356D02*
Y286556D01*
G01X1521358Y283356D02*
X1515158D01*
G01X1521358Y286556D02*
Y283356D01*
G01X1515158Y286556D02*
X1521358D01*
G01X1524618Y305886D02*
X1530618D01*
G01X1517362Y305882D02*
X1517228D01*
G01X1517362Y302780D02*
Y305882D01*
G01X1520228Y303875D02*
X1523428D01*
G01X1528071Y835668D02*
X1524332D01*
G01D02*
Y838464D01*
G01X1524331Y835668D02*
Y838464D01*
G01X1528071Y835668D02*
X1524331D01*
G01X1516458Y835708D02*
Y838464D01*
G01X1516457Y835708D02*
Y838464D01*
G01X1516458Y835708D02*
Y832558D01*
G01Y833556D02*
Y829802D01*
G01D02*
Y832558D01*
G01X1516457Y835708D02*
Y832558D01*
G01Y833556D02*
Y829803D01*
G01D02*
Y832558D01*
G01X1524332Y838464D02*
X1516458D01*
G01X1524331D02*
X1516457D01*
G01X1524882Y996338D02*
X1532954Y1003031D01*
G01X1524882Y996338D02*
X1532953Y1003031D01*
G01X1524882Y986102D02*
Y996338D01*
G01Y986103D02*
Y996338D01*
G01X1532954Y979409D02*
X1524882Y986102D01*
G01X1532953Y979410D02*
X1524882Y986103D01*
G01X1528820Y1116456D02*
G03Y1110157I0J-3149D01*
G01X1528819Y1116456D02*
G03Y1110157I0J-3149D01*
G01X1524332Y1143976D02*
Y1146771D01*
G01X1524331Y1143977D02*
Y1146771D01*
G01X1516458Y1152637D02*
Y1143976D01*
G01D02*
X1524332D01*
G01X1516457Y1152638D02*
Y1143977D01*
G01D02*
X1524331D01*
G01X1528071Y1146771D02*
X1524332D01*
G01X1528071D02*
X1524331D01*
G01X1519995Y1286909D02*
Y1290009D01*
X1520915D01*
X1521222Y1289854D01*
X1521452Y1289492D01*
X1521529Y1289079D01*
X1521452Y1288666D01*
X1521260Y1288356D01*
X1520915Y1288201D01*
X1519995D01*
G01X1523095Y1290009D02*
Y1286909D01*
X1524629D01*
G01X1526885D02*
X1526962Y1287581D01*
X1527077Y1288149D01*
X1527230Y1288666D01*
X1527422Y1289234D01*
X1527729Y1290009D01*
X1526195D01*
G01X1524093Y1371291D02*
X1527293D01*
G01X1524093Y1365091D02*
Y1371291D01*
G01X1527293Y1365091D02*
X1524093D01*
G01X1511278Y1368319D02*
Y1371519D01*
G01X1517478Y1368319D02*
X1511278D01*
G01X1517478Y1371519D02*
Y1368319D01*
G01X1511278Y1371519D02*
X1517478D01*
G01X1523251Y1365091D02*
X1520051D01*
G01X1523251Y1371291D02*
Y1365091D01*
G01X1520051Y1371291D02*
X1523251D01*
G01X1520051Y1365091D02*
Y1371291D01*
G01X1529229Y1534714D02*
G02X1522429Y1529714I-6035J1083D01*
G01X1523529Y1539914D02*
G03X1516829Y1534714I-585J-6163D01*
G01D02*
G03X1523629Y1529714I6035J1083D01*
G01X1522529Y1539914D02*
G02X1529229Y1534714I585J-6163D01*
G01X1531039Y1553714D02*
G03I-8010J0D01*
G01X1510679Y1541564D02*
X1511879D01*
G01X1510729Y1541914D02*
X1510679Y1541564D01*
G01X1510829Y1542214D02*
X1510729Y1541914D01*
G01X1510929Y1542364D02*
X1510829Y1542214D01*
G01X1511029Y1542464D02*
X1510929Y1542364D01*
G01X1511179Y1542664D02*
X1511029Y1542464D01*
G01X1511379Y1542814D02*
X1511179Y1542664D01*
G01X1511529Y1542914D02*
X1511379Y1542814D01*
G01X1511629Y1543014D02*
X1511529Y1542914D01*
G01X1511729Y1543164D02*
X1511629Y1543014D01*
G01X1511779Y1543314D02*
X1511729Y1543164D01*
G01X1511779Y1543664D02*
Y1543314D01*
G01X1511729Y1543814D02*
X1511779Y1543664D01*
G01X1511479Y1544064D02*
X1511729Y1543814D01*
G01X1511229Y1544114D02*
X1511479Y1544064D01*
G01X1511029D02*
X1511229Y1544114D01*
G01X1510879Y1543964D02*
X1511029Y1544064D01*
G01X1510779Y1543864D02*
X1510879Y1543964D01*
G01X1510679Y1543664D02*
X1510779Y1543864D01*
G01X1512829Y1543264D02*
Y1541564D01*
G01X1513929Y1542814D02*
Y1541564D01*
G01X1513829Y1543014D02*
X1513929Y1542814D01*
G01X1513679Y1543214D02*
X1513829Y1543014D01*
G01X1513479Y1543264D02*
X1513679Y1543214D01*
G01X1513329Y1543264D02*
X1513479D01*
G01X1513129Y1543214D02*
X1513329Y1543264D01*
G01X1513029Y1543114D02*
X1513129Y1543214D01*
G01X1512929Y1542964D02*
X1513029Y1543114D01*
G01X1512829Y1542764D02*
X1512929Y1542964D01*
G01X1516129Y1544114D02*
Y1541564D01*
G01X1516289Y1542314D02*
G03I-710J0D01*
G01X1516029Y1541764D02*
X1516129Y1541864D01*
G01X1515879Y1541664D02*
X1516029Y1541764D01*
G01X1515629Y1541614D02*
X1515879Y1541664D01*
G01X1515429Y1541614D02*
X1515629D01*
G01X1515279Y1541664D02*
X1515429Y1541614D01*
G01X1515129Y1541764D02*
X1515279Y1541664D01*
G01X1515029Y1541864D02*
X1515129Y1541764D01*
G01X1514929Y1542014D02*
X1515029Y1541864D01*
G01X1514879Y1542264D02*
X1514929Y1542014D01*
G01X1514879Y1542464D02*
Y1542264D01*
G01X1514929Y1542614D02*
X1514879Y1542464D01*
G01X1514979Y1542714D02*
X1514929Y1542614D01*
G01X1515129Y1542864D02*
X1514979Y1542714D01*
G01X1515279Y1542964D02*
X1515129Y1542864D01*
G01X1515479Y1543014D02*
X1515279Y1542964D01*
G01X1515729Y1543014D02*
X1515479D01*
G01X1515879Y1542964D02*
X1515729Y1543014D01*
G01X1516029Y1542864D02*
X1515879Y1542964D01*
G01X1516129Y1542764D02*
X1516029Y1542864D01*
G01X1518479Y1544164D02*
Y1541564D01*
G01X1520679D02*
X1521379Y1543264D01*
G01X1519979D02*
X1520679Y1541564D01*
G01X1522879Y1544164D02*
Y1541564D01*
G01X1525879Y1544464D02*
X1525779Y1544564D01*
G01Y1544264D02*
X1525879Y1544364D01*
G01X1525679D02*
X1525779Y1544264D01*
G01X1525679Y1544464D02*
Y1544364D01*
G01X1525779Y1544564D02*
X1525679Y1544464D01*
G01X1517829Y1559714D02*
X1528829Y1548214D01*
G01X1510422Y1656265D02*
X1510652Y1656575D01*
X1510920Y1656730D01*
X1511227Y1656782D01*
X1511610Y1656679D01*
X1511878Y1656420D01*
X1511955Y1656110D01*
X1511917Y1655800D01*
X1511763Y1655542D01*
X1510997Y1655025D01*
X1510652Y1654664D01*
X1510422Y1654147D01*
X1510345Y1653682D01*
X1511955D01*
G01X1518181Y1654302D02*
X1518411Y1653940D01*
X1518717Y1653734D01*
X1519062Y1653682D01*
X1519369Y1653734D01*
X1519676Y1653992D01*
X1519867Y1654302D01*
X1519906Y1654612D01*
X1519829Y1654974D01*
X1519561Y1655232D01*
X1519292Y1655335D01*
X1518947D01*
G01X1519292D02*
X1519522Y1655490D01*
X1519714Y1655749D01*
X1519791Y1656059D01*
X1519714Y1656369D01*
X1519522Y1656627D01*
X1519177Y1656782D01*
X1518832Y1656730D01*
X1518487Y1656524D01*
G01X1527358Y1653682D02*
Y1656782D01*
X1525940Y1654560D01*
X1527856D01*
G01X1513136Y1736629D02*
X1512070D01*
Y1739129D01*
X1513136D01*
G01X1512710Y1737921D02*
X1512070D01*
G01X1514216Y1736629D02*
Y1739129D01*
X1514750D01*
X1514963Y1739004D01*
X1515123Y1738837D01*
X1515256Y1738587D01*
X1515363Y1738296D01*
X1515390Y1737879D01*
X1515363Y1737462D01*
X1515256Y1737171D01*
X1515123Y1736921D01*
X1514963Y1736754D01*
X1514750Y1736629D01*
X1514216D01*
G01X1517163Y1737879D02*
X1517696D01*
Y1737129D01*
X1517536Y1736879D01*
X1517350Y1736712D01*
X1517083Y1736629D01*
X1516816Y1736712D01*
X1516630Y1736879D01*
X1516470Y1737129D01*
X1516363Y1737421D01*
X1516310Y1737754D01*
Y1738046D01*
X1516363Y1738296D01*
X1516470Y1738587D01*
X1516630Y1738837D01*
X1516790Y1739004D01*
X1517003Y1739129D01*
X1517190D01*
X1517403Y1739046D01*
X1517563Y1738879D01*
G01X1519736Y1736629D02*
X1518670D01*
Y1739129D01*
X1519736D01*
G01X1519310Y1737921D02*
X1518670D01*
G01X1523603Y1736629D02*
X1523390Y1736671D01*
X1523203Y1736837D01*
X1523043Y1737087D01*
X1522936Y1737379D01*
X1522883Y1737712D01*
Y1738046D01*
X1522936Y1738379D01*
X1523043Y1738671D01*
X1523203Y1738921D01*
X1523390Y1739087D01*
X1523603Y1739129D01*
X1523816Y1739087D01*
X1524003Y1738921D01*
X1524163Y1738671D01*
X1524270Y1738379D01*
X1524323Y1738046D01*
Y1737712D01*
X1524270Y1737379D01*
X1524163Y1737087D01*
X1524003Y1736837D01*
X1523816Y1736671D01*
X1523603Y1736629D01*
G01X1525296D02*
Y1739129D01*
X1526310D01*
G01X1525936Y1737921D02*
X1525296D01*
G01X1529616Y1736629D02*
Y1739129D01*
X1530150D01*
X1530363Y1739004D01*
X1530523Y1738837D01*
X1530656Y1738587D01*
X1530763Y1738296D01*
X1530790Y1737879D01*
X1530763Y1737462D01*
X1530656Y1737171D01*
X1530523Y1736921D01*
X1530363Y1736754D01*
X1530150Y1736629D01*
X1529616D01*
G01X1531736D02*
X1532403Y1739129D01*
X1533070Y1736629D01*
G01X1532830Y1737504D02*
X1531976D01*
G01X1534016Y1739129D02*
Y1737337D01*
X1534123Y1736962D01*
X1534336Y1736712D01*
X1534603Y1736629D01*
X1534870Y1736712D01*
X1535083Y1736962D01*
X1535190Y1737337D01*
Y1739129D01*
G01X1536963Y1737879D02*
X1537496D01*
Y1737129D01*
X1537336Y1736879D01*
X1537150Y1736712D01*
X1536883Y1736629D01*
X1536616Y1736712D01*
X1536430Y1736879D01*
X1536270Y1737129D01*
X1536163Y1737421D01*
X1536110Y1737754D01*
Y1738046D01*
X1536163Y1738296D01*
X1536270Y1738587D01*
X1536430Y1738837D01*
X1536590Y1739004D01*
X1536803Y1739129D01*
X1536990D01*
X1537203Y1739046D01*
X1537363Y1738879D01*
G01X1538443Y1736629D02*
Y1739129D01*
G01X1539563D02*
Y1736629D01*
G01Y1737879D02*
X1538443D01*
G01X1541203Y1739129D02*
Y1736629D01*
G01X1540590Y1739129D02*
X1541816D01*
G01X1543936Y1736629D02*
X1542870D01*
Y1739129D01*
X1543936D01*
G01X1543510Y1737921D02*
X1542870D01*
G01X1545070Y1736629D02*
Y1739129D01*
X1545736D01*
X1545950Y1739004D01*
X1546083Y1738837D01*
X1546136Y1738504D01*
X1546083Y1738171D01*
X1545923Y1737962D01*
X1545736Y1737837D01*
X1545070D01*
G01X1545736D02*
X1546136Y1736629D01*
G01X1550590Y1738921D02*
X1550430Y1739046D01*
X1550243Y1739129D01*
X1550030D01*
X1549790Y1739004D01*
X1549603Y1738796D01*
X1549470Y1738546D01*
X1549363Y1738129D01*
X1549336Y1737754D01*
X1549390Y1737379D01*
X1549470Y1737129D01*
X1549630Y1736879D01*
X1549816Y1736712D01*
X1550003Y1736629D01*
X1550190D01*
X1550376Y1736712D01*
X1550536Y1736837D01*
X1550670Y1737004D01*
G01X1551536Y1736629D02*
X1552203Y1739129D01*
X1552870Y1736629D01*
G01X1552630Y1737504D02*
X1551776D01*
G01X1553870Y1736629D02*
Y1739129D01*
X1554536D01*
X1554750Y1739004D01*
X1554883Y1738837D01*
X1554936Y1738504D01*
X1554883Y1738171D01*
X1554723Y1737962D01*
X1554536Y1737837D01*
X1553870D01*
G01X1554536D02*
X1554936Y1736629D01*
G01X1556016D02*
Y1739129D01*
X1556550D01*
X1556763Y1739004D01*
X1556923Y1738837D01*
X1557056Y1738587D01*
X1557163Y1738296D01*
X1557190Y1737879D01*
X1557163Y1737462D01*
X1557056Y1737171D01*
X1556923Y1736921D01*
X1556763Y1736754D01*
X1556550Y1736629D01*
X1556016D01*
G01X1510053Y1736412D02*
X1510953Y1737312D01*
G01X1525789Y48112D02*
Y-2566D01*
G01X1539071Y43779D02*
X1527881D01*
Y79D01*
X1794181D01*
Y43779D01*
G01X1528454Y51096D02*
X1543096D01*
G01X1526254Y59215D02*
Y53015D01*
G01X1530254D02*
X1527054D01*
G01X1530254Y59215D02*
Y53015D01*
G01X1527054D02*
Y59215D01*
G01D02*
X1530254D01*
G01X1538776Y80862D02*
Y83962D01*
X1540540Y80862D01*
Y83962D01*
G01X1542298D02*
X1543218D01*
G01X1542758D02*
Y80862D01*
G01X1542298D02*
X1543218D01*
G01X1546701Y83704D02*
X1546471Y83859D01*
X1546203Y83962D01*
X1545896D01*
X1545551Y83807D01*
X1545283Y83549D01*
X1545091Y83239D01*
X1544938Y82722D01*
X1544900Y82257D01*
X1544976Y81792D01*
X1545091Y81482D01*
X1545321Y81172D01*
X1545590Y80965D01*
X1545858Y80862D01*
X1546126D01*
X1546395Y80965D01*
X1546625Y81120D01*
X1546816Y81327D01*
G01X1548958Y83962D02*
X1548651Y83859D01*
X1548421Y83600D01*
X1548268Y83290D01*
X1548153Y82877D01*
X1548115Y82412D01*
X1548153Y81947D01*
X1548268Y81534D01*
X1548421Y81224D01*
X1548651Y80965D01*
X1548958Y80862D01*
X1549265Y80965D01*
X1549495Y81224D01*
X1549648Y81534D01*
X1549763Y81947D01*
X1549801Y82412D01*
X1549763Y82877D01*
X1549648Y83290D01*
X1549495Y83600D01*
X1549265Y83859D01*
X1548958Y83962D01*
G01X1536849Y88028D02*
X1537041Y87718D01*
X1537271Y87511D01*
X1537539Y87408D01*
X1537846Y87511D01*
X1538076Y87718D01*
X1538306Y88028D01*
X1538383Y88441D01*
Y90508D01*
G01X1539873Y88028D02*
X1540103Y87666D01*
X1540409Y87460D01*
X1540754Y87408D01*
X1541061Y87460D01*
X1541368Y87718D01*
X1541559Y88028D01*
X1541598Y88338D01*
X1541521Y88700D01*
X1541253Y88958D01*
X1540984Y89061D01*
X1540639D01*
G01X1540984D02*
X1541214Y89216D01*
X1541406Y89475D01*
X1541483Y89785D01*
X1541406Y90095D01*
X1541214Y90353D01*
X1540869Y90508D01*
X1540524Y90456D01*
X1540179Y90250D01*
G01X1543739Y87408D02*
X1543816Y88080D01*
X1543931Y88648D01*
X1544084Y89165D01*
X1544276Y89733D01*
X1544583Y90508D01*
X1543049D01*
G01X1529555Y114058D02*
X1532157Y111456D01*
G01X1529555Y118280D02*
Y114058D01*
G01X1541759Y118280D02*
X1529555D01*
G01X1541759Y104632D02*
Y118280D01*
G01X1529555Y104632D02*
X1541759D01*
G01X1529555Y108854D02*
Y104632D01*
G01X1532157Y111456D02*
X1529555Y108854D01*
G01X1527718Y117705D02*
Y111505D01*
G01X1537100Y119762D02*
X1530900D01*
Y122962D01*
X1537100D01*
Y119762D01*
G01X1536321Y147602D02*
Y133746D01*
G01X1540039Y140385D02*
Y136163D01*
G01D02*
X1552243D01*
G01X1537100Y123762D02*
X1530900D01*
Y126962D01*
X1537100D01*
Y123762D01*
G01X1542641Y142987D02*
X1540039Y140385D01*
G01X1552243Y149811D02*
X1540039D01*
G01D02*
Y145589D01*
G01D02*
X1542641Y142987D01*
G01X1530758Y152251D02*
Y149051D01*
G01X1547052Y151273D02*
X1540852D01*
G01D02*
Y154473D01*
G01X1526805Y157961D02*
Y155739D01*
X1526958Y155274D01*
X1527265Y154964D01*
X1527648Y154861D01*
X1528031Y154964D01*
X1528338Y155274D01*
X1528491Y155739D01*
Y157961D01*
G01X1529905Y155326D02*
X1530135Y155068D01*
X1530403Y154913D01*
X1530748Y154861D01*
X1531093Y154964D01*
X1531361Y155171D01*
X1531553Y155533D01*
X1531591Y155946D01*
X1531515Y156359D01*
X1531323Y156618D01*
X1531055Y156824D01*
X1530786Y156876D01*
X1530518Y156824D01*
X1530173Y156618D01*
X1530288Y157961D01*
X1531323D01*
G01X1533120Y157444D02*
X1533350Y157754D01*
X1533618Y157909D01*
X1533925Y157961D01*
X1534308Y157858D01*
X1534576Y157599D01*
X1534653Y157289D01*
X1534615Y156979D01*
X1534461Y156721D01*
X1533695Y156204D01*
X1533350Y155843D01*
X1533120Y155326D01*
X1533043Y154861D01*
X1534653D01*
G01X1540852Y154473D02*
X1547052D01*
G01X1540472Y182460D02*
Y194809D01*
G01X1562724Y182460D02*
X1540472D01*
G01X1532133Y188408D02*
X1532363Y188150D01*
X1532631Y187995D01*
X1532976Y187943D01*
X1533321Y188046D01*
X1533589Y188253D01*
X1533781Y188615D01*
X1533819Y189028D01*
X1533743Y189441D01*
X1533551Y189700D01*
X1533283Y189906D01*
X1533014Y189958D01*
X1532746Y189906D01*
X1532401Y189700D01*
X1532516Y191043D01*
X1533551D01*
G01X1535424Y188305D02*
X1535693Y188046D01*
X1535999Y187943D01*
X1536306Y188046D01*
X1536574Y188356D01*
X1536766Y188821D01*
X1536843Y189286D01*
Y189855D01*
X1536766Y190320D01*
X1536574Y190733D01*
X1536344Y190940D01*
X1536076Y191043D01*
X1535769Y190940D01*
X1535539Y190733D01*
X1535386Y190423D01*
X1535309Y190010D01*
X1535386Y189648D01*
X1535578Y189286D01*
X1535808Y189080D01*
X1536076Y189028D01*
X1536383Y189131D01*
X1536613Y189390D01*
X1536843Y189855D01*
G01X1540472Y266358D02*
X1562724D01*
G01X1540472Y254009D02*
Y266358D01*
G01X1530618Y305886D02*
Y293886D01*
G01X1532048D02*
Y305886D01*
G01X1538048Y293886D02*
X1532048D01*
G01X1538048Y305886D02*
Y293886D01*
G01X1539718Y296026D02*
Y306026D01*
G01Y296026D02*
X1544318D01*
G01X1532048Y305886D02*
X1538048D01*
G01X1539718Y300526D02*
X1544318D01*
G01X1539718Y306026D02*
X1544318D01*
G01X1539718Y301526D02*
X1544318D01*
G01X1536239Y312087D02*
X1542439D01*
G01X1536239Y308887D02*
Y312087D01*
G01X1542439Y308887D02*
X1536239D01*
G01X1538120Y588962D02*
X1541320D01*
G01X1538120Y582762D02*
Y588962D01*
G01X1541320Y582762D02*
X1538120D01*
G01X1541320Y588962D02*
Y582762D01*
G01X1538589Y606038D02*
X1558389D01*
G01X1538589Y617238D02*
Y606038D01*
G01X1558389Y617238D02*
X1538589D01*
G01X1541637Y632565D02*
Y635765D01*
G01X1547837Y632565D02*
X1541637D01*
G01Y635765D02*
X1547837D01*
G01X1528345Y817862D02*
Y820962D01*
G01X1529955D02*
Y817862D01*
G01Y819412D02*
X1528345D01*
G01X1531522Y820445D02*
X1531752Y820755D01*
X1532020Y820910D01*
X1532327Y820962D01*
X1532710Y820859D01*
X1532978Y820600D01*
X1533055Y820290D01*
X1533017Y819980D01*
X1532863Y819722D01*
X1532097Y819205D01*
X1531752Y818844D01*
X1531522Y818327D01*
X1531445Y817862D01*
X1533055D01*
G01X1535350D02*
Y820962D01*
X1534890Y820342D01*
G01Y817862D02*
X1535810D01*
G01X1528071Y835668D02*
G03X1531025Y838621I1J2953D01*
G01X1528071Y835668D02*
G03X1531024Y838621I0J2953D01*
G01X1536891Y829802D02*
Y850235D01*
G01X1536890Y829803D02*
Y850236D01*
G01X1528229Y838464D02*
Y1143976D01*
G01X1538860Y853424D02*
G03X1536891Y851456I-1J-1968D01*
G01D02*
Y850235D01*
G01X1530986D02*
X1528230D01*
G01D02*
Y842361D01*
G01D02*
X1531025D01*
G01X1530986D02*
X1531025D01*
G01D02*
Y838621D01*
G01X1538859Y853425D02*
G03X1536890Y851456I0J-1969D01*
G01D02*
Y850236D01*
G01X1530985D02*
X1528229D01*
G01D02*
Y842362D01*
G01D02*
X1531024D01*
G01X1530985D02*
X1531024D01*
G01D02*
Y838621D01*
G01X1530986Y850235D02*
Y860511D01*
G01X1530985Y850236D02*
Y860512D01*
G01X1543780Y861299D02*
Y853424D01*
X1538839D01*
G01X1530986Y861298D02*
X1532954D01*
G01X1530986Y860511D02*
Y861298D01*
G01X1530985Y861299D02*
X1532953D01*
G01X1530985Y860512D02*
Y861299D01*
G01X1532954Y861298D02*
Y979409D01*
G01X1532953Y861299D02*
Y979410D01*
G01X1538843Y1138857D02*
G03X1536891Y1136895I17J-1969D01*
G01Y861299D01*
G01X1543780Y853424D02*
X1538860D01*
G01X1543780Y853425D02*
X1538859D01*
G01X1536891Y861299D02*
X1532954Y861298D01*
G01X1543780Y869960D02*
X1536891D01*
G01X1560659Y991220D02*
G03I-9950J0D01*
G01X1532954Y1003031D02*
Y1110157D01*
G01X1532953Y1003031D02*
Y1110157D01*
G01X1532954D02*
X1536891D01*
G01D02*
Y1116456D01*
G01X1532954Y1110157D02*
X1528820D01*
G01X1532953D02*
X1536890D01*
G01D02*
Y1116456D01*
G01X1532953Y1110157D02*
X1528819D01*
G01X1536891Y1116456D02*
X1532954D01*
G01X1528820D02*
X1536891D01*
G01X1536890D02*
X1532953D01*
G01X1528819D02*
X1536890D01*
G01X1532954D02*
Y1132204D01*
G01X1532953Y1116456D02*
Y1132205D01*
G01X1531025Y1143818D02*
G03X1528071Y1146771I-2953J0D01*
G01X1531025Y1143818D02*
Y1140078D01*
G01D02*
X1528230D01*
G01X1531024Y1143818D02*
G03X1528071Y1146771I-2952J1D01*
G01X1531024Y1143818D02*
Y1140079D01*
G01D02*
X1528229D01*
G01X1536891Y1148692D02*
G03X1538840Y1146731I1967J6D01*
G01X1543781D01*
Y1138857D01*
X1538843D01*
G01X1543780D02*
X1538860D01*
G01X1543780D02*
X1538859D01*
G01X1538860D02*
G03X1536891Y1136889I-1J-1968D01*
G01X1538859Y1138857D02*
G03X1536890Y1136890I-1J-1968D01*
G01X1532954Y1132204D02*
X1536891D01*
G01Y1136889D02*
Y1132204D01*
G01X1528230Y1140078D02*
Y1132204D01*
G01D02*
X1532954D01*
G01X1536890Y1136890D02*
Y1132205D01*
G01X1528229Y1140079D02*
Y1132205D01*
G01X1532953D02*
X1536890D01*
G01X1528229D02*
X1532953D01*
G01X1536891Y1148700D02*
G03X1538860Y1146731I1969J0D01*
G01X1536891Y1152637D02*
Y1148700D01*
G01X1536890Y1148701D02*
G03X1538859Y1146731I1969J-1D01*
G01X1536890Y1152638D02*
Y1148701D01*
G01X1538860Y1146731D02*
X1543780D01*
G01X1538859D02*
X1543780D01*
G01X1533890Y1291541D02*
Y1334849D01*
G01X1528549Y1291541D02*
X1533890D01*
G01X1539346Y1301818D02*
X1536146D01*
G01X1539346Y1308018D02*
Y1301818D01*
G01X1536146D02*
Y1308018D01*
G01D02*
X1539346D01*
G01X1528505Y1338256D02*
X1527712D01*
G01X1528505Y1340856D02*
Y1338256D01*
G01X1533890Y1334849D02*
X1528549D01*
G01X1531127Y1353568D02*
X1534327D01*
G01X1531127Y1347368D02*
Y1353568D01*
G01X1534327Y1347368D02*
X1531127D01*
G01X1534327Y1353568D02*
Y1347368D01*
G01X1535510Y1353568D02*
X1538710D01*
G01X1535510Y1347368D02*
Y1353568D01*
G01X1538710Y1347368D02*
X1535510D01*
G01X1538710Y1353568D02*
Y1347368D01*
G01X1528505Y1361878D02*
Y1359687D01*
G01X1527772Y1361878D02*
X1528505D01*
G01X1527293Y1371291D02*
Y1365091D01*
G01X1525779Y1543314D02*
Y1541564D01*
G01X1525879Y1544364D02*
Y1544464D01*
G01X1528629Y1542814D02*
Y1541564D01*
G01X1528529Y1543014D02*
X1528629Y1542814D01*
G01X1528379Y1543214D02*
X1528529Y1543014D01*
G01X1528179Y1543264D02*
X1528379Y1543214D01*
G01X1528029Y1543264D02*
X1528179D01*
G01X1527829Y1543214D02*
X1528029Y1543264D01*
G01X1527729Y1543114D02*
X1527829Y1543214D01*
G01X1527629Y1542964D02*
X1527729Y1543114D01*
G01X1527529Y1542764D02*
X1527629Y1542964D01*
G01X1527529Y1543264D02*
Y1541564D01*
G01X1529729Y1543214D02*
X1530629D01*
G01X1530179Y1541564D02*
X1530879Y1541614D01*
G01X1530179Y1544064D02*
Y1541564D01*
G01X1532629D02*
X1532879Y1541664D01*
G01X1532429Y1541564D02*
X1532629D01*
G01X1532179Y1541614D02*
X1532429Y1541564D01*
G01X1532079Y1541664D02*
X1532179Y1541614D01*
G01X1531929Y1541764D02*
X1532079Y1541664D01*
G01X1531829Y1541864D02*
X1531929Y1541764D01*
G01X1531729Y1542014D02*
X1531829Y1541864D01*
G01X1531679Y1542114D02*
X1531729Y1542014D01*
G01X1531629Y1542314D02*
X1531679Y1542114D01*
G01X1531629Y1542464D02*
Y1542314D01*
G01X1531679Y1542714D02*
X1531629Y1542464D01*
G01X1531729Y1542814D02*
X1531679Y1542714D01*
G01X1531829Y1542964D02*
X1531729Y1542814D01*
G01X1531929Y1543064D02*
X1531829Y1542964D01*
G01X1532079Y1543164D02*
X1531929Y1543064D01*
G01X1532179Y1543214D02*
X1532079Y1543164D01*
G01X1532379Y1543264D02*
X1532179Y1543214D01*
G01X1532529Y1543264D02*
X1532379D01*
G01X1532729Y1543214D02*
X1532529Y1543264D01*
G01X1532879Y1543164D02*
X1532729Y1543214D01*
G01X1534579Y1541564D02*
X1535279Y1541614D01*
G01X1534579Y1544064D02*
Y1541564D01*
G01X1534129Y1543214D02*
X1535029D01*
G01X1533929Y1654147D02*
X1534159Y1653889D01*
X1534427Y1653734D01*
X1534772Y1653682D01*
X1535117Y1653785D01*
X1535385Y1653992D01*
X1535577Y1654354D01*
X1535615Y1654767D01*
X1535539Y1655180D01*
X1535347Y1655439D01*
X1535079Y1655645D01*
X1534810Y1655697D01*
X1534542Y1655645D01*
X1534197Y1655439D01*
X1534312Y1656782D01*
X1535347D01*
G01X1541918Y1654974D02*
X1542186Y1655335D01*
X1542416Y1655542D01*
X1542723Y1655645D01*
X1542991Y1655542D01*
X1543183Y1655335D01*
X1543336Y1655025D01*
X1543374Y1654664D01*
X1543336Y1654354D01*
X1543183Y1654044D01*
X1542953Y1653785D01*
X1542684Y1653682D01*
X1542378Y1653785D01*
X1542109Y1654095D01*
X1541956Y1654560D01*
X1541918Y1655077D01*
X1541994Y1655749D01*
X1542109Y1656110D01*
X1542301Y1656472D01*
X1542569Y1656730D01*
X1542838Y1656782D01*
X1543106Y1656679D01*
X1543298Y1656420D01*
G01X1551042Y51096D02*
X1554807D01*
G01X1546807Y112462D02*
Y110240D01*
X1546960Y109775D01*
X1547267Y109465D01*
X1547650Y109362D01*
X1548033Y109465D01*
X1548340Y109775D01*
X1548493Y110240D01*
Y112462D01*
G01X1550750Y109362D02*
Y112462D01*
X1550290Y111842D01*
G01Y109362D02*
X1551210D01*
G01X1553850Y112462D02*
X1553543Y112359D01*
X1553313Y112100D01*
X1553160Y111790D01*
X1553045Y111377D01*
X1553007Y110912D01*
X1553045Y110447D01*
X1553160Y110034D01*
X1553313Y109724D01*
X1553543Y109465D01*
X1553850Y109362D01*
X1554157Y109465D01*
X1554387Y109724D01*
X1554540Y110034D01*
X1554655Y110447D01*
X1554693Y110912D01*
X1554655Y111377D01*
X1554540Y111790D01*
X1554387Y112100D01*
X1554157Y112359D01*
X1553850Y112462D01*
G01X1557410Y109362D02*
Y112462D01*
X1555992Y110240D01*
X1557908D01*
G01X1542179Y119678D02*
Y125878D01*
G01X1545379Y119678D02*
X1542179D01*
G01X1545379Y125878D02*
Y119678D01*
G01X1549297D02*
X1546097D01*
G01X1549297Y125878D02*
Y119678D01*
G01X1546097D02*
Y125878D01*
G01X1552243Y136163D02*
Y149811D01*
G01X1551488Y126181D02*
X1545288D01*
G01D02*
Y129381D01*
G01D02*
X1551488D01*
G01D02*
Y126181D01*
G01X1542179Y125878D02*
X1545379D01*
G01X1546097D02*
X1549297D01*
G01X1557727Y144732D02*
Y142510D01*
X1557880Y142045D01*
X1558187Y141735D01*
X1558570Y141632D01*
X1558953Y141735D01*
X1559260Y142045D01*
X1559413Y142510D01*
Y144732D01*
G01X1560942Y144215D02*
X1561172Y144525D01*
X1561440Y144680D01*
X1561747Y144732D01*
X1562130Y144629D01*
X1562398Y144370D01*
X1562475Y144060D01*
X1562437Y143750D01*
X1562283Y143492D01*
X1561517Y142975D01*
X1561172Y142614D01*
X1560942Y142097D01*
X1560865Y141632D01*
X1562475D01*
G01X1564770D02*
Y144732D01*
X1564310Y144112D01*
G01Y141632D02*
X1565230D01*
G01X1567870Y144732D02*
X1567563Y144629D01*
X1567333Y144370D01*
X1567180Y144060D01*
X1567065Y143647D01*
X1567027Y143182D01*
X1567065Y142717D01*
X1567180Y142304D01*
X1567333Y141994D01*
X1567563Y141735D01*
X1567870Y141632D01*
X1568177Y141735D01*
X1568407Y141994D01*
X1568560Y142304D01*
X1568675Y142717D01*
X1568713Y143182D01*
X1568675Y143647D01*
X1568560Y144060D01*
X1568407Y144370D01*
X1568177Y144629D01*
X1567870Y144732D01*
G01X1547052Y154473D02*
Y151273D01*
G01X1547723Y277740D02*
Y280840D01*
X1548720Y278257D01*
X1549717Y280840D01*
Y277740D01*
G01X1552587D02*
X1551053D01*
Y280840D01*
X1552587D01*
G01X1551973Y279342D02*
X1551053D01*
G01X1557253Y277740D02*
Y280840D01*
X1558212D01*
X1558518Y280685D01*
X1558710Y280478D01*
X1558787Y280065D01*
X1558710Y279652D01*
X1558480Y279393D01*
X1558212Y279238D01*
X1557253D01*
G01X1558212D02*
X1558787Y277740D01*
G01X1561887D02*
X1560353D01*
Y280840D01*
X1561887D01*
G01X1561273Y279342D02*
X1560353D01*
G01X1565063Y280582D02*
X1564833Y280737D01*
X1564565Y280840D01*
X1564258D01*
X1563913Y280685D01*
X1563645Y280427D01*
X1563453Y280117D01*
X1563300Y279600D01*
X1563262Y279135D01*
X1563338Y278670D01*
X1563453Y278360D01*
X1563683Y278050D01*
X1563952Y277843D01*
X1564220Y277740D01*
X1564488D01*
X1564757Y277843D01*
X1564987Y277998D01*
X1565178Y278205D01*
G01X1567320Y277740D02*
X1567013Y277792D01*
X1566745Y277998D01*
X1566515Y278308D01*
X1566362Y278670D01*
X1566285Y279083D01*
Y279497D01*
X1566362Y279910D01*
X1566515Y280272D01*
X1566745Y280582D01*
X1567013Y280788D01*
X1567320Y280840D01*
X1567627Y280788D01*
X1567895Y280582D01*
X1568125Y280272D01*
X1568278Y279910D01*
X1568355Y279497D01*
Y279083D01*
X1568278Y278670D01*
X1568125Y278308D01*
X1567895Y277998D01*
X1567627Y277792D01*
X1567320Y277740D01*
G01X1569462Y280840D02*
X1570420Y277740D01*
X1571378Y280840D01*
G01X1574287Y277740D02*
X1572753D01*
Y280840D01*
X1574287D01*
G01X1573673Y279342D02*
X1572753D01*
G01X1575853Y277740D02*
Y280840D01*
X1576812D01*
X1577118Y280685D01*
X1577310Y280478D01*
X1577387Y280065D01*
X1577310Y279652D01*
X1577080Y279393D01*
X1576812Y279238D01*
X1575853D01*
G01X1576812D02*
X1577387Y277740D01*
G01X1579720D02*
Y279135D01*
X1578953Y280840D01*
G01X1580487D02*
X1579720Y279135D01*
G01X1547953Y271740D02*
Y274840D01*
X1548873D01*
X1549180Y274685D01*
X1549410Y274323D01*
X1549487Y273910D01*
X1549410Y273497D01*
X1549218Y273187D01*
X1548873Y273032D01*
X1547953D01*
G01X1550862Y271740D02*
X1551820Y274840D01*
X1552778Y271740D01*
G01X1552433Y272825D02*
X1551207D01*
G01X1554115Y272153D02*
X1554422Y271895D01*
X1554767Y271740D01*
X1555073D01*
X1555380Y271895D01*
X1555610Y272153D01*
X1555725Y272515D01*
X1555648Y272877D01*
X1555457Y273187D01*
X1555112Y273393D01*
X1554652Y273497D01*
X1554383Y273703D01*
X1554268Y274065D01*
X1554345Y274427D01*
X1554537Y274685D01*
X1554805Y274840D01*
X1555073D01*
X1555342Y274737D01*
X1555572Y274478D01*
G01X1557215Y272153D02*
X1557522Y271895D01*
X1557867Y271740D01*
X1558173D01*
X1558480Y271895D01*
X1558710Y272153D01*
X1558825Y272515D01*
X1558748Y272877D01*
X1558557Y273187D01*
X1558212Y273393D01*
X1557752Y273497D01*
X1557483Y273703D01*
X1557368Y274065D01*
X1557445Y274427D01*
X1557637Y274685D01*
X1557905Y274840D01*
X1558173D01*
X1558442Y274737D01*
X1558672Y274478D01*
G01X1559970Y274840D02*
X1560507Y271740D01*
X1561120Y274840D01*
X1561733Y271740D01*
X1562270Y274840D01*
G01X1564220Y271740D02*
X1563913Y271792D01*
X1563645Y271998D01*
X1563415Y272308D01*
X1563262Y272670D01*
X1563185Y273083D01*
Y273497D01*
X1563262Y273910D01*
X1563415Y274272D01*
X1563645Y274582D01*
X1563913Y274788D01*
X1564220Y274840D01*
X1564527Y274788D01*
X1564795Y274582D01*
X1565025Y274272D01*
X1565178Y273910D01*
X1565255Y273497D01*
Y273083D01*
X1565178Y272670D01*
X1565025Y272308D01*
X1564795Y271998D01*
X1564527Y271792D01*
X1564220Y271740D01*
G01X1566553D02*
Y274840D01*
X1567512D01*
X1567818Y274685D01*
X1568010Y274478D01*
X1568087Y274065D01*
X1568010Y273652D01*
X1567780Y273393D01*
X1567512Y273238D01*
X1566553D01*
G01X1567512D02*
X1568087Y271740D01*
G01X1569577D02*
Y274840D01*
X1570343D01*
X1570650Y274685D01*
X1570880Y274478D01*
X1571072Y274168D01*
X1571225Y273807D01*
X1571263Y273290D01*
X1571225Y272773D01*
X1571072Y272412D01*
X1570880Y272102D01*
X1570650Y271895D01*
X1570343Y271740D01*
X1569577D01*
G01X1577463Y274582D02*
X1577233Y274737D01*
X1576965Y274840D01*
X1576658D01*
X1576313Y274685D01*
X1576045Y274427D01*
X1575853Y274117D01*
X1575700Y273600D01*
X1575662Y273135D01*
X1575738Y272670D01*
X1575853Y272360D01*
X1576083Y272050D01*
X1576352Y271843D01*
X1576620Y271740D01*
X1576888D01*
X1577157Y271843D01*
X1577387Y271998D01*
X1577578Y272205D01*
G01X1578953Y274840D02*
Y271740D01*
X1580487D01*
G01X1583587D02*
X1582053D01*
Y274840D01*
X1583587D01*
G01X1582973Y273342D02*
X1582053D01*
G01X1584962Y271740D02*
X1585920Y274840D01*
X1586878Y271740D01*
G01X1586533Y272825D02*
X1585307D01*
G01X1588253Y271740D02*
Y274840D01*
X1589212D01*
X1589518Y274685D01*
X1589710Y274478D01*
X1589787Y274065D01*
X1589710Y273652D01*
X1589480Y273393D01*
X1589212Y273238D01*
X1588253D01*
G01X1589212D02*
X1589787Y271740D01*
G01X1549027Y297393D02*
X1549180Y297548D01*
X1549295Y297807D01*
X1549372Y298168D01*
X1549295Y298478D01*
X1549142Y298685D01*
X1548873Y298840D01*
X1547838D01*
Y295740D01*
X1549103D01*
X1549372Y295947D01*
X1549525Y296257D01*
X1549602Y296618D01*
X1549525Y296980D01*
X1549295Y297290D01*
X1549027Y297393D01*
X1547838D01*
G01X1551360Y298840D02*
X1552280D01*
G01X1551820D02*
Y295740D01*
G01X1551360D02*
X1552280D01*
G01X1554920D02*
X1554613Y295792D01*
X1554345Y295998D01*
X1554115Y296308D01*
X1553962Y296670D01*
X1553885Y297083D01*
Y297497D01*
X1553962Y297910D01*
X1554115Y298272D01*
X1554345Y298582D01*
X1554613Y298788D01*
X1554920Y298840D01*
X1555227Y298788D01*
X1555495Y298582D01*
X1555725Y298272D01*
X1555878Y297910D01*
X1555955Y297497D01*
Y297083D01*
X1555878Y296670D01*
X1555725Y296308D01*
X1555495Y295998D01*
X1555227Y295792D01*
X1554920Y295740D01*
G01X1557215Y296153D02*
X1557522Y295895D01*
X1557867Y295740D01*
X1558173D01*
X1558480Y295895D01*
X1558710Y296153D01*
X1558825Y296515D01*
X1558748Y296877D01*
X1558557Y297187D01*
X1558212Y297393D01*
X1557752Y297497D01*
X1557483Y297703D01*
X1557368Y298065D01*
X1557445Y298427D01*
X1557637Y298685D01*
X1557905Y298840D01*
X1558173D01*
X1558442Y298737D01*
X1558672Y298478D01*
G01X1563415Y296153D02*
X1563722Y295895D01*
X1564067Y295740D01*
X1564373D01*
X1564680Y295895D01*
X1564910Y296153D01*
X1565025Y296515D01*
X1564948Y296877D01*
X1564757Y297187D01*
X1564412Y297393D01*
X1563952Y297497D01*
X1563683Y297703D01*
X1563568Y298065D01*
X1563645Y298427D01*
X1563837Y298685D01*
X1564105Y298840D01*
X1564373D01*
X1564642Y298737D01*
X1564872Y298478D01*
G01X1566170Y298840D02*
X1566707Y295740D01*
X1567320Y298840D01*
X1567933Y295740D01*
X1568470Y298840D01*
G01X1569462Y295740D02*
X1570420Y298840D01*
X1571378Y295740D01*
G01X1571033Y296825D02*
X1569807D01*
G01X1572753Y295740D02*
Y298840D01*
X1573673D01*
X1573980Y298685D01*
X1574210Y298323D01*
X1574287Y297910D01*
X1574210Y297497D01*
X1574018Y297187D01*
X1573673Y297032D01*
X1572753D01*
G01X1579720Y295740D02*
X1579413Y295792D01*
X1579145Y295998D01*
X1578915Y296308D01*
X1578762Y296670D01*
X1578685Y297083D01*
Y297497D01*
X1578762Y297910D01*
X1578915Y298272D01*
X1579145Y298582D01*
X1579413Y298788D01*
X1579720Y298840D01*
X1580027Y298788D01*
X1580295Y298582D01*
X1580525Y298272D01*
X1580678Y297910D01*
X1580755Y297497D01*
Y297083D01*
X1580678Y296670D01*
X1580525Y296308D01*
X1580295Y295998D01*
X1580027Y295792D01*
X1579720Y295740D01*
G01X1581862Y298840D02*
X1582820Y295740D01*
X1583778Y298840D01*
G01X1585153Y295740D02*
Y298840D01*
X1586112D01*
X1586418Y298685D01*
X1586610Y298478D01*
X1586687Y298065D01*
X1586610Y297652D01*
X1586380Y297393D01*
X1586112Y297238D01*
X1585153D01*
G01X1586112D02*
X1586687Y295740D01*
G01X1548260Y292840D02*
X1549180D01*
G01X1548720D02*
Y289740D01*
G01X1548260D02*
X1549180D01*
G01X1550823D02*
Y292840D01*
X1551820Y290257D01*
X1552817Y292840D01*
Y289740D01*
G01X1553962D02*
X1554920Y292840D01*
X1555878Y289740D01*
G01X1555533Y290825D02*
X1554307D01*
G01X1558250Y291290D02*
X1559017D01*
Y290360D01*
X1558787Y290050D01*
X1558518Y289843D01*
X1558135Y289740D01*
X1557752Y289843D01*
X1557483Y290050D01*
X1557253Y290360D01*
X1557100Y290722D01*
X1557023Y291135D01*
Y291497D01*
X1557100Y291807D01*
X1557253Y292168D01*
X1557483Y292478D01*
X1557713Y292685D01*
X1558020Y292840D01*
X1558288D01*
X1558595Y292737D01*
X1558825Y292530D01*
G01X1561887Y289740D02*
X1560353D01*
Y292840D01*
X1561887D01*
G01X1561273Y291342D02*
X1560353D01*
G01X1566515Y290153D02*
X1566822Y289895D01*
X1567167Y289740D01*
X1567473D01*
X1567780Y289895D01*
X1568010Y290153D01*
X1568125Y290515D01*
X1568048Y290877D01*
X1567857Y291187D01*
X1567512Y291393D01*
X1567052Y291497D01*
X1566783Y291703D01*
X1566668Y292065D01*
X1566745Y292427D01*
X1566937Y292685D01*
X1567205Y292840D01*
X1567473D01*
X1567742Y292737D01*
X1567972Y292478D01*
G01X1569270Y292840D02*
X1569807Y289740D01*
X1570420Y292840D01*
X1571033Y289740D01*
X1571570Y292840D01*
G01X1572562Y289740D02*
X1573520Y292840D01*
X1574478Y289740D01*
G01X1574133Y290825D02*
X1572907D01*
G01X1575853Y289740D02*
Y292840D01*
X1576773D01*
X1577080Y292685D01*
X1577310Y292323D01*
X1577387Y291910D01*
X1577310Y291497D01*
X1577118Y291187D01*
X1576773Y291032D01*
X1575853D01*
G01X1547992Y283740D02*
Y286840D01*
X1549448D01*
G01X1548912Y285342D02*
X1547992D01*
G01X1551053Y286840D02*
Y283740D01*
X1552587D01*
G01X1553962D02*
X1554920Y286840D01*
X1555878Y283740D01*
G01X1555533Y284825D02*
X1554307D01*
G01X1557215Y284153D02*
X1557522Y283895D01*
X1557867Y283740D01*
X1558173D01*
X1558480Y283895D01*
X1558710Y284153D01*
X1558825Y284515D01*
X1558748Y284877D01*
X1558557Y285187D01*
X1558212Y285393D01*
X1557752Y285497D01*
X1557483Y285703D01*
X1557368Y286065D01*
X1557445Y286427D01*
X1557637Y286685D01*
X1557905Y286840D01*
X1558173D01*
X1558442Y286737D01*
X1558672Y286478D01*
G01X1560315Y283740D02*
Y286840D01*
G01X1561925D02*
Y283740D01*
G01Y285290D02*
X1560315D01*
G01X1566515Y284153D02*
X1566822Y283895D01*
X1567167Y283740D01*
X1567473D01*
X1567780Y283895D01*
X1568010Y284153D01*
X1568125Y284515D01*
X1568048Y284877D01*
X1567857Y285187D01*
X1567512Y285393D01*
X1567052Y285497D01*
X1566783Y285703D01*
X1566668Y286065D01*
X1566745Y286427D01*
X1566937Y286685D01*
X1567205Y286840D01*
X1567473D01*
X1567742Y286737D01*
X1567972Y286478D01*
G01X1571263Y286582D02*
X1571033Y286737D01*
X1570765Y286840D01*
X1570458D01*
X1570113Y286685D01*
X1569845Y286427D01*
X1569653Y286117D01*
X1569500Y285600D01*
X1569462Y285135D01*
X1569538Y284670D01*
X1569653Y284360D01*
X1569883Y284050D01*
X1570152Y283843D01*
X1570420Y283740D01*
X1570688D01*
X1570957Y283843D01*
X1571187Y283998D01*
X1571378Y284205D01*
G01X1573520Y283740D02*
Y285135D01*
X1572753Y286840D01*
G01X1574287D02*
X1573520Y285135D01*
G01X1579720Y283740D02*
X1579413Y283792D01*
X1579145Y283998D01*
X1578915Y284308D01*
X1578762Y284670D01*
X1578685Y285083D01*
Y285497D01*
X1578762Y285910D01*
X1578915Y286272D01*
X1579145Y286582D01*
X1579413Y286788D01*
X1579720Y286840D01*
X1580027Y286788D01*
X1580295Y286582D01*
X1580525Y286272D01*
X1580678Y285910D01*
X1580755Y285497D01*
Y285083D01*
X1580678Y284670D01*
X1580525Y284308D01*
X1580295Y283998D01*
X1580027Y283792D01*
X1579720Y283740D01*
G01X1581862Y286840D02*
X1582820Y283740D01*
X1583778Y286840D01*
G01X1585153Y283740D02*
Y286840D01*
X1586112D01*
X1586418Y286685D01*
X1586610Y286478D01*
X1586687Y286065D01*
X1586610Y285652D01*
X1586380Y285393D01*
X1586112Y285238D01*
X1585153D01*
G01X1586112D02*
X1586687Y283740D01*
G01X1544318Y306026D02*
Y296026D01*
G01X1549887Y310140D02*
X1548353D01*
Y313240D01*
X1549887D01*
G01X1549273Y311742D02*
X1548353D01*
G01X1551415Y310553D02*
X1551722Y310295D01*
X1552067Y310140D01*
X1552373D01*
X1552680Y310295D01*
X1552910Y310553D01*
X1553025Y310915D01*
X1552948Y311277D01*
X1552757Y311587D01*
X1552412Y311793D01*
X1551952Y311897D01*
X1551683Y312103D01*
X1551568Y312465D01*
X1551645Y312827D01*
X1551837Y313085D01*
X1552105Y313240D01*
X1552373D01*
X1552642Y313137D01*
X1552872Y312878D01*
G01X1554553Y310140D02*
Y313240D01*
X1555473D01*
X1555780Y313085D01*
X1556010Y312723D01*
X1556087Y312310D01*
X1556010Y311897D01*
X1555818Y311587D01*
X1555473Y311432D01*
X1554553D01*
G01X1557960Y313240D02*
X1558880D01*
G01X1558420D02*
Y310140D01*
G01X1557960D02*
X1558880D01*
G01X1549027Y303393D02*
X1549180Y303548D01*
X1549295Y303807D01*
X1549372Y304168D01*
X1549295Y304478D01*
X1549142Y304685D01*
X1548873Y304840D01*
X1547838D01*
Y301740D01*
X1549103D01*
X1549372Y301947D01*
X1549525Y302257D01*
X1549602Y302618D01*
X1549525Y302980D01*
X1549295Y303290D01*
X1549027Y303393D01*
X1547838D01*
G01X1551360Y304840D02*
X1552280D01*
G01X1551820D02*
Y301740D01*
G01X1551360D02*
X1552280D01*
G01X1554920D02*
X1554613Y301792D01*
X1554345Y301998D01*
X1554115Y302308D01*
X1553962Y302670D01*
X1553885Y303083D01*
Y303497D01*
X1553962Y303910D01*
X1554115Y304272D01*
X1554345Y304582D01*
X1554613Y304788D01*
X1554920Y304840D01*
X1555227Y304788D01*
X1555495Y304582D01*
X1555725Y304272D01*
X1555878Y303910D01*
X1555955Y303497D01*
Y303083D01*
X1555878Y302670D01*
X1555725Y302308D01*
X1555495Y301998D01*
X1555227Y301792D01*
X1554920Y301740D01*
G01X1557215Y302153D02*
X1557522Y301895D01*
X1557867Y301740D01*
X1558173D01*
X1558480Y301895D01*
X1558710Y302153D01*
X1558825Y302515D01*
X1558748Y302877D01*
X1558557Y303187D01*
X1558212Y303393D01*
X1557752Y303497D01*
X1557483Y303703D01*
X1557368Y304065D01*
X1557445Y304427D01*
X1557637Y304685D01*
X1557905Y304840D01*
X1558173D01*
X1558442Y304737D01*
X1558672Y304478D01*
G01X1563453Y301740D02*
Y304840D01*
X1564412D01*
X1564718Y304685D01*
X1564910Y304478D01*
X1564987Y304065D01*
X1564910Y303652D01*
X1564680Y303393D01*
X1564412Y303238D01*
X1563453D01*
G01X1564412D02*
X1564987Y301740D01*
G01X1568163Y304582D02*
X1567933Y304737D01*
X1567665Y304840D01*
X1567358D01*
X1567013Y304685D01*
X1566745Y304427D01*
X1566553Y304117D01*
X1566400Y303600D01*
X1566362Y303135D01*
X1566438Y302670D01*
X1566553Y302360D01*
X1566783Y302050D01*
X1567052Y301843D01*
X1567320Y301740D01*
X1567588D01*
X1567857Y301843D01*
X1568087Y301998D01*
X1568278Y302205D01*
G01X1569462Y304840D02*
X1570420Y301740D01*
X1571378Y304840D01*
G01X1572753Y301740D02*
Y304840D01*
X1573712D01*
X1574018Y304685D01*
X1574210Y304478D01*
X1574287Y304065D01*
X1574210Y303652D01*
X1573980Y303393D01*
X1573712Y303238D01*
X1572753D01*
G01X1573712D02*
X1574287Y301740D01*
G01X1544218Y306026D02*
X1544318D01*
G01X1542439Y312087D02*
Y308887D01*
G01X1547992Y319240D02*
Y322340D01*
X1549448D01*
G01X1548912Y320842D02*
X1547992D01*
G01X1551168Y321307D02*
Y319860D01*
X1551322Y319498D01*
X1551552Y319292D01*
X1551820Y319240D01*
X1552088Y319292D01*
X1552318Y319498D01*
X1552472Y319860D01*
G01Y319240D02*
Y321307D01*
G01X1554268Y319240D02*
Y321307D01*
G01Y320790D02*
X1554422Y321048D01*
X1554652Y321255D01*
X1554958Y321307D01*
X1555227Y321255D01*
X1555457Y321048D01*
X1555572Y320687D01*
Y319240D01*
G01X1558633Y321048D02*
X1558365Y321255D01*
X1558135Y321307D01*
X1557828Y321203D01*
X1557598Y320997D01*
X1557445Y320635D01*
X1557407Y320273D01*
X1557445Y319912D01*
X1557598Y319602D01*
X1557828Y319343D01*
X1558135Y319240D01*
X1558403Y319343D01*
X1558633Y319550D01*
G01X1561120Y322340D02*
Y319240D01*
G01X1560583Y321307D02*
X1561657D01*
G01X1564220D02*
Y319240D01*
G01Y322133D02*
X1564143Y322185D01*
Y322288D01*
X1564220Y322340D01*
X1564297Y322288D01*
Y322185D01*
X1564220Y322133D01*
G01X1567320Y319240D02*
X1567090Y319292D01*
X1566860Y319498D01*
X1566707Y319860D01*
X1566630Y320273D01*
X1566707Y320687D01*
X1566860Y321048D01*
X1567090Y321255D01*
X1567320Y321307D01*
X1567550Y321255D01*
X1567780Y321048D01*
X1567933Y320687D01*
X1567972Y320273D01*
X1567933Y319860D01*
X1567780Y319498D01*
X1567550Y319292D01*
X1567320Y319240D01*
G01X1569768D02*
Y321307D01*
G01Y320790D02*
X1569922Y321048D01*
X1570152Y321255D01*
X1570458Y321307D01*
X1570727Y321255D01*
X1570957Y321048D01*
X1571072Y320687D01*
Y319240D01*
G01X1555147Y587815D02*
Y594015D01*
G01X1558347Y587815D02*
X1555147D01*
G01X1545320Y582762D02*
X1542120D01*
G01X1545320Y588962D02*
Y582762D01*
G01X1542120Y588962D02*
X1545320D01*
G01X1542120Y582762D02*
Y588962D01*
G01X1550320Y582762D02*
X1547120D01*
G01X1550320Y588962D02*
Y582762D01*
G01X1547120Y588962D02*
X1550320D01*
G01X1547120Y582762D02*
Y588962D01*
G01X1551120D02*
X1554320D01*
G01X1551120Y582762D02*
Y588962D01*
G01X1554320Y582762D02*
X1551120D01*
G01X1554320Y588962D02*
Y582762D01*
G01X1555147Y594015D02*
X1558347D01*
G01X1556589Y611638D02*
X1558389Y613438D01*
G01Y609838D02*
X1556589Y611638D01*
G01X1558887Y627335D02*
X1555687D01*
G01Y633535D02*
X1558887D01*
G01X1555687Y627335D02*
Y633535D01*
G01X1547837Y635765D02*
Y632565D01*
G01X1544712Y636116D02*
Y642316D01*
G01X1547912Y636116D02*
X1544712D01*
G01X1547912Y642316D02*
Y636116D01*
G01X1548562D02*
Y642316D01*
G01X1551762Y636116D02*
X1548562D01*
G01X1551762Y642316D02*
Y636116D01*
G01X1554837Y635765D02*
Y632565D01*
G01X1548637Y635765D02*
X1554837D01*
G01X1548637Y632565D02*
Y635765D01*
G01X1554837Y632565D02*
X1548637D01*
G01X1544712Y642316D02*
X1547912D01*
G01X1548562D02*
X1551762D01*
G01X1543780Y861298D02*
Y860511D01*
G01D02*
Y854212D01*
G01D02*
Y853424D01*
G01Y869960D02*
Y860512D01*
G01D02*
Y854212D01*
G01D02*
Y853425D01*
G01Y1139645D02*
Y1138857D01*
G01Y1145944D02*
Y1139645D01*
G01D02*
Y1138857D01*
G01Y1145944D02*
Y1139645D01*
G01Y1146731D02*
Y1145944D01*
G01Y1146731D02*
Y1145944D01*
G01X1544900Y1349962D02*
X1618500D01*
Y1351362D01*
G01X1544900Y1349962D02*
Y1351362D01*
G01D02*
Y1361062D01*
G01X1546725Y1366435D02*
X1546410Y1365965D01*
X1546200Y1365417D01*
Y1364790D01*
X1546515Y1364085D01*
X1547040Y1363537D01*
X1547670Y1363145D01*
X1548720Y1362832D01*
X1549665Y1362754D01*
X1550610Y1362910D01*
X1551240Y1363145D01*
X1551870Y1363615D01*
X1552290Y1364164D01*
X1552500Y1364712D01*
Y1365260D01*
X1552290Y1365809D01*
X1551975Y1366279D01*
X1551555Y1366670D01*
G01X1552500Y1371952D02*
X1546200D01*
X1550715Y1369054D01*
Y1372970D01*
G01X1562000Y1362754D02*
X1555700Y1364712D01*
X1562000Y1366670D01*
G01X1559795Y1365965D02*
Y1363459D01*
G01X1562000Y1371952D02*
X1555700D01*
X1560215Y1369054D01*
Y1372970D01*
G01X1563300Y1361062D02*
X1554100D01*
G01X1544900Y1374562D02*
X1554100D01*
Y1361062D01*
X1544900D01*
Y1374562D01*
G01X1554100D02*
X1563300D01*
G01X1553753Y1555257D02*
Y1558357D01*
X1554750Y1555774D01*
X1555747Y1558357D01*
Y1555257D01*
G01X1558617D02*
X1557083D01*
Y1558357D01*
X1558617D01*
G01X1558003Y1556859D02*
X1557083D01*
G01X1560950Y1555257D02*
Y1558357D01*
X1560490Y1557737D01*
G01Y1555257D02*
X1561410D01*
G01X1563207Y1555722D02*
X1563437Y1555464D01*
X1563705Y1555309D01*
X1564050Y1555257D01*
X1564395Y1555360D01*
X1564663Y1555567D01*
X1564855Y1555929D01*
X1564893Y1556342D01*
X1564817Y1556755D01*
X1564625Y1557014D01*
X1564357Y1557220D01*
X1564088Y1557272D01*
X1563820Y1557220D01*
X1563475Y1557014D01*
X1563590Y1558357D01*
X1564625D01*
G01X1547745Y1624235D02*
X1548665Y1623452D01*
X1549700Y1622982D01*
X1550620D01*
X1551540Y1623452D01*
X1552230Y1624235D01*
X1552575Y1625332D01*
X1552345Y1626429D01*
X1551770Y1627369D01*
X1550735Y1627995D01*
X1549355Y1628309D01*
X1548550Y1628935D01*
X1548205Y1630032D01*
X1548435Y1631129D01*
X1549010Y1631912D01*
X1549815Y1632382D01*
X1550620D01*
X1551425Y1632069D01*
X1552115Y1631285D01*
G01X1555910Y1632382D02*
X1557520Y1622982D01*
X1559360Y1632382D01*
X1561200Y1622982D01*
X1562810Y1632382D01*
G01X1569480Y1627995D02*
X1569940Y1628465D01*
X1570285Y1629248D01*
X1570515Y1630345D01*
X1570285Y1631285D01*
X1569825Y1631912D01*
X1569020Y1632382D01*
X1565915D01*
Y1622982D01*
X1569710D01*
X1570515Y1623609D01*
X1570975Y1624549D01*
X1571205Y1625645D01*
X1570975Y1626742D01*
X1570285Y1627682D01*
X1569480Y1627995D01*
X1565915D01*
G01X1574310Y1619849D02*
X1581210D01*
G01X1587880Y1627995D02*
X1588340Y1628465D01*
X1588685Y1629248D01*
X1588915Y1630345D01*
X1588685Y1631285D01*
X1588225Y1631912D01*
X1587420Y1632382D01*
X1584315D01*
Y1622982D01*
X1588110D01*
X1588915Y1623609D01*
X1589375Y1624549D01*
X1589605Y1625645D01*
X1589375Y1626742D01*
X1588685Y1627682D01*
X1587880Y1627995D01*
X1584315D01*
G01X1558475Y1641309D02*
X1558667Y1640999D01*
X1558897Y1640792D01*
X1559165Y1640689D01*
X1559472Y1640792D01*
X1559702Y1640999D01*
X1559932Y1641309D01*
X1560009Y1641722D01*
Y1643789D01*
G01X1562342Y1640689D02*
Y1643789D01*
X1561882Y1643169D01*
G01Y1640689D02*
X1562802D01*
G01X1565442Y1643789D02*
X1565135Y1643686D01*
X1564905Y1643427D01*
X1564752Y1643117D01*
X1564637Y1642704D01*
X1564599Y1642239D01*
X1564637Y1641774D01*
X1564752Y1641361D01*
X1564905Y1641051D01*
X1565135Y1640792D01*
X1565442Y1640689D01*
X1565749Y1640792D01*
X1565979Y1641051D01*
X1566132Y1641361D01*
X1566247Y1641774D01*
X1566285Y1642239D01*
X1566247Y1642704D01*
X1566132Y1643117D01*
X1565979Y1643427D01*
X1565749Y1643686D01*
X1565442Y1643789D01*
G01X1567699Y1641154D02*
X1567929Y1640896D01*
X1568197Y1640741D01*
X1568542Y1640689D01*
X1568887Y1640792D01*
X1569155Y1640999D01*
X1569347Y1641361D01*
X1569385Y1641774D01*
X1569309Y1642187D01*
X1569117Y1642446D01*
X1568849Y1642652D01*
X1568580Y1642704D01*
X1568312Y1642652D01*
X1567967Y1642446D01*
X1568082Y1643789D01*
X1569117D01*
G01X1553150Y1646023D02*
Y1781456D01*
G01X1643307Y1646023D02*
X1553150D01*
G01X1558394Y1653682D02*
X1558662Y1653734D01*
X1558969Y1653889D01*
X1559161Y1654147D01*
X1559237Y1654509D01*
X1559161Y1654870D01*
X1558931Y1655180D01*
X1558586Y1655335D01*
X1558202D01*
X1557972Y1655439D01*
X1557781Y1655697D01*
X1557704Y1656059D01*
X1557819Y1656420D01*
X1558087Y1656679D01*
X1558394Y1656782D01*
X1558701Y1656679D01*
X1558969Y1656420D01*
X1559084Y1656059D01*
X1559007Y1655697D01*
X1558816Y1655439D01*
X1558586Y1655335D01*
X1558202D01*
X1557857Y1655180D01*
X1557627Y1654870D01*
X1557551Y1654509D01*
X1557627Y1654147D01*
X1557819Y1653889D01*
X1558126Y1653734D01*
X1558394Y1653682D01*
G01X1550443D02*
X1550520Y1654354D01*
X1550635Y1654922D01*
X1550788Y1655439D01*
X1550980Y1656007D01*
X1551287Y1656782D01*
X1549753D01*
G01X1553150Y1781456D02*
X1643307D01*
G01X1573411Y51096D02*
X1578134D01*
G01X1566677D02*
X1570698D01*
G01X1558828D02*
X1563901D01*
G01X1563753Y122544D02*
X1563523Y122699D01*
X1563255Y122802D01*
X1562948D01*
X1562603Y122647D01*
X1562335Y122389D01*
X1562143Y122079D01*
X1561990Y121562D01*
X1561952Y121097D01*
X1562028Y120632D01*
X1562143Y120322D01*
X1562373Y120012D01*
X1562642Y119805D01*
X1562910Y119702D01*
X1563178D01*
X1563447Y119805D01*
X1563677Y119960D01*
X1563868Y120167D01*
G01X1565243Y122802D02*
Y119702D01*
X1566777D01*
G01X1569877D02*
X1568343D01*
Y122802D01*
X1569877D01*
G01X1569263Y121304D02*
X1568343D01*
G01X1571252Y119702D02*
X1572210Y122802D01*
X1573168Y119702D01*
G01X1572823Y120787D02*
X1571597D01*
G01X1574543Y119702D02*
Y122802D01*
X1575502D01*
X1575808Y122647D01*
X1576000Y122440D01*
X1576077Y122027D01*
X1576000Y121614D01*
X1575770Y121355D01*
X1575502Y121200D01*
X1574543D01*
G01X1575502D02*
X1576077Y119702D01*
G01X1582353Y122544D02*
X1582123Y122699D01*
X1581855Y122802D01*
X1581548D01*
X1581203Y122647D01*
X1580935Y122389D01*
X1580743Y122079D01*
X1580590Y121562D01*
X1580552Y121097D01*
X1580628Y120632D01*
X1580743Y120322D01*
X1580973Y120012D01*
X1581242Y119805D01*
X1581510Y119702D01*
X1581778D01*
X1582047Y119805D01*
X1582277Y119960D01*
X1582468Y120167D01*
G01X1583613Y119702D02*
Y122802D01*
X1584610Y120219D01*
X1585607Y122802D01*
Y119702D01*
G01X1587710D02*
X1587403Y119754D01*
X1587135Y119960D01*
X1586905Y120270D01*
X1586752Y120632D01*
X1586675Y121045D01*
Y121459D01*
X1586752Y121872D01*
X1586905Y122234D01*
X1587135Y122544D01*
X1587403Y122750D01*
X1587710Y122802D01*
X1588017Y122750D01*
X1588285Y122544D01*
X1588515Y122234D01*
X1588668Y121872D01*
X1588745Y121459D01*
Y121045D01*
X1588668Y120632D01*
X1588515Y120270D01*
X1588285Y119960D01*
X1588017Y119754D01*
X1587710Y119702D01*
G01X1590005Y120115D02*
X1590312Y119857D01*
X1590657Y119702D01*
X1590963D01*
X1591270Y119857D01*
X1591500Y120115D01*
X1591615Y120477D01*
X1591538Y120839D01*
X1591347Y121149D01*
X1591002Y121355D01*
X1590542Y121459D01*
X1590273Y121665D01*
X1590158Y122027D01*
X1590235Y122389D01*
X1590427Y122647D01*
X1590695Y122802D01*
X1590963D01*
X1591232Y122699D01*
X1591462Y122440D01*
G01X1597317Y121355D02*
X1597470Y121510D01*
X1597585Y121769D01*
X1597662Y122130D01*
X1597585Y122440D01*
X1597432Y122647D01*
X1597163Y122802D01*
X1596128D01*
Y119702D01*
X1597393D01*
X1597662Y119909D01*
X1597815Y120219D01*
X1597892Y120580D01*
X1597815Y120942D01*
X1597585Y121252D01*
X1597317Y121355D01*
X1596128D01*
G01X1599267Y122802D02*
Y120580D01*
X1599420Y120115D01*
X1599727Y119805D01*
X1600110Y119702D01*
X1600493Y119805D01*
X1600800Y120115D01*
X1600953Y120580D01*
Y122802D01*
G01X1603210D02*
Y119702D01*
G01X1602328Y122802D02*
X1604092D01*
G01X1606310D02*
Y119702D01*
G01X1605428Y122802D02*
X1607192D01*
G01X1609410Y119702D02*
X1609103Y119754D01*
X1608835Y119960D01*
X1608605Y120270D01*
X1608452Y120632D01*
X1608375Y121045D01*
Y121459D01*
X1608452Y121872D01*
X1608605Y122234D01*
X1608835Y122544D01*
X1609103Y122750D01*
X1609410Y122802D01*
X1609717Y122750D01*
X1609985Y122544D01*
X1610215Y122234D01*
X1610368Y121872D01*
X1610445Y121459D01*
Y121045D01*
X1610368Y120632D01*
X1610215Y120270D01*
X1609985Y119960D01*
X1609717Y119754D01*
X1609410Y119702D01*
G01X1611628D02*
Y122802D01*
X1613392Y119702D01*
Y122802D01*
G01X1561213Y174146D02*
X1562823Y177246D01*
G01X1561213D02*
X1562823Y174146D01*
G01X1564275D02*
Y177246D01*
X1565041D01*
X1565348Y177091D01*
X1565578Y176884D01*
X1565770Y176574D01*
X1565923Y176213D01*
X1565961Y175696D01*
X1565923Y175179D01*
X1565770Y174818D01*
X1565578Y174508D01*
X1565348Y174301D01*
X1565041Y174146D01*
X1564275D01*
G01X1567451D02*
Y177246D01*
X1568371D01*
X1568678Y177091D01*
X1568908Y176729D01*
X1568985Y176316D01*
X1568908Y175903D01*
X1568716Y175593D01*
X1568371Y175438D01*
X1567451D01*
G01X1575261Y176988D02*
X1575031Y177143D01*
X1574763Y177246D01*
X1574456D01*
X1574111Y177091D01*
X1573843Y176833D01*
X1573651Y176523D01*
X1573498Y176006D01*
X1573460Y175541D01*
X1573536Y175076D01*
X1573651Y174766D01*
X1573881Y174456D01*
X1574150Y174249D01*
X1574418Y174146D01*
X1574686D01*
X1574955Y174249D01*
X1575185Y174404D01*
X1575376Y174611D01*
G01X1577518Y174146D02*
X1577211Y174198D01*
X1576943Y174404D01*
X1576713Y174714D01*
X1576560Y175076D01*
X1576483Y175489D01*
Y175903D01*
X1576560Y176316D01*
X1576713Y176678D01*
X1576943Y176988D01*
X1577211Y177194D01*
X1577518Y177246D01*
X1577825Y177194D01*
X1578093Y176988D01*
X1578323Y176678D01*
X1578476Y176316D01*
X1578553Y175903D01*
Y175489D01*
X1578476Y175076D01*
X1578323Y174714D01*
X1578093Y174404D01*
X1577825Y174198D01*
X1577518Y174146D01*
G01X1579736D02*
Y177246D01*
X1581500Y174146D01*
Y177246D01*
G01X1582836Y174146D02*
Y177246D01*
X1584600Y174146D01*
Y177246D01*
G01X1568976Y182460D02*
X1567724D01*
G01X1568976Y194809D02*
Y182460D01*
G01X1572677Y189756D02*
X1572869Y189446D01*
X1573099Y189239D01*
X1573367Y189136D01*
X1573674Y189239D01*
X1573904Y189446D01*
X1574134Y189756D01*
X1574211Y190169D01*
Y192236D01*
G01X1577004Y189136D02*
Y192236D01*
X1575586Y190014D01*
X1577502D01*
G01X1578916Y191719D02*
X1579146Y192029D01*
X1579414Y192184D01*
X1579721Y192236D01*
X1580104Y192133D01*
X1580372Y191874D01*
X1580449Y191564D01*
X1580411Y191254D01*
X1580257Y190996D01*
X1579491Y190479D01*
X1579146Y190118D01*
X1578916Y189601D01*
X1578839Y189136D01*
X1580449D01*
G01X1572768Y198575D02*
X1573036Y198936D01*
X1573266Y199143D01*
X1573573Y199246D01*
X1573841Y199143D01*
X1574033Y198936D01*
X1574186Y198626D01*
X1574224Y198265D01*
X1574186Y197955D01*
X1574033Y197645D01*
X1573803Y197386D01*
X1573534Y197283D01*
X1573228Y197386D01*
X1572959Y197696D01*
X1572806Y198161D01*
X1572768Y198678D01*
X1572844Y199350D01*
X1572959Y199711D01*
X1573151Y200073D01*
X1573419Y200331D01*
X1573688Y200383D01*
X1573956Y200280D01*
X1574148Y200021D01*
G01X1576596Y200383D02*
X1576289Y200280D01*
X1576059Y200021D01*
X1575906Y199711D01*
X1575791Y199298D01*
X1575753Y198833D01*
X1575791Y198368D01*
X1575906Y197955D01*
X1576059Y197645D01*
X1576289Y197386D01*
X1576596Y197283D01*
X1576903Y197386D01*
X1577133Y197645D01*
X1577286Y197955D01*
X1577401Y198368D01*
X1577439Y198833D01*
X1577401Y199298D01*
X1577286Y199711D01*
X1577133Y200021D01*
X1576903Y200280D01*
X1576596Y200383D01*
G01X1572882Y255816D02*
X1573112Y256126D01*
X1573380Y256281D01*
X1573687Y256333D01*
X1574070Y256230D01*
X1574338Y255971D01*
X1574415Y255661D01*
X1574377Y255351D01*
X1574223Y255093D01*
X1573457Y254576D01*
X1573112Y254215D01*
X1572882Y253698D01*
X1572805Y253233D01*
X1574415D01*
G01X1567724Y266358D02*
X1568976D01*
G01D02*
Y254009D01*
G01X1558347Y594015D02*
Y587815D01*
G01X1562394Y579617D02*
Y585817D01*
G01D02*
X1565594D01*
G01D02*
Y579617D01*
G01D02*
X1562394D01*
G01X1566394D02*
Y585817D01*
G01D02*
X1569594D01*
G01D02*
Y579617D01*
G01D02*
X1566394D01*
G01X1587827Y595825D02*
G03I-10827J0D01*
G01X1560777Y610912D02*
Y608690D01*
X1560930Y608225D01*
X1561237Y607915D01*
X1561620Y607812D01*
X1562003Y607915D01*
X1562310Y608225D01*
X1562463Y608690D01*
Y610912D01*
G01X1563877Y608432D02*
X1564107Y608070D01*
X1564413Y607864D01*
X1564758Y607812D01*
X1565065Y607864D01*
X1565372Y608122D01*
X1565563Y608432D01*
X1565602Y608742D01*
X1565525Y609104D01*
X1565257Y609362D01*
X1564988Y609465D01*
X1564643D01*
G01X1564988D02*
X1565218Y609620D01*
X1565410Y609879D01*
X1565487Y610189D01*
X1565410Y610499D01*
X1565218Y610757D01*
X1564873Y610912D01*
X1564528Y610860D01*
X1564183Y610654D01*
G01X1567820Y610912D02*
X1567513Y610809D01*
X1567283Y610550D01*
X1567130Y610240D01*
X1567015Y609827D01*
X1566977Y609362D01*
X1567015Y608897D01*
X1567130Y608484D01*
X1567283Y608174D01*
X1567513Y607915D01*
X1567820Y607812D01*
X1568127Y607915D01*
X1568357Y608174D01*
X1568510Y608484D01*
X1568625Y608897D01*
X1568663Y609362D01*
X1568625Y609827D01*
X1568510Y610240D01*
X1568357Y610550D01*
X1568127Y610809D01*
X1567820Y610912D01*
G01X1558389Y606038D02*
Y609838D01*
G01X1587827Y595825D02*
X1566173D01*
G01X1558389Y613438D02*
Y617238D01*
G01X1587827Y620325D02*
G03I-10827J0D01*
G01D02*
X1566173D01*
G01X1558887Y633535D02*
Y627335D01*
G01X1587827Y644825D02*
G03I-10827J0D01*
G01X1567679Y657016D02*
Y653816D01*
G01D02*
X1561479D01*
G01D02*
Y657016D01*
G01X1565392Y649439D02*
X1559192D01*
G01D02*
Y652639D01*
G01D02*
X1565392D01*
G01D02*
Y649439D01*
G01X1587827Y644825D02*
X1566173D01*
G01X1561479Y661016D02*
X1567679D01*
G01D02*
Y657816D01*
G01D02*
X1561479D01*
G01D02*
Y661016D01*
G01Y657016D02*
X1567679D01*
G01X1587827Y669225D02*
G03I-10827J0D01*
G01D02*
X1566173D01*
G01X1587827Y693725D02*
G03I-10827J0D01*
G01D02*
X1566173D01*
G01X1587827Y718225D02*
G03I-10827J0D01*
G01D02*
X1566173D01*
G01X1573172Y739077D02*
Y731825D01*
G01Y731647D02*
X1589268D01*
G01X1564356Y734091D02*
Y737291D01*
G01X1570556Y734091D02*
X1564356D01*
G01X1570556Y737291D02*
Y734091D01*
G01X1564356Y737291D02*
X1570556D01*
G01X1564356Y730565D02*
Y733765D01*
G01X1570556Y730565D02*
X1564356D01*
G01X1570556Y733765D02*
Y730565D01*
G01X1564356Y733765D02*
X1570556D01*
G01X1589268Y748077D02*
X1573172D01*
G01D02*
Y740825D01*
G01Y740647D02*
X1589268D01*
G01Y739077D02*
X1573172D01*
G01X1569345Y1008362D02*
Y1011462D01*
G01X1570955D02*
Y1008362D01*
G01Y1009912D02*
X1569345D01*
G01X1573250Y1008362D02*
Y1011462D01*
X1572790Y1010842D01*
G01Y1008362D02*
X1573710D01*
G01X1575698Y1008724D02*
X1575967Y1008465D01*
X1576273Y1008362D01*
X1576580Y1008465D01*
X1576848Y1008775D01*
X1577040Y1009240D01*
X1577117Y1009705D01*
Y1010274D01*
X1577040Y1010739D01*
X1576848Y1011152D01*
X1576618Y1011359D01*
X1576350Y1011462D01*
X1576043Y1011359D01*
X1575813Y1011152D01*
X1575660Y1010842D01*
X1575583Y1010429D01*
X1575660Y1010067D01*
X1575852Y1009705D01*
X1576082Y1009499D01*
X1576350Y1009447D01*
X1576657Y1009550D01*
X1576887Y1009809D01*
X1577117Y1010274D01*
G01X1570627Y1352262D02*
Y1358562D01*
X1572193D01*
X1572820Y1358247D01*
X1573290Y1357827D01*
X1573682Y1357197D01*
X1573995Y1356462D01*
X1574073Y1355412D01*
X1573995Y1354362D01*
X1573682Y1353627D01*
X1573290Y1352997D01*
X1572820Y1352577D01*
X1572193Y1352262D01*
X1570627D01*
G01X1577710Y1358562D02*
X1579590D01*
G01X1578650D02*
Y1352262D01*
G01X1577710D02*
X1579590D01*
G01X1582913D02*
Y1358562D01*
X1584950Y1353312D01*
X1586987Y1358562D01*
Y1352262D01*
G01X1589213D02*
Y1358562D01*
X1591250Y1353312D01*
X1593287Y1358562D01*
Y1352262D01*
G01X1565225Y1366435D02*
X1564910Y1365965D01*
X1564700Y1365417D01*
Y1364790D01*
X1565015Y1364085D01*
X1565540Y1363537D01*
X1566170Y1363145D01*
X1567220Y1362832D01*
X1568165Y1362754D01*
X1569110Y1362910D01*
X1569740Y1363145D01*
X1570370Y1363615D01*
X1570790Y1364164D01*
X1571000Y1364712D01*
Y1365260D01*
X1570790Y1365809D01*
X1570475Y1366279D01*
X1570055Y1366670D01*
G01Y1369289D02*
X1570580Y1369759D01*
X1570895Y1370307D01*
X1571000Y1371012D01*
X1570790Y1371717D01*
X1570370Y1372265D01*
X1569635Y1372657D01*
X1568795Y1372735D01*
X1567955Y1372579D01*
X1567430Y1372187D01*
X1567010Y1371639D01*
X1566905Y1371090D01*
X1567010Y1370542D01*
X1567430Y1369837D01*
X1564700Y1370072D01*
Y1372187D01*
G01X1580000Y1362754D02*
X1573700Y1364712D01*
X1580000Y1366670D01*
G01X1577795Y1365965D02*
Y1363459D01*
G01X1579055Y1369289D02*
X1579580Y1369759D01*
X1579895Y1370307D01*
X1580000Y1371012D01*
X1579790Y1371717D01*
X1579370Y1372265D01*
X1578635Y1372657D01*
X1577795Y1372735D01*
X1576955Y1372579D01*
X1576430Y1372187D01*
X1576010Y1371639D01*
X1575905Y1371090D01*
X1576010Y1370542D01*
X1576430Y1369837D01*
X1573700Y1370072D01*
Y1372187D01*
G01X1572500Y1361062D02*
X1563300D01*
G01Y1374562D02*
Y1361062D01*
G01X1581700D02*
X1572500D01*
G01Y1374562D02*
Y1361062D01*
G01X1563300Y1374562D02*
X1572500D01*
G01D02*
X1581700D01*
G01X1571565Y1653152D02*
Y1656252D01*
X1571105Y1655632D01*
G01Y1653152D02*
X1572025D01*
G01X1564961Y1769645D02*
Y1657834D01*
G01D02*
X1631496D01*
G01X1564567D02*
Y1769645D01*
G01X1561392Y1671465D02*
Y1674565D01*
X1563156Y1671465D01*
Y1674565D01*
G01X1561277Y1676189D02*
Y1679289D01*
X1562274Y1676706D01*
X1563271Y1679289D01*
Y1676189D01*
G01X1561507Y1684013D02*
Y1680913D01*
X1563041D01*
G01X1561814Y1698187D02*
X1562734D01*
G01X1562274D02*
Y1695087D01*
G01X1561814D02*
X1562734D01*
G01X1561431Y1685638D02*
Y1688738D01*
G01X1562887D02*
X1561431Y1686826D01*
G01X1563117Y1685638D02*
X1562082Y1687705D01*
G01X1561507Y1690982D02*
X1561699Y1690672D01*
X1561929Y1690465D01*
X1562197Y1690362D01*
X1562504Y1690465D01*
X1562734Y1690672D01*
X1562964Y1690982D01*
X1563041Y1691395D01*
Y1693462D01*
G01X1561469Y1699811D02*
Y1702911D01*
G01X1563079D02*
Y1699811D01*
G01Y1701361D02*
X1561469D01*
G01X1562504Y1706086D02*
X1563271D01*
Y1705156D01*
X1563041Y1704846D01*
X1562772Y1704639D01*
X1562389Y1704536D01*
X1562006Y1704639D01*
X1561737Y1704846D01*
X1561507Y1705156D01*
X1561354Y1705518D01*
X1561277Y1705931D01*
Y1706293D01*
X1561354Y1706603D01*
X1561507Y1706964D01*
X1561737Y1707274D01*
X1561967Y1707481D01*
X1562274Y1707636D01*
X1562542D01*
X1562849Y1707533D01*
X1563079Y1707326D01*
G01X1561546Y1709260D02*
Y1712360D01*
X1563002D01*
G01X1562466Y1710862D02*
X1561546D01*
G01X1563041Y1713984D02*
X1561507D01*
Y1717084D01*
X1563041D01*
G01X1562427Y1715586D02*
X1561507D01*
G01X1563117Y1726275D02*
X1562887Y1726430D01*
X1562619Y1726533D01*
X1562312D01*
X1561967Y1726378D01*
X1561699Y1726120D01*
X1561507Y1725810D01*
X1561354Y1725293D01*
X1561316Y1724828D01*
X1561392Y1724363D01*
X1561507Y1724053D01*
X1561737Y1723743D01*
X1562006Y1723536D01*
X1562274Y1723433D01*
X1562542D01*
X1562811Y1723536D01*
X1563041Y1723691D01*
X1563232Y1723898D01*
G01X1562581Y1729811D02*
X1562734Y1729966D01*
X1562849Y1730225D01*
X1562926Y1730586D01*
X1562849Y1730896D01*
X1562696Y1731103D01*
X1562427Y1731258D01*
X1561392D01*
Y1728158D01*
X1562657D01*
X1562926Y1728365D01*
X1563079Y1728675D01*
X1563156Y1729036D01*
X1563079Y1729398D01*
X1562849Y1729708D01*
X1562581Y1729811D01*
X1561392D01*
G01X1561431Y1718709D02*
Y1721809D01*
X1562197D01*
X1562504Y1721654D01*
X1562734Y1721447D01*
X1562926Y1721137D01*
X1563079Y1720776D01*
X1563117Y1720259D01*
X1563079Y1719742D01*
X1562926Y1719381D01*
X1562734Y1719071D01*
X1562504Y1718864D01*
X1562197Y1718709D01*
X1561431D01*
G01X1571982Y1739812D02*
X1569982Y1737812D01*
G01D02*
X1573982D01*
G01D02*
X1571982Y1739812D01*
G01D02*
Y1736412D01*
G01D02*
X1576982D01*
G01X1564961Y1740118D02*
X1631496D01*
G01Y1769645D02*
X1564961D01*
G01X1588058Y51096D02*
X1592175D01*
G01X1580495D02*
X1585154D01*
G01X1582145Y126505D02*
X1582452Y126247D01*
X1582797Y126092D01*
X1583103D01*
X1583410Y126247D01*
X1583640Y126505D01*
X1583755Y126867D01*
X1583678Y127229D01*
X1583487Y127539D01*
X1583142Y127745D01*
X1582682Y127849D01*
X1582413Y128055D01*
X1582298Y128417D01*
X1582375Y128779D01*
X1582567Y129037D01*
X1582835Y129192D01*
X1583103D01*
X1583372Y129089D01*
X1583602Y128830D01*
G01X1584900Y129192D02*
X1585437Y126092D01*
X1586050Y129192D01*
X1586663Y126092D01*
X1587200Y129192D01*
G01X1588307Y126557D02*
X1588537Y126299D01*
X1588805Y126144D01*
X1589150Y126092D01*
X1589495Y126195D01*
X1589763Y126402D01*
X1589955Y126764D01*
X1589993Y127177D01*
X1589917Y127590D01*
X1589725Y127849D01*
X1589457Y128055D01*
X1589188Y128107D01*
X1588920Y128055D01*
X1588575Y127849D01*
X1588690Y129192D01*
X1589725D01*
G01X1587400Y200962D02*
X1593600D01*
G01X1587400Y197762D02*
Y200962D01*
G01X1593600Y197762D02*
X1587400D01*
G01X1587478Y217926D02*
Y221126D01*
G01X1593678Y217926D02*
X1587478D01*
G01Y221126D02*
X1593678D01*
G01X1587478Y225926D02*
Y229126D01*
G01X1593678Y225926D02*
X1587478D01*
G01Y229126D02*
X1593678D01*
G01X1587239Y246408D02*
Y249608D01*
G01X1593439Y246408D02*
X1587239D01*
G01Y249608D02*
X1593439D01*
G01X1587259Y242290D02*
Y245490D01*
G01X1593459Y242290D02*
X1587259D01*
G01Y245490D02*
X1593459D01*
G01X1587219Y250526D02*
Y253726D01*
G01X1593419Y250526D02*
X1587219D01*
G01Y253726D02*
X1593419D01*
G01X1587239Y257844D02*
X1593439D01*
G01X1587239Y254644D02*
Y257844D01*
G01X1593439Y254644D02*
X1587239D01*
G01X1586090Y704934D02*
Y708034D01*
X1587010D01*
X1587317Y707879D01*
X1587547Y707517D01*
X1587624Y707104D01*
X1587547Y706691D01*
X1587355Y706381D01*
X1587010Y706226D01*
X1586090D01*
G01X1589190Y708034D02*
Y704934D01*
X1590724D01*
G01X1592214Y705399D02*
X1592444Y705141D01*
X1592712Y704986D01*
X1593057Y704934D01*
X1593402Y705037D01*
X1593670Y705244D01*
X1593862Y705606D01*
X1593900Y706019D01*
X1593824Y706432D01*
X1593632Y706691D01*
X1593364Y706897D01*
X1593095Y706949D01*
X1592827Y706897D01*
X1592482Y706691D01*
X1592597Y708034D01*
X1593632D01*
G01X1589268Y731647D02*
Y739077D01*
G01Y740647D02*
Y748077D01*
G01X1583725Y1366435D02*
X1583410Y1365965D01*
X1583200Y1365417D01*
Y1364790D01*
X1583515Y1364085D01*
X1584040Y1363537D01*
X1584670Y1363145D01*
X1585720Y1362832D01*
X1586665Y1362754D01*
X1587610Y1362910D01*
X1588240Y1363145D01*
X1588870Y1363615D01*
X1589290Y1364164D01*
X1589500Y1364712D01*
Y1365260D01*
X1589290Y1365809D01*
X1588975Y1366279D01*
X1588555Y1366670D01*
G01X1586875Y1369524D02*
X1586140Y1370072D01*
X1585720Y1370542D01*
X1585510Y1371169D01*
X1585720Y1371717D01*
X1586140Y1372109D01*
X1586770Y1372422D01*
X1587505Y1372500D01*
X1588135Y1372422D01*
X1588765Y1372109D01*
X1589290Y1371639D01*
X1589500Y1371090D01*
X1589290Y1370464D01*
X1588660Y1369915D01*
X1587715Y1369602D01*
X1586665Y1369524D01*
X1585300Y1369680D01*
X1584565Y1369915D01*
X1583830Y1370307D01*
X1583305Y1370855D01*
X1583200Y1371404D01*
X1583410Y1371952D01*
X1583935Y1372344D01*
G01X1590900Y1361062D02*
X1581700D01*
G01Y1374562D02*
Y1361062D01*
G01Y1374562D02*
X1590900D01*
G01X1576378Y1666470D02*
Y1646023D01*
G01X1586470Y1653772D02*
X1586700Y1653410D01*
X1587006Y1653204D01*
X1587351Y1653152D01*
X1587658Y1653204D01*
X1587965Y1653462D01*
X1588156Y1653772D01*
X1588195Y1654082D01*
X1588118Y1654444D01*
X1587850Y1654702D01*
X1587581Y1654805D01*
X1587236D01*
G01X1587581D02*
X1587811Y1654960D01*
X1588003Y1655219D01*
X1588080Y1655529D01*
X1588003Y1655839D01*
X1587811Y1656097D01*
X1587466Y1656252D01*
X1587121Y1656200D01*
X1586776Y1655994D01*
G01X1578711Y1655735D02*
X1578941Y1656045D01*
X1579209Y1656200D01*
X1579516Y1656252D01*
X1579899Y1656149D01*
X1580167Y1655890D01*
X1580244Y1655580D01*
X1580206Y1655270D01*
X1580052Y1655012D01*
X1579286Y1654495D01*
X1578941Y1654134D01*
X1578711Y1653617D01*
X1578634Y1653152D01*
X1580244D01*
G01X1580065Y1736629D02*
X1578999D01*
Y1739129D01*
X1580065D01*
G01X1579639Y1737921D02*
X1578999D01*
G01X1581145Y1736629D02*
Y1739129D01*
X1581679D01*
X1581892Y1739004D01*
X1582052Y1738837D01*
X1582185Y1738587D01*
X1582292Y1738296D01*
X1582319Y1737879D01*
X1582292Y1737462D01*
X1582185Y1737171D01*
X1582052Y1736921D01*
X1581892Y1736754D01*
X1581679Y1736629D01*
X1581145D01*
G01X1584092Y1737879D02*
X1584625D01*
Y1737129D01*
X1584465Y1736879D01*
X1584279Y1736712D01*
X1584012Y1736629D01*
X1583745Y1736712D01*
X1583559Y1736879D01*
X1583399Y1737129D01*
X1583292Y1737421D01*
X1583239Y1737754D01*
Y1738046D01*
X1583292Y1738296D01*
X1583399Y1738587D01*
X1583559Y1738837D01*
X1583719Y1739004D01*
X1583932Y1739129D01*
X1584119D01*
X1584332Y1739046D01*
X1584492Y1738879D01*
G01X1586665Y1736629D02*
X1585599D01*
Y1739129D01*
X1586665D01*
G01X1586239Y1737921D02*
X1585599D01*
G01X1590532Y1736629D02*
X1590319Y1736671D01*
X1590132Y1736837D01*
X1589972Y1737087D01*
X1589865Y1737379D01*
X1589812Y1737712D01*
Y1738046D01*
X1589865Y1738379D01*
X1589972Y1738671D01*
X1590132Y1738921D01*
X1590319Y1739087D01*
X1590532Y1739129D01*
X1590745Y1739087D01*
X1590932Y1738921D01*
X1591092Y1738671D01*
X1591199Y1738379D01*
X1591252Y1738046D01*
Y1737712D01*
X1591199Y1737379D01*
X1591092Y1737087D01*
X1590932Y1736837D01*
X1590745Y1736671D01*
X1590532Y1736629D01*
G01X1592225D02*
Y1739129D01*
X1593239D01*
G01X1592865Y1737921D02*
X1592225D01*
G01X1596545Y1736629D02*
Y1739129D01*
X1597079D01*
X1597292Y1739004D01*
X1597452Y1738837D01*
X1597585Y1738587D01*
X1597692Y1738296D01*
X1597719Y1737879D01*
X1597692Y1737462D01*
X1597585Y1737171D01*
X1597452Y1736921D01*
X1597292Y1736754D01*
X1597079Y1736629D01*
X1596545D01*
G01X1598665D02*
X1599332Y1739129D01*
X1599999Y1736629D01*
G01X1599759Y1737504D02*
X1598905D01*
G01X1600945Y1739129D02*
Y1737337D01*
X1601052Y1736962D01*
X1601265Y1736712D01*
X1601532Y1736629D01*
X1601799Y1736712D01*
X1602012Y1736962D01*
X1602119Y1737337D01*
Y1739129D01*
G01X1603892Y1737879D02*
X1604425D01*
Y1737129D01*
X1604265Y1736879D01*
X1604079Y1736712D01*
X1603812Y1736629D01*
X1603545Y1736712D01*
X1603359Y1736879D01*
X1603199Y1737129D01*
X1603092Y1737421D01*
X1603039Y1737754D01*
Y1738046D01*
X1603092Y1738296D01*
X1603199Y1738587D01*
X1603359Y1738837D01*
X1603519Y1739004D01*
X1603732Y1739129D01*
X1603919D01*
X1604132Y1739046D01*
X1604292Y1738879D01*
G01X1605372Y1736629D02*
Y1739129D01*
G01X1606492D02*
Y1736629D01*
G01Y1737879D02*
X1605372D01*
G01X1608132Y1739129D02*
Y1736629D01*
G01X1607519Y1739129D02*
X1608745D01*
G01X1610865Y1736629D02*
X1609799D01*
Y1739129D01*
X1610865D01*
G01X1610439Y1737921D02*
X1609799D01*
G01X1611999Y1736629D02*
Y1739129D01*
X1612665D01*
X1612879Y1739004D01*
X1613012Y1738837D01*
X1613065Y1738504D01*
X1613012Y1738171D01*
X1612852Y1737962D01*
X1612665Y1737837D01*
X1611999D01*
G01X1612665D02*
X1613065Y1736629D01*
G01X1617519Y1738921D02*
X1617359Y1739046D01*
X1617172Y1739129D01*
X1616959D01*
X1616719Y1739004D01*
X1616532Y1738796D01*
X1616399Y1738546D01*
X1616292Y1738129D01*
X1616265Y1737754D01*
X1616319Y1737379D01*
X1616399Y1737129D01*
X1616559Y1736879D01*
X1616745Y1736712D01*
X1616932Y1736629D01*
X1617119D01*
X1617305Y1736712D01*
X1617465Y1736837D01*
X1617599Y1737004D01*
G01X1618465Y1736629D02*
X1619132Y1739129D01*
X1619799Y1736629D01*
G01X1619559Y1737504D02*
X1618705D01*
G01X1620799Y1736629D02*
Y1739129D01*
X1621465D01*
X1621679Y1739004D01*
X1621812Y1738837D01*
X1621865Y1738504D01*
X1621812Y1738171D01*
X1621652Y1737962D01*
X1621465Y1737837D01*
X1620799D01*
G01X1621465D02*
X1621865Y1736629D01*
G01X1622945D02*
Y1739129D01*
X1623479D01*
X1623692Y1739004D01*
X1623852Y1738837D01*
X1623985Y1738587D01*
X1624092Y1738296D01*
X1624119Y1737879D01*
X1624092Y1737462D01*
X1623985Y1737171D01*
X1623852Y1736921D01*
X1623692Y1736754D01*
X1623479Y1736629D01*
X1622945D01*
G01X1576982Y1736412D02*
X1577882Y1737312D01*
G01X1576378Y1781456D02*
Y1742790D01*
G01X1604269Y51096D02*
X1627852D01*
G01X1596195D02*
X1600664D01*
G01X1622131Y43779D02*
X1605391D01*
G01X1598908Y131450D02*
X1610308D01*
G01X1592403D02*
X1592608D01*
G01X1592403Y155860D02*
Y131450D01*
G01X1611498Y143655D02*
G03I-6890J0D01*
G01X1610308Y155860D02*
X1598908D01*
G01X1592608D02*
X1592403D01*
G01X1593600Y200962D02*
Y197762D01*
G01X1593678Y221126D02*
Y217926D01*
G01Y229126D02*
Y225926D01*
G01X1593439Y249608D02*
Y246408D01*
G01X1593459Y245490D02*
Y242290D01*
G01X1593419Y253726D02*
Y250526D01*
G01X1593439Y257844D02*
Y254644D01*
G01X1593515Y278753D02*
X1593822Y278495D01*
X1594167Y278340D01*
X1594473D01*
X1594780Y278495D01*
X1595010Y278753D01*
X1595125Y279115D01*
X1595048Y279477D01*
X1594857Y279787D01*
X1594512Y279993D01*
X1594052Y280097D01*
X1593783Y280303D01*
X1593668Y280665D01*
X1593745Y281027D01*
X1593937Y281285D01*
X1594205Y281440D01*
X1594473D01*
X1594742Y281337D01*
X1594972Y281078D01*
G01X1596768Y278340D02*
Y281440D01*
G01Y279942D02*
X1596960Y280200D01*
X1597152Y280355D01*
X1597458Y280407D01*
X1597688Y280355D01*
X1597957Y280148D01*
X1598072Y279838D01*
Y278340D01*
G01X1600520D02*
X1600290Y278392D01*
X1600060Y278598D01*
X1599907Y278960D01*
X1599830Y279373D01*
X1599907Y279787D01*
X1600060Y280148D01*
X1600290Y280355D01*
X1600520Y280407D01*
X1600750Y280355D01*
X1600980Y280148D01*
X1601133Y279787D01*
X1601172Y279373D01*
X1601133Y278960D01*
X1600980Y278598D01*
X1600750Y278392D01*
X1600520Y278340D01*
G01X1603083D02*
Y280407D01*
G01Y279993D02*
X1603275Y280200D01*
X1603467Y280355D01*
X1603735Y280407D01*
X1603927Y280355D01*
X1604157Y280200D01*
G01X1606720Y281440D02*
Y278340D01*
G01X1606183Y280407D02*
X1607257D01*
G01X1609628Y277307D02*
X1609245Y277823D01*
X1609053Y278340D01*
Y280407D01*
X1609245Y280923D01*
X1609628Y281440D01*
G01X1612920Y278340D02*
Y281440D01*
X1612460Y280820D01*
G01Y278340D02*
X1613380D01*
G01X1616020D02*
Y281440D01*
X1615560Y280820D01*
G01Y278340D02*
X1616480D01*
G01X1618622Y279373D02*
X1619618D01*
G01X1622220Y278340D02*
Y281440D01*
X1621760Y280820D01*
G01Y278340D02*
X1622680D01*
G01X1624592Y280923D02*
X1624822Y281233D01*
X1625090Y281388D01*
X1625397Y281440D01*
X1625780Y281337D01*
X1626048Y281078D01*
X1626125Y280768D01*
X1626087Y280458D01*
X1625933Y280200D01*
X1625167Y279683D01*
X1624822Y279322D01*
X1624592Y278805D01*
X1624515Y278340D01*
X1626125D01*
G01X1628612Y277307D02*
X1628995Y277823D01*
X1629187Y278340D01*
Y280407D01*
X1628995Y280923D01*
X1628612Y281440D01*
G01X1593515Y272753D02*
X1593822Y272495D01*
X1594167Y272340D01*
X1594473D01*
X1594780Y272495D01*
X1595010Y272753D01*
X1595125Y273115D01*
X1595048Y273477D01*
X1594857Y273787D01*
X1594512Y273993D01*
X1594052Y274097D01*
X1593783Y274303D01*
X1593668Y274665D01*
X1593745Y275027D01*
X1593937Y275285D01*
X1594205Y275440D01*
X1594473D01*
X1594742Y275337D01*
X1594972Y275078D01*
G01X1596768Y272340D02*
Y275440D01*
G01Y273942D02*
X1596960Y274200D01*
X1597152Y274355D01*
X1597458Y274407D01*
X1597688Y274355D01*
X1597957Y274148D01*
X1598072Y273838D01*
Y272340D01*
G01X1600520D02*
X1600290Y272392D01*
X1600060Y272598D01*
X1599907Y272960D01*
X1599830Y273373D01*
X1599907Y273787D01*
X1600060Y274148D01*
X1600290Y274355D01*
X1600520Y274407D01*
X1600750Y274355D01*
X1600980Y274148D01*
X1601133Y273787D01*
X1601172Y273373D01*
X1601133Y272960D01*
X1600980Y272598D01*
X1600750Y272392D01*
X1600520Y272340D01*
G01X1603083D02*
Y274407D01*
G01Y273993D02*
X1603275Y274200D01*
X1603467Y274355D01*
X1603735Y274407D01*
X1603927Y274355D01*
X1604157Y274200D01*
G01X1606720Y275440D02*
Y272340D01*
G01X1606183Y274407D02*
X1607257D01*
G01X1609628Y271307D02*
X1609245Y271823D01*
X1609053Y272340D01*
Y274407D01*
X1609245Y274923D01*
X1609628Y275440D01*
G01X1612920Y272340D02*
Y275440D01*
X1612460Y274820D01*
G01Y272340D02*
X1613380D01*
G01X1615177Y272960D02*
X1615407Y272598D01*
X1615713Y272392D01*
X1616058Y272340D01*
X1616365Y272392D01*
X1616672Y272650D01*
X1616863Y272960D01*
X1616902Y273270D01*
X1616825Y273632D01*
X1616557Y273890D01*
X1616288Y273993D01*
X1615943D01*
G01X1616288D02*
X1616518Y274148D01*
X1616710Y274407D01*
X1616787Y274717D01*
X1616710Y275027D01*
X1616518Y275285D01*
X1616173Y275440D01*
X1615828Y275388D01*
X1615483Y275182D01*
G01X1618622Y273373D02*
X1619618D01*
G01X1622220Y272340D02*
Y275440D01*
X1621760Y274820D01*
G01Y272340D02*
X1622680D01*
G01X1625780D02*
Y275440D01*
X1624362Y273218D01*
X1626278D01*
G01X1628612Y271307D02*
X1628995Y271823D01*
X1629187Y272340D01*
Y274407D01*
X1628995Y274923D01*
X1628612Y275440D01*
G01X1593515Y296753D02*
X1593822Y296495D01*
X1594167Y296340D01*
X1594473D01*
X1594780Y296495D01*
X1595010Y296753D01*
X1595125Y297115D01*
X1595048Y297477D01*
X1594857Y297787D01*
X1594512Y297993D01*
X1594052Y298097D01*
X1593783Y298303D01*
X1593668Y298665D01*
X1593745Y299027D01*
X1593937Y299285D01*
X1594205Y299440D01*
X1594473D01*
X1594742Y299337D01*
X1594972Y299078D01*
G01X1596768Y296340D02*
Y299440D01*
G01Y297942D02*
X1596960Y298200D01*
X1597152Y298355D01*
X1597458Y298407D01*
X1597688Y298355D01*
X1597957Y298148D01*
X1598072Y297838D01*
Y296340D01*
G01X1600520D02*
X1600290Y296392D01*
X1600060Y296598D01*
X1599907Y296960D01*
X1599830Y297373D01*
X1599907Y297787D01*
X1600060Y298148D01*
X1600290Y298355D01*
X1600520Y298407D01*
X1600750Y298355D01*
X1600980Y298148D01*
X1601133Y297787D01*
X1601172Y297373D01*
X1601133Y296960D01*
X1600980Y296598D01*
X1600750Y296392D01*
X1600520Y296340D01*
G01X1603083D02*
Y298407D01*
G01Y297993D02*
X1603275Y298200D01*
X1603467Y298355D01*
X1603735Y298407D01*
X1603927Y298355D01*
X1604157Y298200D01*
G01X1606720Y299440D02*
Y296340D01*
G01X1606183Y298407D02*
X1607257D01*
G01X1609628Y295307D02*
X1609245Y295823D01*
X1609053Y296340D01*
Y298407D01*
X1609245Y298923D01*
X1609628Y299440D01*
G01X1612077Y296805D02*
X1612307Y296547D01*
X1612575Y296392D01*
X1612920Y296340D01*
X1613265Y296443D01*
X1613533Y296650D01*
X1613725Y297012D01*
X1613763Y297425D01*
X1613687Y297838D01*
X1613495Y298097D01*
X1613227Y298303D01*
X1612958Y298355D01*
X1612690Y298303D01*
X1612345Y298097D01*
X1612460Y299440D01*
X1613495D01*
G01X1615522Y297373D02*
X1616518D01*
G01X1618392Y297632D02*
X1618660Y297993D01*
X1618890Y298200D01*
X1619197Y298303D01*
X1619465Y298200D01*
X1619657Y297993D01*
X1619810Y297683D01*
X1619848Y297322D01*
X1619810Y297012D01*
X1619657Y296702D01*
X1619427Y296443D01*
X1619158Y296340D01*
X1618852Y296443D01*
X1618583Y296753D01*
X1618430Y297218D01*
X1618392Y297735D01*
X1618468Y298407D01*
X1618583Y298768D01*
X1618775Y299130D01*
X1619043Y299388D01*
X1619312Y299440D01*
X1619580Y299337D01*
X1619772Y299078D01*
G01X1622412Y295307D02*
X1622795Y295823D01*
X1622987Y296340D01*
Y298407D01*
X1622795Y298923D01*
X1622412Y299440D01*
G01X1593515Y290753D02*
X1593822Y290495D01*
X1594167Y290340D01*
X1594473D01*
X1594780Y290495D01*
X1595010Y290753D01*
X1595125Y291115D01*
X1595048Y291477D01*
X1594857Y291787D01*
X1594512Y291993D01*
X1594052Y292097D01*
X1593783Y292303D01*
X1593668Y292665D01*
X1593745Y293027D01*
X1593937Y293285D01*
X1594205Y293440D01*
X1594473D01*
X1594742Y293337D01*
X1594972Y293078D01*
G01X1596768Y290340D02*
Y293440D01*
G01Y291942D02*
X1596960Y292200D01*
X1597152Y292355D01*
X1597458Y292407D01*
X1597688Y292355D01*
X1597957Y292148D01*
X1598072Y291838D01*
Y290340D01*
G01X1600520D02*
X1600290Y290392D01*
X1600060Y290598D01*
X1599907Y290960D01*
X1599830Y291373D01*
X1599907Y291787D01*
X1600060Y292148D01*
X1600290Y292355D01*
X1600520Y292407D01*
X1600750Y292355D01*
X1600980Y292148D01*
X1601133Y291787D01*
X1601172Y291373D01*
X1601133Y290960D01*
X1600980Y290598D01*
X1600750Y290392D01*
X1600520Y290340D01*
G01X1603083D02*
Y292407D01*
G01Y291993D02*
X1603275Y292200D01*
X1603467Y292355D01*
X1603735Y292407D01*
X1603927Y292355D01*
X1604157Y292200D01*
G01X1606720Y293440D02*
Y290340D01*
G01X1606183Y292407D02*
X1607257D01*
G01X1609628Y289307D02*
X1609245Y289823D01*
X1609053Y290340D01*
Y292407D01*
X1609245Y292923D01*
X1609628Y293440D01*
G01X1612843Y290340D02*
X1612920Y291012D01*
X1613035Y291580D01*
X1613188Y292097D01*
X1613380Y292665D01*
X1613687Y293440D01*
X1612153D01*
G01X1615522Y291373D02*
X1616518D01*
G01X1619120Y290340D02*
X1619388Y290392D01*
X1619695Y290547D01*
X1619887Y290805D01*
X1619963Y291167D01*
X1619887Y291528D01*
X1619657Y291838D01*
X1619312Y291993D01*
X1618928D01*
X1618698Y292097D01*
X1618507Y292355D01*
X1618430Y292717D01*
X1618545Y293078D01*
X1618813Y293337D01*
X1619120Y293440D01*
X1619427Y293337D01*
X1619695Y293078D01*
X1619810Y292717D01*
X1619733Y292355D01*
X1619542Y292097D01*
X1619312Y291993D01*
X1618928D01*
X1618583Y291838D01*
X1618353Y291528D01*
X1618277Y291167D01*
X1618353Y290805D01*
X1618545Y290547D01*
X1618852Y290392D01*
X1619120Y290340D01*
G01X1622412Y289307D02*
X1622795Y289823D01*
X1622987Y290340D01*
Y292407D01*
X1622795Y292923D01*
X1622412Y293440D01*
G01X1593515Y284753D02*
X1593822Y284495D01*
X1594167Y284340D01*
X1594473D01*
X1594780Y284495D01*
X1595010Y284753D01*
X1595125Y285115D01*
X1595048Y285477D01*
X1594857Y285787D01*
X1594512Y285993D01*
X1594052Y286097D01*
X1593783Y286303D01*
X1593668Y286665D01*
X1593745Y287027D01*
X1593937Y287285D01*
X1594205Y287440D01*
X1594473D01*
X1594742Y287337D01*
X1594972Y287078D01*
G01X1596768Y284340D02*
Y287440D01*
G01Y285942D02*
X1596960Y286200D01*
X1597152Y286355D01*
X1597458Y286407D01*
X1597688Y286355D01*
X1597957Y286148D01*
X1598072Y285838D01*
Y284340D01*
G01X1600520D02*
X1600290Y284392D01*
X1600060Y284598D01*
X1599907Y284960D01*
X1599830Y285373D01*
X1599907Y285787D01*
X1600060Y286148D01*
X1600290Y286355D01*
X1600520Y286407D01*
X1600750Y286355D01*
X1600980Y286148D01*
X1601133Y285787D01*
X1601172Y285373D01*
X1601133Y284960D01*
X1600980Y284598D01*
X1600750Y284392D01*
X1600520Y284340D01*
G01X1603083D02*
Y286407D01*
G01Y285993D02*
X1603275Y286200D01*
X1603467Y286355D01*
X1603735Y286407D01*
X1603927Y286355D01*
X1604157Y286200D01*
G01X1606720Y287440D02*
Y284340D01*
G01X1606183Y286407D02*
X1607257D01*
G01X1609628Y283307D02*
X1609245Y283823D01*
X1609053Y284340D01*
Y286407D01*
X1609245Y286923D01*
X1609628Y287440D01*
G01X1612268Y284702D02*
X1612537Y284443D01*
X1612843Y284340D01*
X1613150Y284443D01*
X1613418Y284753D01*
X1613610Y285218D01*
X1613687Y285683D01*
Y286252D01*
X1613610Y286717D01*
X1613418Y287130D01*
X1613188Y287337D01*
X1612920Y287440D01*
X1612613Y287337D01*
X1612383Y287130D01*
X1612230Y286820D01*
X1612153Y286407D01*
X1612230Y286045D01*
X1612422Y285683D01*
X1612652Y285477D01*
X1612920Y285425D01*
X1613227Y285528D01*
X1613457Y285787D01*
X1613687Y286252D01*
G01X1615522Y285373D02*
X1616518D01*
G01X1619120Y284340D02*
Y287440D01*
X1618660Y286820D01*
G01Y284340D02*
X1619580D01*
G01X1622220Y287440D02*
X1621913Y287337D01*
X1621683Y287078D01*
X1621530Y286768D01*
X1621415Y286355D01*
X1621377Y285890D01*
X1621415Y285425D01*
X1621530Y285012D01*
X1621683Y284702D01*
X1621913Y284443D01*
X1622220Y284340D01*
X1622527Y284443D01*
X1622757Y284702D01*
X1622910Y285012D01*
X1623025Y285425D01*
X1623063Y285890D01*
X1623025Y286355D01*
X1622910Y286768D01*
X1622757Y287078D01*
X1622527Y287337D01*
X1622220Y287440D01*
G01X1625512Y283307D02*
X1625895Y283823D01*
X1626087Y284340D01*
Y286407D01*
X1625895Y286923D01*
X1625512Y287440D01*
G01X1594720Y310740D02*
X1594413Y310792D01*
X1594145Y310998D01*
X1593915Y311308D01*
X1593762Y311670D01*
X1593685Y312083D01*
Y312497D01*
X1593762Y312910D01*
X1593915Y313272D01*
X1594145Y313582D01*
X1594413Y313788D01*
X1594720Y313840D01*
X1595027Y313788D01*
X1595295Y313582D01*
X1595525Y313272D01*
X1595678Y312910D01*
X1595755Y312497D01*
Y312083D01*
X1595678Y311670D01*
X1595525Y311308D01*
X1595295Y310998D01*
X1595027Y310792D01*
X1594720Y310740D01*
G01X1597130Y309707D02*
Y312807D01*
G01Y312342D02*
X1597322Y312600D01*
X1597513Y312755D01*
X1597820Y312807D01*
X1598088Y312755D01*
X1598357Y312497D01*
X1598472Y312135D01*
X1598510Y311773D01*
X1598472Y311412D01*
X1598357Y311050D01*
X1598127Y310843D01*
X1597820Y310740D01*
X1597552Y310792D01*
X1597283Y310947D01*
X1597130Y311153D01*
G01X1600345Y312135D02*
X1601572D01*
X1601457Y312497D01*
X1601265Y312703D01*
X1600997Y312807D01*
X1600728Y312755D01*
X1600498Y312600D01*
X1600345Y312238D01*
X1600268Y311928D01*
Y311618D01*
X1600345Y311308D01*
X1600537Y310998D01*
X1600767Y310792D01*
X1601035Y310740D01*
X1601303Y310843D01*
X1601572Y311153D01*
G01X1603368Y310740D02*
Y312807D01*
G01Y312290D02*
X1603522Y312548D01*
X1603752Y312755D01*
X1604058Y312807D01*
X1604327Y312755D01*
X1604557Y312548D01*
X1604672Y312187D01*
Y310740D01*
G01X1593515Y302753D02*
X1593822Y302495D01*
X1594167Y302340D01*
X1594473D01*
X1594780Y302495D01*
X1595010Y302753D01*
X1595125Y303115D01*
X1595048Y303477D01*
X1594857Y303787D01*
X1594512Y303993D01*
X1594052Y304097D01*
X1593783Y304303D01*
X1593668Y304665D01*
X1593745Y305027D01*
X1593937Y305285D01*
X1594205Y305440D01*
X1594473D01*
X1594742Y305337D01*
X1594972Y305078D01*
G01X1596768Y302340D02*
Y305440D01*
G01Y303942D02*
X1596960Y304200D01*
X1597152Y304355D01*
X1597458Y304407D01*
X1597688Y304355D01*
X1597957Y304148D01*
X1598072Y303838D01*
Y302340D01*
G01X1600520D02*
X1600290Y302392D01*
X1600060Y302598D01*
X1599907Y302960D01*
X1599830Y303373D01*
X1599907Y303787D01*
X1600060Y304148D01*
X1600290Y304355D01*
X1600520Y304407D01*
X1600750Y304355D01*
X1600980Y304148D01*
X1601133Y303787D01*
X1601172Y303373D01*
X1601133Y302960D01*
X1600980Y302598D01*
X1600750Y302392D01*
X1600520Y302340D01*
G01X1603083D02*
Y304407D01*
G01Y303993D02*
X1603275Y304200D01*
X1603467Y304355D01*
X1603735Y304407D01*
X1603927Y304355D01*
X1604157Y304200D01*
G01X1606720Y305440D02*
Y302340D01*
G01X1606183Y304407D02*
X1607257D01*
G01X1609628Y301307D02*
X1609245Y301823D01*
X1609053Y302340D01*
Y304407D01*
X1609245Y304923D01*
X1609628Y305440D01*
G01X1612077Y302960D02*
X1612307Y302598D01*
X1612613Y302392D01*
X1612958Y302340D01*
X1613265Y302392D01*
X1613572Y302650D01*
X1613763Y302960D01*
X1613802Y303270D01*
X1613725Y303632D01*
X1613457Y303890D01*
X1613188Y303993D01*
X1612843D01*
G01X1613188D02*
X1613418Y304148D01*
X1613610Y304407D01*
X1613687Y304717D01*
X1613610Y305027D01*
X1613418Y305285D01*
X1613073Y305440D01*
X1612728Y305388D01*
X1612383Y305182D01*
G01X1615522Y303373D02*
X1616518D01*
G01X1619580Y302340D02*
Y305440D01*
X1618162Y303218D01*
X1620078D01*
G01X1622412Y301307D02*
X1622795Y301823D01*
X1622987Y302340D01*
Y304407D01*
X1622795Y304923D01*
X1622412Y305440D01*
G01X1595417Y319050D02*
X1593883D01*
Y322150D01*
X1595417D01*
G01X1594803Y320652D02*
X1593883D01*
G01X1597098Y319050D02*
Y321117D01*
G01Y320600D02*
X1597252Y320858D01*
X1597482Y321065D01*
X1597788Y321117D01*
X1598057Y321065D01*
X1598287Y320858D01*
X1598402Y320497D01*
Y319050D01*
G01X1601540D02*
Y321117D01*
G01Y320755D02*
X1601387Y320962D01*
X1601157Y321065D01*
X1600888Y321117D01*
X1600620Y321013D01*
X1600390Y320807D01*
X1600237Y320497D01*
X1600160Y320083D01*
X1600237Y319670D01*
X1600390Y319360D01*
X1600620Y319153D01*
X1600888Y319050D01*
X1601157Y319102D01*
X1601387Y319257D01*
X1601540Y319463D01*
G01X1603260Y319050D02*
Y322150D01*
G01Y320600D02*
X1603452Y320910D01*
X1603682Y321065D01*
X1603912Y321117D01*
X1604257Y321013D01*
X1604487Y320807D01*
X1604640Y320445D01*
Y320032D01*
X1604563Y319618D01*
X1604410Y319308D01*
X1604142Y319102D01*
X1603912Y319050D01*
X1603682Y319102D01*
X1603452Y319257D01*
X1603260Y319515D01*
G01X1607050Y319050D02*
Y322150D01*
G01X1609575Y320445D02*
X1610802D01*
X1610687Y320807D01*
X1610495Y321013D01*
X1610227Y321117D01*
X1609958Y321065D01*
X1609728Y320910D01*
X1609575Y320548D01*
X1609498Y320238D01*
Y319928D01*
X1609575Y319618D01*
X1609767Y319308D01*
X1609997Y319102D01*
X1610265Y319050D01*
X1610533Y319153D01*
X1610802Y319463D01*
G01X1595646Y590036D02*
Y595984D01*
G01X1633442Y590036D02*
X1595646D01*
G01X1599955Y623832D02*
X1611955D01*
G01X1599955Y617832D02*
Y623832D01*
G01X1611955Y617832D02*
X1599955D01*
G01X1595646Y615232D02*
X1633442D01*
G01X1595646Y609284D02*
Y615232D01*
G01X1621278Y625732D02*
X1595688D01*
G01D02*
Y629727D01*
G01Y651322D02*
X1621278D01*
G01X1595688Y647327D02*
Y651322D01*
G01X1602680Y652942D02*
Y656142D01*
G01X1608880Y652942D02*
X1602680D01*
G01Y656142D02*
X1608880D01*
G01X1621278Y659732D02*
X1595688D01*
G01D02*
Y663727D01*
G01X1596013Y686810D02*
Y689910D01*
X1596933D01*
X1597240Y689755D01*
X1597470Y689393D01*
X1597547Y688980D01*
X1597470Y688567D01*
X1597278Y688257D01*
X1596933Y688102D01*
X1596013D01*
G01X1599113Y689910D02*
Y686810D01*
X1600647D01*
G01X1603440D02*
Y689910D01*
X1602022Y687688D01*
X1603938D01*
G01X1595688Y685322D02*
X1621278D01*
G01X1595688Y681327D02*
Y685322D01*
G01X1596667Y697211D02*
X1622257D01*
G01X1621278Y693732D02*
X1595688D01*
G01D02*
Y697727D01*
G01X1596667Y1335007D02*
Y716572D01*
G01X1595688Y719322D02*
X1621278D01*
G01X1595688Y715327D02*
Y719322D01*
G01X1600860Y720982D02*
Y724182D01*
G01X1607060Y720982D02*
X1600860D01*
G01X1607060Y724182D02*
Y720982D01*
G01X1622257Y732644D02*
X1596667D01*
G01X1600860Y724182D02*
X1607060D01*
G01X1622257Y1299574D02*
X1596667D01*
G01X1595345Y1336996D02*
X1595537Y1336686D01*
X1595767Y1336479D01*
X1596035Y1336376D01*
X1596342Y1336479D01*
X1596572Y1336686D01*
X1596802Y1336996D01*
X1596879Y1337409D01*
Y1339476D01*
G01X1599212Y1336376D02*
Y1339476D01*
X1598752Y1338856D01*
G01Y1336376D02*
X1599672D01*
G01X1602312Y1339476D02*
X1602005Y1339373D01*
X1601775Y1339114D01*
X1601622Y1338804D01*
X1601507Y1338391D01*
X1601469Y1337926D01*
X1601507Y1337461D01*
X1601622Y1337048D01*
X1601775Y1336738D01*
X1602005Y1336479D01*
X1602312Y1336376D01*
X1602619Y1336479D01*
X1602849Y1336738D01*
X1603002Y1337048D01*
X1603117Y1337461D01*
X1603155Y1337926D01*
X1603117Y1338391D01*
X1603002Y1338804D01*
X1602849Y1339114D01*
X1602619Y1339373D01*
X1602312Y1339476D01*
G01X1622257Y1335007D02*
X1596667D01*
G01X1602225Y1366435D02*
X1601910Y1365965D01*
X1601700Y1365417D01*
Y1364790D01*
X1602015Y1364085D01*
X1602540Y1363537D01*
X1603170Y1363145D01*
X1604220Y1362832D01*
X1605165Y1362754D01*
X1606110Y1362910D01*
X1606740Y1363145D01*
X1607370Y1363615D01*
X1607790Y1364164D01*
X1608000Y1364712D01*
Y1365260D01*
X1607790Y1365809D01*
X1607475Y1366279D01*
X1607055Y1366670D01*
G01X1608000Y1370855D02*
X1606635Y1371012D01*
X1605480Y1371247D01*
X1604430Y1371560D01*
X1603275Y1371952D01*
X1601700Y1372579D01*
Y1369445D01*
G01X1598500Y1362754D02*
X1592200Y1364712D01*
X1598500Y1366670D01*
G01X1596295Y1365965D02*
Y1363459D01*
G01X1595875Y1369524D02*
X1595140Y1370072D01*
X1594720Y1370542D01*
X1594510Y1371169D01*
X1594720Y1371717D01*
X1595140Y1372109D01*
X1595770Y1372422D01*
X1596505Y1372500D01*
X1597135Y1372422D01*
X1597765Y1372109D01*
X1598290Y1371639D01*
X1598500Y1371090D01*
X1598290Y1370464D01*
X1597660Y1369915D01*
X1596715Y1369602D01*
X1595665Y1369524D01*
X1594300Y1369680D01*
X1593565Y1369915D01*
X1592830Y1370307D01*
X1592305Y1370855D01*
X1592200Y1371404D01*
X1592410Y1371952D01*
X1592935Y1372344D01*
G01X1600100Y1361062D02*
X1590900D01*
G01Y1374562D02*
Y1361062D01*
G01X1609300D02*
X1600100D01*
G01Y1374562D02*
Y1361062D01*
G01X1590900Y1374562D02*
X1600100D01*
G01D02*
X1609300D01*
G01X1602016Y1412769D02*
Y1409569D01*
G01X1595816Y1412769D02*
X1602016D01*
G01X1595816Y1409569D02*
Y1412769D01*
G01X1602016Y1409569D02*
X1595816D01*
G01X1602016Y1417269D02*
Y1414069D01*
G01X1595816Y1417269D02*
X1602016D01*
G01X1595816Y1414069D02*
Y1417269D01*
G01X1602016Y1414069D02*
X1595816D01*
G01Y1418569D02*
Y1421769D01*
G01X1602016Y1418569D02*
X1595816D01*
G01X1602016Y1421769D02*
Y1418569D01*
G01X1595816Y1421769D02*
X1602016D01*
G01X1595816Y1432069D02*
Y1435269D01*
G01X1602016Y1432069D02*
X1595816D01*
G01X1602016Y1435269D02*
Y1432069D01*
G01X1595816Y1435269D02*
X1602016D01*
G01X1595816Y1436569D02*
Y1439769D01*
G01X1602016Y1436569D02*
X1595816D01*
G01X1602016Y1439769D02*
Y1436569D01*
G01Y1426269D02*
Y1423069D01*
G01X1595816Y1426269D02*
X1602016D01*
G01X1595816Y1423069D02*
Y1426269D01*
G01X1602016Y1423069D02*
X1595816D01*
G01X1602016Y1430769D02*
Y1427569D01*
G01X1595816Y1430769D02*
X1602016D01*
G01X1595816Y1427569D02*
Y1430769D01*
G01X1602016Y1427569D02*
X1595816D01*
G01Y1439769D02*
X1602016D01*
G01Y1444269D02*
Y1441069D01*
G01X1595816Y1444269D02*
X1602016D01*
G01X1595816Y1441069D02*
Y1444269D01*
G01X1602016Y1441069D02*
X1595816D01*
G01Y1450471D02*
Y1453671D01*
G01X1602016Y1450471D02*
X1595816D01*
G01X1602016Y1453671D02*
Y1450471D01*
G01X1595816Y1453671D02*
X1602016D01*
G01Y1448753D02*
Y1445553D01*
G01X1595816Y1448753D02*
X1602016D01*
G01X1595816Y1445553D02*
Y1448753D01*
G01X1602016Y1445553D02*
X1595816D01*
G01X1595647Y1653152D02*
Y1656252D01*
X1594229Y1654030D01*
X1596145D01*
G01X1602218Y1653617D02*
X1602448Y1653359D01*
X1602716Y1653204D01*
X1603061Y1653152D01*
X1603406Y1653255D01*
X1603674Y1653462D01*
X1603866Y1653824D01*
X1603904Y1654237D01*
X1603828Y1654650D01*
X1603636Y1654909D01*
X1603368Y1655115D01*
X1603099Y1655167D01*
X1602831Y1655115D01*
X1602486Y1654909D01*
X1602601Y1656252D01*
X1603636D01*
G01X1617915Y119159D02*
X1621115D01*
G01X1617915Y112959D02*
Y119159D01*
G01X1621115Y112959D02*
X1617915D01*
G01X1621115Y119159D02*
Y112959D01*
G01X1616813Y131450D02*
Y155860D01*
G01X1616608Y131450D02*
X1616813D01*
G01Y155860D02*
X1616608D01*
G01X1620686Y583473D02*
Y586573D01*
X1621606D01*
X1621913Y586418D01*
X1622143Y586056D01*
X1622220Y585643D01*
X1622143Y585230D01*
X1621951Y584920D01*
X1621606Y584765D01*
X1620686D01*
G01X1623786Y586573D02*
Y583473D01*
X1625320D01*
G01X1626810Y584093D02*
X1627040Y583731D01*
X1627346Y583525D01*
X1627691Y583473D01*
X1627998Y583525D01*
X1628305Y583783D01*
X1628496Y584093D01*
X1628535Y584403D01*
X1628458Y584765D01*
X1628190Y585023D01*
X1627921Y585126D01*
X1627576D01*
G01X1627921D02*
X1628151Y585281D01*
X1628343Y585540D01*
X1628420Y585850D01*
X1628343Y586160D01*
X1628151Y586418D01*
X1627806Y586573D01*
X1627461Y586521D01*
X1627116Y586315D01*
G01X1609720Y585162D02*
Y588362D01*
G01X1615920Y585162D02*
X1609720D01*
G01X1615920Y588362D02*
Y585162D01*
G01X1609720Y588362D02*
X1615920D01*
G01X1611955Y623832D02*
Y617832D01*
G01X1621278Y629727D02*
Y625732D01*
G01X1612723Y653292D02*
Y656392D01*
X1613643D01*
X1613950Y656237D01*
X1614180Y655875D01*
X1614257Y655462D01*
X1614180Y655049D01*
X1613988Y654739D01*
X1613643Y654584D01*
X1612723D01*
G01X1615823Y656392D02*
Y653292D01*
X1617357D01*
G01X1618847Y653912D02*
X1619077Y653550D01*
X1619383Y653344D01*
X1619728Y653292D01*
X1620035Y653344D01*
X1620342Y653602D01*
X1620533Y653912D01*
X1620572Y654222D01*
X1620495Y654584D01*
X1620227Y654842D01*
X1619958Y654945D01*
X1619613D01*
G01X1619958D02*
X1620188Y655100D01*
X1620380Y655359D01*
X1620457Y655669D01*
X1620380Y655979D01*
X1620188Y656237D01*
X1619843Y656392D01*
X1619498Y656340D01*
X1619153Y656134D01*
G01X1621947Y653757D02*
X1622177Y653499D01*
X1622445Y653344D01*
X1622790Y653292D01*
X1623135Y653395D01*
X1623403Y653602D01*
X1623595Y653964D01*
X1623633Y654377D01*
X1623557Y654790D01*
X1623365Y655049D01*
X1623097Y655255D01*
X1622828Y655307D01*
X1622560Y655255D01*
X1622215Y655049D01*
X1622330Y656392D01*
X1623365D01*
G01X1621278Y651322D02*
Y647327D01*
G01X1608880Y656142D02*
Y652942D01*
G01X1621278Y663727D02*
Y659732D01*
G01X1607683Y689067D02*
Y692167D01*
X1608603D01*
X1608910Y692012D01*
X1609140Y691650D01*
X1609217Y691237D01*
X1609140Y690824D01*
X1608948Y690514D01*
X1608603Y690359D01*
X1607683D01*
G01X1610707Y692167D02*
Y689945D01*
X1610860Y689480D01*
X1611167Y689170D01*
X1611550Y689067D01*
X1611933Y689170D01*
X1612240Y689480D01*
X1612393Y689945D01*
Y692167D01*
G01X1615110Y689067D02*
Y692167D01*
X1613692Y689945D01*
X1615608D01*
G01X1618210Y689067D02*
Y692167D01*
X1616792Y689945D01*
X1618708D01*
G01X1619700Y688034D02*
X1622000D01*
G01X1623183Y689067D02*
Y692167D01*
X1624103D01*
X1624410Y692012D01*
X1624640Y691650D01*
X1624717Y691237D01*
X1624640Y690824D01*
X1624448Y690514D01*
X1624103Y690359D01*
X1623183D01*
G01X1627050Y692167D02*
X1626743Y692064D01*
X1626513Y691805D01*
X1626360Y691495D01*
X1626245Y691082D01*
X1626207Y690617D01*
X1626245Y690152D01*
X1626360Y689739D01*
X1626513Y689429D01*
X1626743Y689170D01*
X1627050Y689067D01*
X1627357Y689170D01*
X1627587Y689429D01*
X1627740Y689739D01*
X1627855Y690152D01*
X1627893Y690617D01*
X1627855Y691082D01*
X1627740Y691495D01*
X1627587Y691805D01*
X1627357Y692064D01*
X1627050Y692167D01*
G01X1629000Y688034D02*
X1631300D01*
G01X1632522Y691650D02*
X1632752Y691960D01*
X1633020Y692115D01*
X1633327Y692167D01*
X1633710Y692064D01*
X1633978Y691805D01*
X1634055Y691495D01*
X1634017Y691185D01*
X1633863Y690927D01*
X1633097Y690410D01*
X1632752Y690049D01*
X1632522Y689532D01*
X1632445Y689067D01*
X1634055D01*
G01X1621278Y685322D02*
Y681327D01*
G01X1622257Y697211D02*
Y1335007D01*
G01X1621278Y697727D02*
Y693732D01*
G01Y719322D02*
Y715327D01*
G01X1618500Y1351362D02*
Y1374562D01*
G01X1617000Y1362754D02*
X1610700Y1364712D01*
X1617000Y1366670D01*
G01X1614795Y1365965D02*
Y1363459D01*
G01X1617000Y1370855D02*
X1615635Y1371012D01*
X1614480Y1371247D01*
X1613430Y1371560D01*
X1612275Y1371952D01*
X1610700Y1372579D01*
Y1369445D01*
G01X1618500Y1361062D02*
X1609300D01*
G01Y1374562D02*
Y1361062D01*
G01Y1374562D02*
X1618500D01*
G01X1610793Y1401102D02*
Y1404202D01*
X1611713D01*
X1612020Y1404047D01*
X1612250Y1403685D01*
X1612327Y1403272D01*
X1612250Y1402859D01*
X1612058Y1402549D01*
X1611713Y1402394D01*
X1610793D01*
G01X1613893Y1404202D02*
Y1401102D01*
X1615427D01*
G01X1616917Y1401722D02*
X1617147Y1401360D01*
X1617453Y1401154D01*
X1617798Y1401102D01*
X1618105Y1401154D01*
X1618412Y1401412D01*
X1618603Y1401722D01*
X1618642Y1402032D01*
X1618565Y1402394D01*
X1618297Y1402652D01*
X1618028Y1402755D01*
X1617683D01*
G01X1618028D02*
X1618258Y1402910D01*
X1618450Y1403169D01*
X1618527Y1403479D01*
X1618450Y1403789D01*
X1618258Y1404047D01*
X1617913Y1404202D01*
X1617568Y1404150D01*
X1617223Y1403944D01*
G01X1620017Y1401722D02*
X1620247Y1401360D01*
X1620553Y1401154D01*
X1620898Y1401102D01*
X1621205Y1401154D01*
X1621512Y1401412D01*
X1621703Y1401722D01*
X1621742Y1402032D01*
X1621665Y1402394D01*
X1621397Y1402652D01*
X1621128Y1402755D01*
X1620783D01*
G01X1621128D02*
X1621358Y1402910D01*
X1621550Y1403169D01*
X1621627Y1403479D01*
X1621550Y1403789D01*
X1621358Y1404047D01*
X1621013Y1404202D01*
X1620668Y1404150D01*
X1620323Y1403944D01*
G01X1622753Y1427891D02*
X1625953D01*
G01X1622753Y1421691D02*
Y1427891D01*
G01X1625953Y1421691D02*
X1622753D01*
G01X1625953Y1432191D02*
X1622753D01*
G01D02*
Y1438391D01*
G01X1615802Y1424766D02*
Y1427966D01*
G01X1622002Y1424766D02*
X1615802D01*
G01X1622002Y1427966D02*
Y1424766D01*
G01X1615802Y1427966D02*
X1622002D01*
G01X1615802Y1428296D02*
Y1431496D01*
G01X1622002Y1428296D02*
X1615802D01*
G01X1622002Y1431496D02*
Y1428296D01*
G01X1615802Y1431496D02*
X1622002D01*
G01X1610723Y1449942D02*
Y1453042D01*
X1611643D01*
X1611950Y1452887D01*
X1612180Y1452525D01*
X1612257Y1452112D01*
X1612180Y1451699D01*
X1611988Y1451389D01*
X1611643Y1451234D01*
X1610723D01*
G01X1613747Y1453042D02*
Y1450820D01*
X1613900Y1450355D01*
X1614207Y1450045D01*
X1614590Y1449942D01*
X1614973Y1450045D01*
X1615280Y1450355D01*
X1615433Y1450820D01*
Y1453042D01*
G01X1616962Y1451234D02*
X1617230Y1451595D01*
X1617460Y1451802D01*
X1617767Y1451905D01*
X1618035Y1451802D01*
X1618227Y1451595D01*
X1618380Y1451285D01*
X1618418Y1450924D01*
X1618380Y1450614D01*
X1618227Y1450304D01*
X1617997Y1450045D01*
X1617728Y1449942D01*
X1617422Y1450045D01*
X1617153Y1450355D01*
X1617000Y1450820D01*
X1616962Y1451337D01*
X1617038Y1452009D01*
X1617153Y1452370D01*
X1617345Y1452732D01*
X1617613Y1452990D01*
X1617882Y1453042D01*
X1618150Y1452939D01*
X1618342Y1452680D01*
G01X1620138Y1450304D02*
X1620407Y1450045D01*
X1620713Y1449942D01*
X1621020Y1450045D01*
X1621288Y1450355D01*
X1621480Y1450820D01*
X1621557Y1451285D01*
Y1451854D01*
X1621480Y1452319D01*
X1621288Y1452732D01*
X1621058Y1452939D01*
X1620790Y1453042D01*
X1620483Y1452939D01*
X1620253Y1452732D01*
X1620100Y1452422D01*
X1620023Y1452009D01*
X1620100Y1451647D01*
X1620292Y1451285D01*
X1620522Y1451079D01*
X1620790Y1451027D01*
X1621097Y1451130D01*
X1621327Y1451389D01*
X1621557Y1451854D01*
G01X1622740Y1448909D02*
X1625040D01*
G01X1626223Y1449942D02*
Y1453042D01*
X1627143D01*
X1627450Y1452887D01*
X1627680Y1452525D01*
X1627757Y1452112D01*
X1627680Y1451699D01*
X1627488Y1451389D01*
X1627143Y1451234D01*
X1626223D01*
G01X1630090Y1453042D02*
X1629783Y1452939D01*
X1629553Y1452680D01*
X1629400Y1452370D01*
X1629285Y1451957D01*
X1629247Y1451492D01*
X1629285Y1451027D01*
X1629400Y1450614D01*
X1629553Y1450304D01*
X1629783Y1450045D01*
X1630090Y1449942D01*
X1630397Y1450045D01*
X1630627Y1450304D01*
X1630780Y1450614D01*
X1630895Y1451027D01*
X1630933Y1451492D01*
X1630895Y1451957D01*
X1630780Y1452370D01*
X1630627Y1452680D01*
X1630397Y1452939D01*
X1630090Y1453042D01*
G01X1632040Y1448909D02*
X1634340D01*
G01X1636290Y1449942D02*
Y1453042D01*
X1635830Y1452422D01*
G01Y1449942D02*
X1636750D01*
G01X1622753Y1438391D02*
X1625953D01*
G01X1618732Y1653152D02*
X1618809Y1653824D01*
X1618924Y1654392D01*
X1619077Y1654909D01*
X1619269Y1655477D01*
X1619576Y1656252D01*
X1618042D01*
G01X1610207Y1654444D02*
X1610475Y1654805D01*
X1610705Y1655012D01*
X1611012Y1655115D01*
X1611280Y1655012D01*
X1611472Y1654805D01*
X1611625Y1654495D01*
X1611663Y1654134D01*
X1611625Y1653824D01*
X1611472Y1653514D01*
X1611242Y1653255D01*
X1610973Y1653152D01*
X1610667Y1653255D01*
X1610398Y1653565D01*
X1610245Y1654030D01*
X1610207Y1654547D01*
X1610283Y1655219D01*
X1610398Y1655580D01*
X1610590Y1655942D01*
X1610858Y1656200D01*
X1611127Y1656252D01*
X1611395Y1656149D01*
X1611587Y1655890D01*
G01X1637681Y51096D02*
X1642180D01*
G01X1630660D02*
X1635160D01*
G01X1624933Y116027D02*
Y119227D01*
G01X1631133Y116027D02*
X1624933D01*
G01X1631133Y119227D02*
Y116027D01*
G01X1624933Y119227D02*
X1631133D01*
G01X1624933Y128027D02*
Y131227D01*
G01X1631133Y128027D02*
X1624933D01*
G01X1631133Y131227D02*
Y128027D01*
G01X1624933Y131227D02*
X1631133D01*
G01X1624933Y120027D02*
Y123227D01*
G01X1631133Y120027D02*
X1624933D01*
G01X1631133Y123227D02*
Y120027D01*
G01X1624933Y123227D02*
X1631133D01*
G01X1669530Y169962D02*
X1627200D01*
Y270500D01*
X1627220D01*
G01X1638930Y183452D02*
Y198688D01*
G01X1651130Y183452D02*
X1638930D01*
G01Y198688D02*
X1651130D01*
G01X1634220Y272140D02*
X1633913Y272192D01*
X1633645Y272398D01*
X1633415Y272708D01*
X1633262Y273070D01*
X1633185Y273483D01*
Y273897D01*
X1633262Y274310D01*
X1633415Y274672D01*
X1633645Y274982D01*
X1633913Y275188D01*
X1634220Y275240D01*
X1634527Y275188D01*
X1634795Y274982D01*
X1635025Y274672D01*
X1635178Y274310D01*
X1635255Y273897D01*
Y273483D01*
X1635178Y273070D01*
X1635025Y272708D01*
X1634795Y272398D01*
X1634527Y272192D01*
X1634220Y272140D01*
G01X1636630Y271107D02*
Y274207D01*
G01Y273742D02*
X1636822Y274000D01*
X1637013Y274155D01*
X1637320Y274207D01*
X1637588Y274155D01*
X1637857Y273897D01*
X1637972Y273535D01*
X1638010Y273173D01*
X1637972Y272812D01*
X1637857Y272450D01*
X1637627Y272243D01*
X1637320Y272140D01*
X1637052Y272192D01*
X1636783Y272347D01*
X1636630Y272553D01*
G01X1639845Y273535D02*
X1641072D01*
X1640957Y273897D01*
X1640765Y274103D01*
X1640497Y274207D01*
X1640228Y274155D01*
X1639998Y274000D01*
X1639845Y273638D01*
X1639768Y273328D01*
Y273018D01*
X1639845Y272708D01*
X1640037Y272398D01*
X1640267Y272192D01*
X1640535Y272140D01*
X1640803Y272243D01*
X1641072Y272553D01*
G01X1642868Y272140D02*
Y274207D01*
G01Y273690D02*
X1643022Y273948D01*
X1643252Y274155D01*
X1643558Y274207D01*
X1643827Y274155D01*
X1644057Y273948D01*
X1644172Y273587D01*
Y272140D01*
G01X1634220Y278140D02*
X1633913Y278192D01*
X1633645Y278398D01*
X1633415Y278708D01*
X1633262Y279070D01*
X1633185Y279483D01*
Y279897D01*
X1633262Y280310D01*
X1633415Y280672D01*
X1633645Y280982D01*
X1633913Y281188D01*
X1634220Y281240D01*
X1634527Y281188D01*
X1634795Y280982D01*
X1635025Y280672D01*
X1635178Y280310D01*
X1635255Y279897D01*
Y279483D01*
X1635178Y279070D01*
X1635025Y278708D01*
X1634795Y278398D01*
X1634527Y278192D01*
X1634220Y278140D01*
G01X1636630Y277107D02*
Y280207D01*
G01Y279742D02*
X1636822Y280000D01*
X1637013Y280155D01*
X1637320Y280207D01*
X1637588Y280155D01*
X1637857Y279897D01*
X1637972Y279535D01*
X1638010Y279173D01*
X1637972Y278812D01*
X1637857Y278450D01*
X1637627Y278243D01*
X1637320Y278140D01*
X1637052Y278192D01*
X1636783Y278347D01*
X1636630Y278553D01*
G01X1639845Y279535D02*
X1641072D01*
X1640957Y279897D01*
X1640765Y280103D01*
X1640497Y280207D01*
X1640228Y280155D01*
X1639998Y280000D01*
X1639845Y279638D01*
X1639768Y279328D01*
Y279018D01*
X1639845Y278708D01*
X1640037Y278398D01*
X1640267Y278192D01*
X1640535Y278140D01*
X1640803Y278243D01*
X1641072Y278553D01*
G01X1642868Y278140D02*
Y280207D01*
G01Y279690D02*
X1643022Y279948D01*
X1643252Y280155D01*
X1643558Y280207D01*
X1643827Y280155D01*
X1644057Y279948D01*
X1644172Y279587D01*
Y278140D01*
G01X1634220Y284140D02*
X1633913Y284192D01*
X1633645Y284398D01*
X1633415Y284708D01*
X1633262Y285070D01*
X1633185Y285483D01*
Y285897D01*
X1633262Y286310D01*
X1633415Y286672D01*
X1633645Y286982D01*
X1633913Y287188D01*
X1634220Y287240D01*
X1634527Y287188D01*
X1634795Y286982D01*
X1635025Y286672D01*
X1635178Y286310D01*
X1635255Y285897D01*
Y285483D01*
X1635178Y285070D01*
X1635025Y284708D01*
X1634795Y284398D01*
X1634527Y284192D01*
X1634220Y284140D01*
G01X1636630Y283107D02*
Y286207D01*
G01Y285742D02*
X1636822Y286000D01*
X1637013Y286155D01*
X1637320Y286207D01*
X1637588Y286155D01*
X1637857Y285897D01*
X1637972Y285535D01*
X1638010Y285173D01*
X1637972Y284812D01*
X1637857Y284450D01*
X1637627Y284243D01*
X1637320Y284140D01*
X1637052Y284192D01*
X1636783Y284347D01*
X1636630Y284553D01*
G01X1639845Y285535D02*
X1641072D01*
X1640957Y285897D01*
X1640765Y286103D01*
X1640497Y286207D01*
X1640228Y286155D01*
X1639998Y286000D01*
X1639845Y285638D01*
X1639768Y285328D01*
Y285018D01*
X1639845Y284708D01*
X1640037Y284398D01*
X1640267Y284192D01*
X1640535Y284140D01*
X1640803Y284243D01*
X1641072Y284553D01*
G01X1642868Y284140D02*
Y286207D01*
G01Y285690D02*
X1643022Y285948D01*
X1643252Y286155D01*
X1643558Y286207D01*
X1643827Y286155D01*
X1644057Y285948D01*
X1644172Y285587D01*
Y284140D01*
G01X1634220Y290140D02*
X1633913Y290192D01*
X1633645Y290398D01*
X1633415Y290708D01*
X1633262Y291070D01*
X1633185Y291483D01*
Y291897D01*
X1633262Y292310D01*
X1633415Y292672D01*
X1633645Y292982D01*
X1633913Y293188D01*
X1634220Y293240D01*
X1634527Y293188D01*
X1634795Y292982D01*
X1635025Y292672D01*
X1635178Y292310D01*
X1635255Y291897D01*
Y291483D01*
X1635178Y291070D01*
X1635025Y290708D01*
X1634795Y290398D01*
X1634527Y290192D01*
X1634220Y290140D01*
G01X1636630Y289107D02*
Y292207D01*
G01Y291742D02*
X1636822Y292000D01*
X1637013Y292155D01*
X1637320Y292207D01*
X1637588Y292155D01*
X1637857Y291897D01*
X1637972Y291535D01*
X1638010Y291173D01*
X1637972Y290812D01*
X1637857Y290450D01*
X1637627Y290243D01*
X1637320Y290140D01*
X1637052Y290192D01*
X1636783Y290347D01*
X1636630Y290553D01*
G01X1639845Y291535D02*
X1641072D01*
X1640957Y291897D01*
X1640765Y292103D01*
X1640497Y292207D01*
X1640228Y292155D01*
X1639998Y292000D01*
X1639845Y291638D01*
X1639768Y291328D01*
Y291018D01*
X1639845Y290708D01*
X1640037Y290398D01*
X1640267Y290192D01*
X1640535Y290140D01*
X1640803Y290243D01*
X1641072Y290553D01*
G01X1642868Y290140D02*
Y292207D01*
G01Y291690D02*
X1643022Y291948D01*
X1643252Y292155D01*
X1643558Y292207D01*
X1643827Y292155D01*
X1644057Y291948D01*
X1644172Y291587D01*
Y290140D01*
G01X1634220Y296140D02*
X1633913Y296192D01*
X1633645Y296398D01*
X1633415Y296708D01*
X1633262Y297070D01*
X1633185Y297483D01*
Y297897D01*
X1633262Y298310D01*
X1633415Y298672D01*
X1633645Y298982D01*
X1633913Y299188D01*
X1634220Y299240D01*
X1634527Y299188D01*
X1634795Y298982D01*
X1635025Y298672D01*
X1635178Y298310D01*
X1635255Y297897D01*
Y297483D01*
X1635178Y297070D01*
X1635025Y296708D01*
X1634795Y296398D01*
X1634527Y296192D01*
X1634220Y296140D01*
G01X1636630Y295107D02*
Y298207D01*
G01Y297742D02*
X1636822Y298000D01*
X1637013Y298155D01*
X1637320Y298207D01*
X1637588Y298155D01*
X1637857Y297897D01*
X1637972Y297535D01*
X1638010Y297173D01*
X1637972Y296812D01*
X1637857Y296450D01*
X1637627Y296243D01*
X1637320Y296140D01*
X1637052Y296192D01*
X1636783Y296347D01*
X1636630Y296553D01*
G01X1639845Y297535D02*
X1641072D01*
X1640957Y297897D01*
X1640765Y298103D01*
X1640497Y298207D01*
X1640228Y298155D01*
X1639998Y298000D01*
X1639845Y297638D01*
X1639768Y297328D01*
Y297018D01*
X1639845Y296708D01*
X1640037Y296398D01*
X1640267Y296192D01*
X1640535Y296140D01*
X1640803Y296243D01*
X1641072Y296553D01*
G01X1642868Y296140D02*
Y298207D01*
G01Y297690D02*
X1643022Y297948D01*
X1643252Y298155D01*
X1643558Y298207D01*
X1643827Y298155D01*
X1644057Y297948D01*
X1644172Y297587D01*
Y296140D01*
G01X1634220Y302140D02*
X1633913Y302192D01*
X1633645Y302398D01*
X1633415Y302708D01*
X1633262Y303070D01*
X1633185Y303483D01*
Y303897D01*
X1633262Y304310D01*
X1633415Y304672D01*
X1633645Y304982D01*
X1633913Y305188D01*
X1634220Y305240D01*
X1634527Y305188D01*
X1634795Y304982D01*
X1635025Y304672D01*
X1635178Y304310D01*
X1635255Y303897D01*
Y303483D01*
X1635178Y303070D01*
X1635025Y302708D01*
X1634795Y302398D01*
X1634527Y302192D01*
X1634220Y302140D01*
G01X1636630Y301107D02*
Y304207D01*
G01Y303742D02*
X1636822Y304000D01*
X1637013Y304155D01*
X1637320Y304207D01*
X1637588Y304155D01*
X1637857Y303897D01*
X1637972Y303535D01*
X1638010Y303173D01*
X1637972Y302812D01*
X1637857Y302450D01*
X1637627Y302243D01*
X1637320Y302140D01*
X1637052Y302192D01*
X1636783Y302347D01*
X1636630Y302553D01*
G01X1639845Y303535D02*
X1641072D01*
X1640957Y303897D01*
X1640765Y304103D01*
X1640497Y304207D01*
X1640228Y304155D01*
X1639998Y304000D01*
X1639845Y303638D01*
X1639768Y303328D01*
Y303018D01*
X1639845Y302708D01*
X1640037Y302398D01*
X1640267Y302192D01*
X1640535Y302140D01*
X1640803Y302243D01*
X1641072Y302553D01*
G01X1642868Y302140D02*
Y304207D01*
G01Y303690D02*
X1643022Y303948D01*
X1643252Y304155D01*
X1643558Y304207D01*
X1643827Y304155D01*
X1644057Y303948D01*
X1644172Y303587D01*
Y302140D01*
G01X1632845Y313180D02*
X1633152Y312922D01*
X1633497Y312767D01*
X1633803D01*
X1634110Y312922D01*
X1634340Y313180D01*
X1634455Y313542D01*
X1634378Y313904D01*
X1634187Y314214D01*
X1633842Y314420D01*
X1633382Y314524D01*
X1633113Y314730D01*
X1632998Y315092D01*
X1633075Y315454D01*
X1633267Y315712D01*
X1633535Y315867D01*
X1633803D01*
X1634072Y315764D01*
X1634302Y315505D01*
G01X1636098Y312767D02*
Y315867D01*
G01Y314369D02*
X1636290Y314627D01*
X1636482Y314782D01*
X1636788Y314834D01*
X1637018Y314782D01*
X1637287Y314575D01*
X1637402Y314265D01*
Y312767D01*
G01X1639850D02*
X1639620Y312819D01*
X1639390Y313025D01*
X1639237Y313387D01*
X1639160Y313800D01*
X1639237Y314214D01*
X1639390Y314575D01*
X1639620Y314782D01*
X1639850Y314834D01*
X1640080Y314782D01*
X1640310Y314575D01*
X1640463Y314214D01*
X1640502Y313800D01*
X1640463Y313387D01*
X1640310Y313025D01*
X1640080Y312819D01*
X1639850Y312767D01*
G01X1642413D02*
Y314834D01*
G01Y314420D02*
X1642605Y314627D01*
X1642797Y314782D01*
X1643065Y314834D01*
X1643257Y314782D01*
X1643487Y314627D01*
G01X1646050Y315867D02*
Y312767D01*
G01X1645513Y314834D02*
X1646587D01*
G01X1633608Y307334D02*
X1633225Y307850D01*
X1633033Y308367D01*
Y310434D01*
X1633225Y310950D01*
X1633608Y311467D01*
G01X1636900Y308367D02*
Y311467D01*
X1636440Y310847D01*
G01Y308367D02*
X1637360D01*
G01X1639502Y309400D02*
X1640498D01*
G01X1642372Y310950D02*
X1642602Y311260D01*
X1642870Y311415D01*
X1643177Y311467D01*
X1643560Y311364D01*
X1643828Y311105D01*
X1643905Y310795D01*
X1643867Y310485D01*
X1643713Y310227D01*
X1642947Y309710D01*
X1642602Y309349D01*
X1642372Y308832D01*
X1642295Y308367D01*
X1643905D01*
G01X1646392Y307334D02*
X1646775Y307850D01*
X1646967Y308367D01*
Y310434D01*
X1646775Y310950D01*
X1646392Y311467D01*
G01X1633057Y318850D02*
Y321950D01*
X1633823D01*
X1634130Y321795D01*
X1634360Y321588D01*
X1634552Y321278D01*
X1634705Y320917D01*
X1634743Y320400D01*
X1634705Y319883D01*
X1634552Y319522D01*
X1634360Y319212D01*
X1634130Y319005D01*
X1633823Y318850D01*
X1633057D01*
G01X1637000Y320917D02*
Y318850D01*
G01Y321743D02*
X1636923Y321795D01*
Y321898D01*
X1637000Y321950D01*
X1637077Y321898D01*
Y321795D01*
X1637000Y321743D01*
G01X1639525Y319212D02*
X1639717Y319005D01*
X1639985Y318850D01*
X1640215D01*
X1640445Y318953D01*
X1640598Y319108D01*
X1640675Y319315D01*
X1640637Y319625D01*
X1640483Y319780D01*
X1639793Y320090D01*
X1639640Y320452D01*
X1639717Y320710D01*
X1639870Y320865D01*
X1640100Y320917D01*
X1640330Y320865D01*
X1640560Y320710D01*
G01X1643890Y318850D02*
Y320917D01*
G01Y320555D02*
X1643737Y320762D01*
X1643507Y320865D01*
X1643238Y320917D01*
X1642970Y320813D01*
X1642740Y320607D01*
X1642587Y320297D01*
X1642510Y319883D01*
X1642587Y319470D01*
X1642740Y319160D01*
X1642970Y318953D01*
X1643238Y318850D01*
X1643507Y318902D01*
X1643737Y319057D01*
X1643890Y319263D01*
G01X1645610Y318850D02*
Y321950D01*
G01Y320400D02*
X1645802Y320710D01*
X1646032Y320865D01*
X1646262Y320917D01*
X1646607Y320813D01*
X1646837Y320607D01*
X1646990Y320245D01*
Y319832D01*
X1646913Y319418D01*
X1646760Y319108D01*
X1646492Y318902D01*
X1646262Y318850D01*
X1646032Y318902D01*
X1645802Y319057D01*
X1645610Y319315D01*
G01X1649400Y318850D02*
Y321950D01*
G01X1651925Y320245D02*
X1653152D01*
X1653037Y320607D01*
X1652845Y320813D01*
X1652577Y320917D01*
X1652308Y320865D01*
X1652078Y320710D01*
X1651925Y320348D01*
X1651848Y320038D01*
Y319728D01*
X1651925Y319418D01*
X1652117Y319108D01*
X1652347Y318902D01*
X1652615Y318850D01*
X1652883Y318953D01*
X1653152Y319263D01*
G01X1628343Y417552D02*
Y420652D01*
X1629263D01*
X1629570Y420497D01*
X1629800Y420135D01*
X1629877Y419722D01*
X1629800Y419309D01*
X1629608Y418999D01*
X1629263Y418844D01*
X1628343D01*
G01X1631367Y420652D02*
Y418430D01*
X1631520Y417965D01*
X1631827Y417655D01*
X1632210Y417552D01*
X1632593Y417655D01*
X1632900Y417965D01*
X1633053Y418430D01*
Y420652D01*
G01X1634582Y420135D02*
X1634812Y420445D01*
X1635080Y420600D01*
X1635387Y420652D01*
X1635770Y420549D01*
X1636038Y420290D01*
X1636115Y419980D01*
X1636077Y419670D01*
X1635923Y419412D01*
X1635157Y418895D01*
X1634812Y418534D01*
X1634582Y418017D01*
X1634505Y417552D01*
X1636115D01*
G01X1638410Y420652D02*
X1638103Y420549D01*
X1637873Y420290D01*
X1637720Y419980D01*
X1637605Y419567D01*
X1637567Y419102D01*
X1637605Y418637D01*
X1637720Y418224D01*
X1637873Y417914D01*
X1638103Y417655D01*
X1638410Y417552D01*
X1638717Y417655D01*
X1638947Y417914D01*
X1639100Y418224D01*
X1639215Y418637D01*
X1639253Y419102D01*
X1639215Y419567D01*
X1639100Y419980D01*
X1638947Y420290D01*
X1638717Y420549D01*
X1638410Y420652D01*
G01X1640667Y418017D02*
X1640897Y417759D01*
X1641165Y417604D01*
X1641510Y417552D01*
X1641855Y417655D01*
X1642123Y417862D01*
X1642315Y418224D01*
X1642353Y418637D01*
X1642277Y419050D01*
X1642085Y419309D01*
X1641817Y419515D01*
X1641548Y419567D01*
X1641280Y419515D01*
X1640935Y419309D01*
X1641050Y420652D01*
X1642085D01*
G01X1633442Y595984D02*
Y590036D01*
G01X1637521Y594563D02*
X1640120D01*
G01X1637521Y597634D02*
Y594563D01*
G01Y610705D02*
Y607634D01*
G01X1633442Y615232D02*
Y609284D01*
G01X1635081Y622875D02*
Y626075D01*
G01X1641281Y622875D02*
X1635081D01*
G01X1640120Y610705D02*
X1637521D01*
G01X1628622Y628684D02*
X1626022D01*
G01D02*
Y629477D01*
G01X1635081Y626075D02*
X1641281D01*
G01X1635233Y648370D02*
X1636931D01*
G01X1626022Y647577D02*
Y648370D01*
G01D02*
X1628622D01*
G01X1633982Y654201D02*
X1640182D01*
G01X1633982Y651001D02*
Y654201D01*
G01X1640182Y651001D02*
X1633982D01*
G01X1628622Y662684D02*
X1626022D01*
G01D02*
Y663477D01*
G01X1635081Y660075D02*
X1641281D01*
G01X1635081Y656875D02*
Y660075D01*
G01X1641281Y656875D02*
X1635081D01*
G01X1635233Y682370D02*
X1636931D01*
G01X1626022Y681577D02*
Y682370D01*
G01D02*
X1628622D01*
G01X1633982Y688201D02*
X1640182D01*
G01X1633982Y685001D02*
Y688201D01*
G01X1640182Y685001D02*
X1633982D01*
G01X1626022Y696684D02*
Y697477D01*
G01X1628622Y696684D02*
X1626022D01*
G01X1635081Y694075D02*
X1641281D01*
G01X1635081Y690875D02*
Y694075D01*
G01X1641281Y690875D02*
X1635081D01*
G01X1626022Y716370D02*
X1628622D01*
G01X1626022Y715577D02*
Y716370D01*
G01X1635233D02*
X1636931D01*
G01X1626367Y1335007D02*
Y718932D01*
G01X1633982Y719001D02*
Y722201D01*
G01X1640182Y719001D02*
X1633982D01*
G01X1651957Y732644D02*
X1626367D01*
G01X1633982Y722201D02*
X1640182D01*
G01X1651957Y1299574D02*
X1626367D01*
G01X1625045Y1336996D02*
X1625237Y1336686D01*
X1625467Y1336479D01*
X1625735Y1336376D01*
X1626042Y1336479D01*
X1626272Y1336686D01*
X1626502Y1336996D01*
X1626579Y1337409D01*
Y1339476D01*
G01X1628260Y1336738D02*
X1628529Y1336479D01*
X1628835Y1336376D01*
X1629142Y1336479D01*
X1629410Y1336789D01*
X1629602Y1337254D01*
X1629679Y1337719D01*
Y1338288D01*
X1629602Y1338753D01*
X1629410Y1339166D01*
X1629180Y1339373D01*
X1628912Y1339476D01*
X1628605Y1339373D01*
X1628375Y1339166D01*
X1628222Y1338856D01*
X1628145Y1338443D01*
X1628222Y1338081D01*
X1628414Y1337719D01*
X1628644Y1337513D01*
X1628912Y1337461D01*
X1629219Y1337564D01*
X1629449Y1337823D01*
X1629679Y1338288D01*
G01X1651957Y1335007D02*
X1626367D01*
G01X1645086Y1358311D02*
G03I-10827J0D01*
G01X1629662Y1371311D02*
X1623698D01*
G01D02*
Y1390996D01*
G01X1645086Y1358311D02*
X1623432D01*
G01X1623698Y1390996D02*
Y1410681D01*
G01X1628584Y1413731D02*
Y1416331D01*
G01X1629377Y1413731D02*
X1628584D01*
G01X1623698Y1410681D02*
X1629612D01*
G01X1628584Y1422942D02*
Y1424640D01*
G01Y1437353D02*
X1629592D01*
G01X1628584Y1435499D02*
Y1437353D01*
G01X1625953Y1427891D02*
Y1421691D01*
G01Y1438391D02*
Y1432191D01*
G01X1625991Y1446680D02*
X1629191D01*
G01X1625991Y1440480D02*
Y1446680D01*
G01X1629191Y1440480D02*
X1625991D01*
G01X1629191Y1446680D02*
Y1440480D01*
G01X1630243Y1444194D02*
Y1447394D01*
G01X1636443Y1444194D02*
X1630243D01*
G01X1636443Y1447394D02*
Y1444194D01*
G01X1630243Y1447394D02*
X1636443D01*
G01X1637792Y1469164D02*
Y1472572D01*
G01X1655508Y1454856D02*
X1637792D01*
G01D02*
Y1458264D01*
G01Y1472572D02*
X1655508D01*
G01X1626683Y1653152D02*
X1626951Y1653204D01*
X1627258Y1653359D01*
X1627450Y1653617D01*
X1627526Y1653979D01*
X1627450Y1654340D01*
X1627220Y1654650D01*
X1626875Y1654805D01*
X1626491D01*
X1626261Y1654909D01*
X1626070Y1655167D01*
X1625993Y1655529D01*
X1626108Y1655890D01*
X1626376Y1656149D01*
X1626683Y1656252D01*
X1626990Y1656149D01*
X1627258Y1655890D01*
X1627373Y1655529D01*
X1627296Y1655167D01*
X1627105Y1654909D01*
X1626875Y1654805D01*
X1626491D01*
X1626146Y1654650D01*
X1625916Y1654340D01*
X1625840Y1653979D01*
X1625916Y1653617D01*
X1626108Y1653359D01*
X1626415Y1653204D01*
X1626683Y1653152D01*
G01X1631496Y1657834D02*
Y1769645D01*
G01X1641134Y1670099D02*
X1633634D01*
Y1672339D01*
X1634009Y1673086D01*
X1634884Y1673646D01*
X1635884Y1673833D01*
X1636884Y1673646D01*
X1637634Y1673179D01*
X1638009Y1672339D01*
Y1670099D01*
G01X1641134Y1677599D02*
X1633634D01*
Y1679933D01*
X1634009Y1680679D01*
X1634509Y1681146D01*
X1635509Y1681333D01*
X1636509Y1681146D01*
X1637134Y1680586D01*
X1637509Y1679933D01*
Y1677599D01*
G01Y1679933D02*
X1641134Y1681333D01*
G01Y1688833D02*
Y1685099D01*
X1633634D01*
Y1688833D01*
G01X1637259Y1687339D02*
Y1685099D01*
G01X1640134Y1692506D02*
X1640759Y1693253D01*
X1641134Y1694093D01*
Y1694839D01*
X1640759Y1695586D01*
X1640134Y1696146D01*
X1639259Y1696426D01*
X1638384Y1696239D01*
X1637634Y1695773D01*
X1637134Y1694933D01*
X1636884Y1693813D01*
X1636384Y1693159D01*
X1635509Y1692879D01*
X1634634Y1693066D01*
X1634009Y1693533D01*
X1633634Y1694186D01*
Y1694839D01*
X1633884Y1695493D01*
X1634509Y1696053D01*
G01X1640134Y1700006D02*
X1640759Y1700753D01*
X1641134Y1701593D01*
Y1702339D01*
X1640759Y1703086D01*
X1640134Y1703646D01*
X1639259Y1703926D01*
X1638384Y1703739D01*
X1637634Y1703273D01*
X1637134Y1702433D01*
X1636884Y1701313D01*
X1636384Y1700659D01*
X1635509Y1700379D01*
X1634634Y1700566D01*
X1634009Y1701033D01*
X1633634Y1701686D01*
Y1702339D01*
X1633884Y1702993D01*
X1634509Y1703553D01*
G01X1638634Y1708253D02*
Y1710679D01*
G01X1641134Y1715193D02*
X1633634D01*
Y1718739D01*
G01X1637259Y1717433D02*
Y1715193D01*
G01X1633634Y1723346D02*
Y1725586D01*
G01Y1724466D02*
X1641134D01*
G01Y1723346D02*
Y1725586D01*
G01X1633634Y1731966D02*
X1641134D01*
G01X1633634Y1729819D02*
Y1734113D01*
G01X1653221Y51096D02*
X1672048D01*
G01X1644924D02*
X1649201D01*
G01X1668631Y43779D02*
X1655431D01*
G01X1655897Y172178D02*
Y175278D01*
X1656663D01*
X1656970Y175123D01*
X1657200Y174916D01*
X1657392Y174606D01*
X1657545Y174245D01*
X1657583Y173728D01*
X1657545Y173211D01*
X1657392Y172850D01*
X1657200Y172540D01*
X1656970Y172333D01*
X1656663Y172178D01*
X1655897D01*
G01X1659763D02*
X1659840Y172850D01*
X1659955Y173418D01*
X1660108Y173935D01*
X1660300Y174503D01*
X1660607Y175278D01*
X1659073D01*
G01X1654730Y189487D02*
Y177013D01*
G01D02*
X1666542D01*
G01X1640007Y177162D02*
Y174940D01*
X1640160Y174475D01*
X1640467Y174165D01*
X1640850Y174062D01*
X1641233Y174165D01*
X1641540Y174475D01*
X1641693Y174940D01*
Y177162D01*
G01X1643298Y174424D02*
X1643567Y174165D01*
X1643873Y174062D01*
X1644180Y174165D01*
X1644448Y174475D01*
X1644640Y174940D01*
X1644717Y175405D01*
Y175974D01*
X1644640Y176439D01*
X1644448Y176852D01*
X1644218Y177059D01*
X1643950Y177162D01*
X1643643Y177059D01*
X1643413Y176852D01*
X1643260Y176542D01*
X1643183Y176129D01*
X1643260Y175767D01*
X1643452Y175405D01*
X1643682Y175199D01*
X1643950Y175147D01*
X1644257Y175250D01*
X1644487Y175509D01*
X1644717Y175974D01*
G01X1646398Y174424D02*
X1646667Y174165D01*
X1646973Y174062D01*
X1647280Y174165D01*
X1647548Y174475D01*
X1647740Y174940D01*
X1647817Y175405D01*
Y175974D01*
X1647740Y176439D01*
X1647548Y176852D01*
X1647318Y177059D01*
X1647050Y177162D01*
X1646743Y177059D01*
X1646513Y176852D01*
X1646360Y176542D01*
X1646283Y176129D01*
X1646360Y175767D01*
X1646552Y175405D01*
X1646782Y175199D01*
X1647050Y175147D01*
X1647357Y175250D01*
X1647587Y175509D01*
X1647817Y175974D01*
G01X1651130Y198688D02*
Y183452D01*
G01X1646555Y182060D02*
Y178860D01*
G01X1640355Y182060D02*
X1646555D01*
G01X1640355Y178860D02*
Y182060D01*
G01X1646555Y178860D02*
X1640355D01*
G01X1666542Y189487D02*
X1654730D01*
G01X1668438Y211286D02*
Y199474D01*
X1654582D01*
Y211286D01*
X1668438D01*
G01X1642760Y201140D02*
Y207340D01*
X1645960D01*
Y201140D01*
X1642760D01*
G01X1646800Y201130D02*
Y207330D01*
X1650000D01*
Y201130D01*
X1646800D01*
G01X1654317Y215647D02*
Y213425D01*
X1654470Y212960D01*
X1654777Y212650D01*
X1655160Y212547D01*
X1655543Y212650D01*
X1655850Y212960D01*
X1656003Y213425D01*
Y215647D01*
G01X1657417Y213167D02*
X1657647Y212805D01*
X1657953Y212599D01*
X1658298Y212547D01*
X1658605Y212599D01*
X1658912Y212857D01*
X1659103Y213167D01*
X1659142Y213477D01*
X1659065Y213839D01*
X1658797Y214097D01*
X1658528Y214200D01*
X1658183D01*
G01X1658528D02*
X1658758Y214355D01*
X1658950Y214614D01*
X1659027Y214924D01*
X1658950Y215234D01*
X1658758Y215492D01*
X1658413Y215647D01*
X1658068Y215595D01*
X1657723Y215389D01*
G01X1660517Y213167D02*
X1660747Y212805D01*
X1661053Y212599D01*
X1661398Y212547D01*
X1661705Y212599D01*
X1662012Y212857D01*
X1662203Y213167D01*
X1662242Y213477D01*
X1662165Y213839D01*
X1661897Y214097D01*
X1661628Y214200D01*
X1661283D01*
G01X1661628D02*
X1661858Y214355D01*
X1662050Y214614D01*
X1662127Y214924D01*
X1662050Y215234D01*
X1661858Y215492D01*
X1661513Y215647D01*
X1661168Y215595D01*
X1660823Y215389D01*
G01X1664460Y215647D02*
X1664153Y215544D01*
X1663923Y215285D01*
X1663770Y214975D01*
X1663655Y214562D01*
X1663617Y214097D01*
X1663655Y213632D01*
X1663770Y213219D01*
X1663923Y212909D01*
X1664153Y212650D01*
X1664460Y212547D01*
X1664767Y212650D01*
X1664997Y212909D01*
X1665150Y213219D01*
X1665265Y213632D01*
X1665303Y214097D01*
X1665265Y214562D01*
X1665150Y214975D01*
X1664997Y215285D01*
X1664767Y215544D01*
X1664460Y215647D01*
G01X1651926Y373155D02*
Y376255D01*
X1652846D01*
X1653153Y376100D01*
X1653383Y375738D01*
X1653460Y375325D01*
X1653383Y374912D01*
X1653191Y374602D01*
X1652846Y374447D01*
X1651926D01*
G01X1654950Y373155D02*
Y376255D01*
X1655716D01*
X1656023Y376100D01*
X1656253Y375893D01*
X1656445Y375583D01*
X1656598Y375222D01*
X1656636Y374705D01*
X1656598Y374188D01*
X1656445Y373827D01*
X1656253Y373517D01*
X1656023Y373310D01*
X1655716Y373155D01*
X1654950D01*
G01X1658893D02*
Y376255D01*
X1658433Y375635D01*
G01Y373155D02*
X1659353D01*
G01X1661993Y376255D02*
X1661686Y376152D01*
X1661456Y375893D01*
X1661303Y375583D01*
X1661188Y375170D01*
X1661150Y374705D01*
X1661188Y374240D01*
X1661303Y373827D01*
X1661456Y373517D01*
X1661686Y373258D01*
X1661993Y373155D01*
X1662300Y373258D01*
X1662530Y373517D01*
X1662683Y373827D01*
X1662798Y374240D01*
X1662836Y374705D01*
X1662798Y375170D01*
X1662683Y375583D01*
X1662530Y375893D01*
X1662300Y376152D01*
X1661993Y376255D01*
G01X1664250Y373775D02*
X1664480Y373413D01*
X1664786Y373207D01*
X1665131Y373155D01*
X1665438Y373207D01*
X1665745Y373465D01*
X1665936Y373775D01*
X1665975Y374085D01*
X1665898Y374447D01*
X1665630Y374705D01*
X1665361Y374808D01*
X1665016D01*
G01X1665361D02*
X1665591Y374963D01*
X1665783Y375222D01*
X1665860Y375532D01*
X1665783Y375842D01*
X1665591Y376100D01*
X1665246Y376255D01*
X1664901Y376203D01*
X1664556Y375997D01*
G01X1646846Y385198D02*
X1649086D01*
G01X1647873Y386823D02*
Y383573D01*
G01X1650487Y379850D02*
Y391346D01*
G01X1680046Y379850D02*
X1650487D01*
G01Y391346D02*
X1680046D01*
G01X1654210Y395602D02*
X1651010D01*
G01X1654210Y401802D02*
Y395602D01*
G01X1651010D02*
Y401802D01*
G01X1649210Y415802D02*
Y412602D01*
G01X1643010D02*
Y415802D01*
G01X1649210Y412602D02*
X1643010D01*
G01X1650729Y408315D02*
Y420089D01*
G01X1660491Y408315D02*
X1650729D01*
G01X1651010Y401802D02*
X1654210D01*
G01X1648710Y427102D02*
X1645510D01*
G01X1648710Y433302D02*
Y427102D01*
G01X1645510D02*
Y433302D01*
G01X1643010Y415802D02*
X1649210D01*
G01X1650729Y420089D02*
X1660491D01*
G01X1652510Y427102D02*
Y433302D01*
G01X1655710Y427102D02*
X1652510D01*
G01X1655710Y433302D02*
Y427102D01*
G01X1645510Y433302D02*
X1648710D01*
G01X1652510D02*
X1655710D01*
G01X1653129Y526471D02*
Y529671D01*
G01X1659329Y526471D02*
X1653129D01*
G01Y525671D02*
X1659329D01*
G01X1653129Y522471D02*
Y525671D01*
G01X1659329Y522471D02*
X1653129D01*
G01X1659280Y518940D02*
X1653080D01*
Y522140D01*
X1659280D01*
Y518940D01*
G01X1653129Y529671D02*
X1659329D01*
G01X1653129Y533671D02*
X1659329D01*
G01X1653129Y530471D02*
Y533671D01*
G01X1659329Y530471D02*
X1653129D01*
G01Y541671D02*
X1659329D01*
G01X1653129Y538471D02*
Y541671D01*
G01X1659329Y538471D02*
X1653129D01*
G01Y537671D02*
X1659329D01*
G01X1653129Y534471D02*
Y537671D01*
G01X1659329Y534471D02*
X1653129D01*
G01X1650891Y553835D02*
Y547635D01*
G01D02*
X1647691D01*
G01Y553835D02*
X1650891D01*
G01X1647691Y547635D02*
Y553835D01*
G01X1653129Y543022D02*
Y546222D01*
G01X1659329Y543022D02*
X1653129D01*
G01Y546222D02*
X1659329D01*
G01X1649603Y562380D02*
Y565480D01*
X1650523D01*
X1650830Y565325D01*
X1651060Y564963D01*
X1651137Y564550D01*
X1651060Y564137D01*
X1650868Y563827D01*
X1650523Y563672D01*
X1649603D01*
G01X1652703Y563000D02*
X1652895Y562690D01*
X1653125Y562483D01*
X1653393Y562380D01*
X1653700Y562483D01*
X1653930Y562690D01*
X1654160Y563000D01*
X1654237Y563413D01*
Y565480D01*
G01X1657030Y562380D02*
Y565480D01*
X1655612Y563258D01*
X1657528D01*
G01X1658942Y563672D02*
X1659210Y564033D01*
X1659440Y564240D01*
X1659747Y564343D01*
X1660015Y564240D01*
X1660207Y564033D01*
X1660360Y563723D01*
X1660398Y563362D01*
X1660360Y563052D01*
X1660207Y562742D01*
X1659977Y562483D01*
X1659708Y562380D01*
X1659402Y562483D01*
X1659133Y562793D01*
X1658980Y563258D01*
X1658942Y563775D01*
X1659018Y564447D01*
X1659133Y564808D01*
X1659325Y565170D01*
X1659593Y565428D01*
X1659862Y565480D01*
X1660130Y565377D01*
X1660322Y565118D01*
G01X1647220Y594563D02*
X1648262D01*
G01X1655362D02*
X1657599D01*
G01X1650820Y613562D02*
X1647620D01*
G01X1650820Y619762D02*
Y613562D01*
G01X1647620Y619762D02*
X1650820D01*
G01X1647620Y613562D02*
Y619762D01*
G01X1641281Y626075D02*
Y622875D01*
G01X1645959Y610705D02*
X1644464D01*
G01X1658820Y613562D02*
X1655620D01*
G01Y619762D02*
X1658820D01*
G01X1655620Y613562D02*
Y619762D01*
G01X1654820Y613562D02*
X1651620D01*
G01X1654820Y619762D02*
Y613562D01*
G01X1651620Y619762D02*
X1654820D01*
G01X1651620Y613562D02*
Y619762D01*
G01X1647032Y616445D02*
Y613245D01*
G01X1640832Y616445D02*
X1647032D01*
G01X1640832Y613245D02*
Y616445D01*
G01X1647032Y613245D02*
X1640832D01*
G01X1649644Y629417D02*
Y628684D01*
G01D02*
X1647453D01*
G01X1652300Y633303D02*
X1658500D01*
G01X1652300Y630103D02*
Y633303D01*
G01X1658500Y630103D02*
X1652300D01*
G01X1652308Y634191D02*
Y637391D01*
G01X1658508Y634191D02*
X1652308D01*
G01Y637391D02*
X1658508D01*
G01X1647790Y648370D02*
X1649644D01*
G01D02*
Y647362D01*
G01X1640182Y654201D02*
Y651001D01*
G01X1644482D02*
Y654201D01*
G01X1650682Y651001D02*
X1644482D01*
G01X1650682Y654201D02*
Y651001D01*
G01X1644482Y654201D02*
X1650682D01*
G01X1652432Y652409D02*
Y658609D01*
G01X1655632Y652409D02*
X1652432D01*
G01X1655632Y658609D02*
Y652409D01*
G01X1652772Y651281D02*
X1658972D01*
G01X1652772Y648081D02*
Y651281D01*
G01X1658972Y648081D02*
X1652772D01*
G01X1649644Y663417D02*
Y662684D01*
G01D02*
X1647453D01*
G01X1641281Y660075D02*
Y656875D01*
G01X1652432Y658609D02*
X1655632D01*
G01X1652300Y667303D02*
X1658500D01*
G01X1652300Y664103D02*
Y667303D01*
G01X1658500Y664103D02*
X1652300D01*
G01X1652308Y668191D02*
Y671391D01*
G01X1658508Y668191D02*
X1652308D01*
G01Y671391D02*
X1658508D01*
G01X1647790Y682370D02*
X1649644D01*
G01D02*
Y681362D01*
G01X1652772Y685281D02*
X1658972D01*
G01X1652772Y682081D02*
Y685281D01*
G01X1658972Y682081D02*
X1652772D01*
G01X1652432Y686409D02*
Y692609D01*
G01X1655632Y686409D02*
X1652432D01*
G01X1655632Y692609D02*
Y686409D01*
G01X1644482Y685001D02*
Y688201D01*
G01X1650682Y685001D02*
X1644482D01*
G01X1650682Y688201D02*
Y685001D01*
G01X1644482Y688201D02*
X1650682D01*
G01X1640182D02*
Y685001D01*
G01X1649644Y696684D02*
X1647453D01*
G01X1649644Y697417D02*
Y696684D01*
G01X1651957Y697211D02*
Y726182D01*
G01X1650910Y697211D02*
X1651957D01*
G01X1652432Y692609D02*
X1655632D01*
G01X1641281Y694075D02*
Y690875D01*
G01X1652300Y701303D02*
X1658500D01*
G01X1652300Y698103D02*
Y701303D01*
G01X1658500Y698103D02*
X1652300D01*
G01X1652308Y702191D02*
Y705391D01*
G01X1658508Y702191D02*
X1652308D01*
G01Y705391D02*
X1658508D01*
G01X1649644Y716370D02*
Y715362D01*
G01X1647790Y716370D02*
X1649644D01*
G01X1644482Y719001D02*
Y722201D01*
G01X1650682Y719001D02*
X1644482D01*
G01X1650682Y722201D02*
Y719001D01*
G01X1652772Y719281D02*
X1658972D01*
G01X1652772Y716081D02*
Y719281D01*
G01X1658972Y716081D02*
X1652772D01*
G01X1640182Y722201D02*
Y719001D01*
G01X1651957Y732112D02*
Y1335007D01*
G01X1644482Y722201D02*
X1650682D01*
G01X1654745Y1336996D02*
X1654937Y1336686D01*
X1655167Y1336479D01*
X1655435Y1336376D01*
X1655742Y1336479D01*
X1655972Y1336686D01*
X1656202Y1336996D01*
X1656279Y1337409D01*
Y1339476D01*
G01X1658612Y1336376D02*
Y1339476D01*
X1658152Y1338856D01*
G01Y1336376D02*
X1659072D01*
G01X1660984Y1338959D02*
X1661214Y1339269D01*
X1661482Y1339424D01*
X1661789Y1339476D01*
X1662172Y1339373D01*
X1662440Y1339114D01*
X1662517Y1338804D01*
X1662479Y1338494D01*
X1662325Y1338236D01*
X1661559Y1337719D01*
X1661214Y1337358D01*
X1660984Y1336841D01*
X1660907Y1336376D01*
X1662517D01*
G01X1669459Y1358336D02*
G03I-10827J0D01*
G01X1653226Y1410681D02*
Y1371311D01*
G01D02*
X1647312D01*
G01X1669459Y1358336D02*
X1647805D01*
G01X1648270Y1413731D02*
X1647477D01*
G01X1648270Y1416331D02*
Y1413731D01*
G01X1647312Y1410681D02*
X1653226D01*
G01X1648270Y1437353D02*
Y1435162D01*
G01X1647537Y1437353D02*
X1648270D01*
G01X1650887Y1428911D02*
X1654087D01*
G01X1650887Y1422711D02*
Y1428911D01*
G01X1654087Y1422711D02*
X1650887D01*
G01X1654087Y1428911D02*
Y1422711D01*
G01X1654991Y1428911D02*
X1658191D01*
G01X1654991Y1422711D02*
Y1428911D01*
G01X1658191Y1422711D02*
X1654991D01*
G01X1649328Y1446536D02*
X1661328D01*
G01X1649328Y1440536D02*
Y1446536D01*
G01X1661328Y1440536D02*
X1649328D01*
G01X1643858Y1446766D02*
X1647058D01*
G01X1643858Y1440566D02*
Y1446766D01*
G01X1647058Y1440566D02*
X1643858D01*
G01X1647058Y1446766D02*
Y1440566D01*
G01X1643016D02*
X1639816D01*
G01X1643016Y1446766D02*
Y1440566D01*
G01X1639816Y1446766D02*
X1643016D01*
G01X1639816Y1440566D02*
Y1446766D01*
G01X1655508Y1458264D02*
Y1454856D01*
G01Y1472572D02*
Y1469164D01*
G01X1642623Y1479951D02*
Y1483051D01*
X1643543D01*
X1643850Y1482896D01*
X1644080Y1482534D01*
X1644157Y1482121D01*
X1644080Y1481708D01*
X1643888Y1481398D01*
X1643543Y1481243D01*
X1642623D01*
G01X1645723Y1483051D02*
Y1479951D01*
X1647257D01*
G01X1649590D02*
Y1483051D01*
X1649130Y1482431D01*
G01Y1479951D02*
X1650050D01*
G01X1652690Y1483051D02*
X1652383Y1482948D01*
X1652153Y1482689D01*
X1652000Y1482379D01*
X1651885Y1481966D01*
X1651847Y1481501D01*
X1651885Y1481036D01*
X1652000Y1480623D01*
X1652153Y1480313D01*
X1652383Y1480054D01*
X1652690Y1479951D01*
X1652997Y1480054D01*
X1653227Y1480313D01*
X1653380Y1480623D01*
X1653495Y1481036D01*
X1653533Y1481501D01*
X1653495Y1481966D01*
X1653380Y1482379D01*
X1653227Y1482689D01*
X1652997Y1482948D01*
X1652690Y1483051D01*
G01X1655790Y1479951D02*
Y1483051D01*
X1655330Y1482431D01*
G01Y1479951D02*
X1656250D01*
G01X1641507Y1475095D02*
Y1478295D01*
G01X1647707Y1475095D02*
X1641507D01*
G01X1647707Y1478295D02*
Y1475095D01*
G01X1641507Y1478295D02*
X1647707D01*
G01X1643307Y1781456D02*
Y1646023D01*
G01X1669530Y169962D02*
X1665700Y166662D01*
G01D02*
Y173732D01*
G01D02*
X1669530Y169962D01*
G01X1666542Y177013D02*
Y189487D01*
G01X1665045Y197535D02*
Y194335D01*
G01X1658845Y197535D02*
X1665045D01*
G01X1658845Y194335D02*
Y197535D01*
G01X1665045Y194335D02*
X1658845D01*
G01X1676280Y200070D02*
X1670080D01*
Y203270D01*
X1676280D01*
Y200070D01*
G01X1658010Y395602D02*
Y401802D01*
G01X1661210Y395602D02*
X1658010D01*
G01X1661210Y401802D02*
Y395602D01*
G01X1662010D02*
Y401802D01*
G01X1665210Y395602D02*
X1662010D01*
G01X1665210Y401802D02*
Y395602D01*
G01X1664570Y411832D02*
Y423832D01*
G01X1670570Y411832D02*
X1664570D01*
G01X1670570Y423832D02*
Y411832D01*
G01X1658010Y401802D02*
X1661210D01*
G01X1660491Y420089D02*
Y408315D01*
G01X1662010Y401802D02*
X1665210D01*
G01X1664570Y423832D02*
X1670570D01*
G01X1662710Y427102D02*
X1659510D01*
G01X1662710Y433302D02*
Y427102D01*
G01X1659510D02*
Y433302D01*
G01D02*
X1662710D01*
G01X1669492Y478827D02*
Y481927D01*
X1670412D01*
X1670719Y481772D01*
X1670949Y481410D01*
X1671026Y480997D01*
X1670949Y480584D01*
X1670757Y480274D01*
X1670412Y480119D01*
X1669492D01*
G01X1672516Y481927D02*
Y479705D01*
X1672669Y479240D01*
X1672976Y478930D01*
X1673359Y478827D01*
X1673742Y478930D01*
X1674049Y479240D01*
X1674202Y479705D01*
Y481927D01*
G01X1675616Y479447D02*
X1675846Y479085D01*
X1676152Y478879D01*
X1676497Y478827D01*
X1676804Y478879D01*
X1677111Y479137D01*
X1677302Y479447D01*
X1677341Y479757D01*
X1677264Y480119D01*
X1676996Y480377D01*
X1676727Y480480D01*
X1676382D01*
G01X1676727D02*
X1676957Y480635D01*
X1677149Y480894D01*
X1677226Y481204D01*
X1677149Y481514D01*
X1676957Y481772D01*
X1676612Y481927D01*
X1676267Y481875D01*
X1675922Y481669D01*
G01X1678716Y479292D02*
X1678946Y479034D01*
X1679214Y478879D01*
X1679559Y478827D01*
X1679904Y478930D01*
X1680172Y479137D01*
X1680364Y479499D01*
X1680402Y479912D01*
X1680326Y480325D01*
X1680134Y480584D01*
X1679866Y480790D01*
X1679597Y480842D01*
X1679329Y480790D01*
X1678984Y480584D01*
X1679099Y481927D01*
X1680134D01*
G01X1659329Y529671D02*
Y526471D01*
G01Y525671D02*
Y522471D01*
G01X1661776Y522688D02*
X1664976D01*
G01X1661776Y516488D02*
Y522688D01*
G01X1664976Y516488D02*
X1661776D01*
G01X1664976Y522688D02*
Y516488D01*
G01X1665776Y522688D02*
X1668976D01*
G01X1665776Y516488D02*
Y522688D01*
G01X1668976Y516488D02*
X1665776D01*
G01X1668976Y522688D02*
Y516488D01*
G01X1672183Y515182D02*
Y518282D01*
X1673103D01*
X1673410Y518127D01*
X1673640Y517765D01*
X1673717Y517352D01*
X1673640Y516939D01*
X1673448Y516629D01*
X1673103Y516474D01*
X1672183D01*
G01X1675207Y518282D02*
Y516060D01*
X1675360Y515595D01*
X1675667Y515285D01*
X1676050Y515182D01*
X1676433Y515285D01*
X1676740Y515595D01*
X1676893Y516060D01*
Y518282D01*
G01X1678307Y515647D02*
X1678537Y515389D01*
X1678805Y515234D01*
X1679150Y515182D01*
X1679495Y515285D01*
X1679763Y515492D01*
X1679955Y515854D01*
X1679993Y516267D01*
X1679917Y516680D01*
X1679725Y516939D01*
X1679457Y517145D01*
X1679188Y517197D01*
X1678920Y517145D01*
X1678575Y516939D01*
X1678690Y518282D01*
X1679725D01*
G01X1661990Y525372D02*
Y527872D01*
X1661003Y526080D01*
X1662337D01*
G01X1663870Y527872D02*
X1663657Y527789D01*
X1663497Y527580D01*
X1663390Y527330D01*
X1663310Y526997D01*
X1663283Y526622D01*
X1663310Y526247D01*
X1663390Y525914D01*
X1663497Y525664D01*
X1663657Y525455D01*
X1663870Y525372D01*
X1664083Y525455D01*
X1664243Y525664D01*
X1664350Y525914D01*
X1664430Y526247D01*
X1664457Y526622D01*
X1664430Y526997D01*
X1664350Y527330D01*
X1664243Y527580D01*
X1664083Y527789D01*
X1663870Y527872D01*
G01X1659329Y533671D02*
Y530471D01*
G01Y541671D02*
Y538471D01*
G01Y537671D02*
Y534471D01*
G01X1668067Y527222D02*
X1666161D01*
G01D02*
Y529128D01*
G01X1664704Y529965D02*
X1661704D01*
G01X1663254Y537765D02*
X1664754D01*
G01X1666403Y551982D02*
Y548782D01*
G01X1660203D02*
Y551982D01*
G01X1666403Y548782D02*
X1660203D01*
G01Y551982D02*
X1666403D01*
G01X1671553Y549682D02*
X1671713Y549390D01*
X1671927Y549224D01*
X1672167Y549182D01*
X1672380Y549224D01*
X1672593Y549432D01*
X1672727Y549682D01*
X1672753Y549932D01*
X1672700Y550224D01*
X1672513Y550432D01*
X1672327Y550515D01*
X1672087D01*
G01X1672327D02*
X1672487Y550640D01*
X1672620Y550849D01*
X1672673Y551099D01*
X1672620Y551349D01*
X1672487Y551557D01*
X1672247Y551682D01*
X1672007Y551640D01*
X1671767Y551474D01*
G01X1674340Y551682D02*
X1674127Y551599D01*
X1673967Y551390D01*
X1673860Y551140D01*
X1673780Y550807D01*
X1673753Y550432D01*
X1673780Y550057D01*
X1673860Y549724D01*
X1673967Y549474D01*
X1674127Y549265D01*
X1674340Y549182D01*
X1674553Y549265D01*
X1674713Y549474D01*
X1674820Y549724D01*
X1674900Y550057D01*
X1674927Y550432D01*
X1674900Y550807D01*
X1674820Y551140D01*
X1674713Y551390D01*
X1674553Y551599D01*
X1674340Y551682D01*
G01X1661703Y545860D02*
X1661863Y545568D01*
X1662077Y545402D01*
X1662317Y545360D01*
X1662530Y545402D01*
X1662743Y545610D01*
X1662877Y545860D01*
X1662903Y546110D01*
X1662850Y546402D01*
X1662663Y546610D01*
X1662477Y546693D01*
X1662237D01*
G01X1662477D02*
X1662637Y546818D01*
X1662770Y547027D01*
X1662823Y547277D01*
X1662770Y547527D01*
X1662637Y547735D01*
X1662397Y547860D01*
X1662157Y547818D01*
X1661917Y547652D01*
G01X1664490Y545360D02*
Y547860D01*
X1664170Y547360D01*
G01Y545360D02*
X1664810D01*
G01X1666161Y545002D02*
Y546908D01*
G01D02*
X1668067D01*
G01X1669004Y548365D02*
Y551365D01*
G01X1656032Y555014D02*
X1659232D01*
G01X1656032Y548814D02*
Y555014D01*
G01X1659232Y548814D02*
X1656032D01*
G01X1659232Y555014D02*
Y548814D01*
G01X1659329Y546222D02*
Y543022D01*
G01X1665640Y562552D02*
X1662440D01*
G01X1665640Y568752D02*
Y562552D01*
G01X1662440Y568752D02*
X1665640D01*
G01X1662440Y562552D02*
Y568752D01*
G01X1673640Y562552D02*
X1670440D01*
G01Y568752D02*
X1673640D01*
G01X1670440Y562552D02*
Y568752D01*
G01X1669640Y562552D02*
X1666440D01*
G01X1669640Y568752D02*
Y562552D01*
G01X1666440Y568752D02*
X1669640D01*
G01X1666440Y562552D02*
Y568752D01*
G01X1668306Y581556D02*
Y593556D01*
G01X1674306Y581556D02*
X1668306D01*
G01X1664106Y590656D02*
X1667306D01*
G01X1664106Y584456D02*
Y590656D01*
G01X1667306Y584456D02*
X1664106D01*
G01X1667306Y590656D02*
Y584456D01*
G01X1659906Y590656D02*
X1663106D01*
G01X1659906Y584456D02*
Y590656D01*
G01X1663106Y584456D02*
X1659906D01*
G01X1663106Y590656D02*
Y584456D01*
G01X1668306Y593556D02*
X1674306D01*
G01X1667431Y596559D02*
Y593359D01*
G01X1661231Y596559D02*
X1667431D01*
G01X1661231Y593359D02*
Y596559D01*
G01X1667431Y593359D02*
X1661231D01*
G01X1666522Y608891D02*
Y605691D01*
G01X1660322D02*
Y608891D01*
G01X1666522Y605691D02*
X1660322D01*
G01X1657599Y594563D02*
Y595088D01*
G01X1661260Y596922D02*
Y600122D01*
G01X1667460Y596922D02*
X1661260D01*
G01X1667460Y600122D02*
Y596922D01*
G01X1661260Y600122D02*
X1667460D01*
G01X1660322Y608891D02*
X1666522D01*
G01X1659532Y618909D02*
Y625109D01*
G01X1662732Y618909D02*
X1659532D01*
G01X1662732Y625109D02*
Y618909D01*
G01X1657599Y610705D02*
X1655933D01*
G01X1657599Y608999D02*
Y610705D01*
G01X1658820Y619762D02*
Y613562D01*
G01X1662720Y618562D02*
Y612362D01*
X1659520D01*
Y618562D01*
X1662720D01*
G01X1669496Y623096D02*
X1696268D01*
G01D02*
G03I-13386J0D01*
G01X1659532Y625109D02*
X1662732D01*
G01X1658500Y633303D02*
Y630103D01*
G01X1658508Y637391D02*
Y634191D01*
G01X1656485Y640511D02*
Y646711D01*
G01X1659685Y640511D02*
X1656485D01*
G01X1659685Y646711D02*
Y640511D01*
G01X1662643Y643752D02*
Y646852D01*
X1663563D01*
X1663870Y646697D01*
X1664100Y646335D01*
X1664177Y645922D01*
X1664100Y645509D01*
X1663908Y645199D01*
X1663563Y645044D01*
X1662643D01*
G01X1665667Y646852D02*
Y644630D01*
X1665820Y644165D01*
X1666127Y643855D01*
X1666510Y643752D01*
X1666893Y643855D01*
X1667200Y644165D01*
X1667353Y644630D01*
Y646852D01*
G01X1668767Y644372D02*
X1668997Y644010D01*
X1669303Y643804D01*
X1669648Y643752D01*
X1669955Y643804D01*
X1670262Y644062D01*
X1670453Y644372D01*
X1670492Y644682D01*
X1670415Y645044D01*
X1670147Y645302D01*
X1669878Y645405D01*
X1669533D01*
G01X1669878D02*
X1670108Y645560D01*
X1670300Y645819D01*
X1670377Y646129D01*
X1670300Y646439D01*
X1670108Y646697D01*
X1669763Y646852D01*
X1669418Y646800D01*
X1669073Y646594D01*
G01X1671982Y645044D02*
X1672250Y645405D01*
X1672480Y645612D01*
X1672787Y645715D01*
X1673055Y645612D01*
X1673247Y645405D01*
X1673400Y645095D01*
X1673438Y644734D01*
X1673400Y644424D01*
X1673247Y644114D01*
X1673017Y643855D01*
X1672748Y643752D01*
X1672442Y643855D01*
X1672173Y644165D01*
X1672020Y644630D01*
X1671982Y645147D01*
X1672058Y645819D01*
X1672173Y646180D01*
X1672365Y646542D01*
X1672633Y646800D01*
X1672902Y646852D01*
X1673170Y646749D01*
X1673362Y646490D01*
G01X1658972Y651281D02*
Y648081D01*
G01X1656485Y646711D02*
X1659685D01*
G01X1658500Y667303D02*
Y664103D01*
G01X1658508Y671391D02*
Y668191D01*
G01X1696268Y674031D02*
G03I-13386J0D01*
G01X1662743Y689222D02*
Y692322D01*
X1663663D01*
X1663970Y692167D01*
X1664200Y691805D01*
X1664277Y691392D01*
X1664200Y690979D01*
X1664008Y690669D01*
X1663663Y690514D01*
X1662743D01*
G01X1665767Y692322D02*
Y690100D01*
X1665920Y689635D01*
X1666227Y689325D01*
X1666610Y689222D01*
X1666993Y689325D01*
X1667300Y689635D01*
X1667453Y690100D01*
Y692322D01*
G01X1670170Y689222D02*
Y692322D01*
X1668752Y690100D01*
X1670668D01*
G01X1671967Y689842D02*
X1672197Y689480D01*
X1672503Y689274D01*
X1672848Y689222D01*
X1673155Y689274D01*
X1673462Y689532D01*
X1673653Y689842D01*
X1673692Y690152D01*
X1673615Y690514D01*
X1673347Y690772D01*
X1673078Y690875D01*
X1672733D01*
G01X1673078D02*
X1673308Y691030D01*
X1673500Y691289D01*
X1673577Y691599D01*
X1673500Y691909D01*
X1673308Y692167D01*
X1672963Y692322D01*
X1672618Y692270D01*
X1672273Y692064D01*
G01X1674760Y688189D02*
X1677060D01*
G01X1678243Y689222D02*
Y692322D01*
X1679163D01*
X1679470Y692167D01*
X1679700Y691805D01*
X1679777Y691392D01*
X1679700Y690979D01*
X1679508Y690669D01*
X1679163Y690514D01*
X1678243D01*
G01X1682110Y692322D02*
X1681803Y692219D01*
X1681573Y691960D01*
X1681420Y691650D01*
X1681305Y691237D01*
X1681267Y690772D01*
X1681305Y690307D01*
X1681420Y689894D01*
X1681573Y689584D01*
X1681803Y689325D01*
X1682110Y689222D01*
X1682417Y689325D01*
X1682647Y689584D01*
X1682800Y689894D01*
X1682915Y690307D01*
X1682953Y690772D01*
X1682915Y691237D01*
X1682800Y691650D01*
X1682647Y691960D01*
X1682417Y692219D01*
X1682110Y692322D01*
G01X1684060Y688189D02*
X1686360D01*
G01X1688310Y689222D02*
Y692322D01*
X1687850Y691702D01*
G01Y689222D02*
X1688770D01*
G01X1658972Y685281D02*
Y682081D01*
G01X1656485Y680711D02*
X1659685D01*
G01X1656485Y674511D02*
Y680711D01*
G01X1659685Y674511D02*
X1656485D01*
G01X1659685Y680711D02*
Y674511D01*
G01X1669496Y674031D02*
X1696268D01*
G01X1656067Y697211D02*
X1681657D01*
G01X1658500Y701303D02*
Y698103D01*
G01X1658508Y705391D02*
Y702191D01*
G01X1656067Y1335007D02*
Y720702D01*
G01X1658972Y719281D02*
Y716081D01*
G01X1656485Y714711D02*
X1659685D01*
G01X1656485Y708511D02*
Y714711D01*
G01X1659685Y708511D02*
X1656485D01*
G01X1659685Y714711D02*
Y708511D01*
G01X1681657Y732644D02*
X1656067D01*
G01X1681657Y1299574D02*
X1656067D01*
G01X1681657Y1335007D02*
X1656067D01*
G01X1667762Y1371311D02*
X1661798D01*
G01D02*
Y1390996D01*
G01D02*
Y1410681D01*
G01X1666727Y1413731D02*
Y1416331D01*
G01X1667520Y1413731D02*
X1666727D01*
G01X1661798Y1410681D02*
X1667712D01*
G01X1666727Y1422942D02*
Y1424640D01*
G01Y1437353D02*
X1667735D01*
G01X1666727Y1435499D02*
Y1437353D01*
G01X1660896Y1427891D02*
X1664096D01*
G01X1660896Y1421691D02*
Y1427891D01*
G01X1664096Y1421691D02*
X1660896D01*
G01X1664096Y1427891D02*
Y1421691D01*
G01Y1432191D02*
X1660896D01*
G01X1664096Y1438391D02*
Y1432191D01*
G01X1660896D02*
Y1438391D01*
G01X1658191Y1428911D02*
Y1422711D01*
G01X1661328Y1446536D02*
Y1440536D01*
G01X1660896Y1438391D02*
X1664096D01*
G01X1664134Y1446680D02*
X1667334D01*
G01X1664134Y1440480D02*
Y1446680D01*
G01X1667334Y1440480D02*
X1664134D01*
G01X1667334Y1446680D02*
Y1440480D01*
G01X1668386Y1444194D02*
Y1447394D01*
G01X1674586Y1444194D02*
X1668386D01*
G01Y1447394D02*
X1674586D01*
G01X1688408Y1463655D02*
G03I-13386J0D01*
G01X1666998Y1498962D02*
X1673198D01*
G01X1666998Y1495762D02*
Y1498962D01*
G01X1673198Y1495762D02*
X1666998D01*
G01Y1491762D02*
Y1494962D01*
G01X1673198Y1491762D02*
X1666998D01*
G01Y1494962D02*
X1673198D01*
G01X1666998Y1499762D02*
Y1502962D01*
G01X1673198Y1499762D02*
X1666998D01*
G01Y1514462D02*
X1673198D01*
G01X1666998Y1511262D02*
Y1514462D01*
G01X1673198Y1511262D02*
X1666998D01*
G01Y1515262D02*
Y1518462D01*
G01X1673198Y1515262D02*
X1666998D01*
G01Y1518462D02*
X1673198D01*
G01X1666998Y1506962D02*
X1673198D01*
G01X1666998Y1503762D02*
Y1506962D01*
G01X1673198Y1503762D02*
X1666998D01*
G01Y1502962D02*
X1673198D01*
G01X1666998Y1532262D02*
Y1535462D01*
G01X1673198Y1532262D02*
X1666998D01*
G01Y1526462D02*
X1673198D01*
G01X1666998Y1523262D02*
Y1526462D01*
G01X1673198Y1523262D02*
X1666998D01*
G01Y1519262D02*
Y1522462D01*
G01X1673198Y1519262D02*
X1666998D01*
G01Y1522462D02*
X1673198D01*
G01X1666998Y1539462D02*
X1673198D01*
G01X1666998Y1536262D02*
Y1539462D01*
G01X1673198Y1536262D02*
X1666998D01*
G01Y1535462D02*
X1673198D01*
G01X1666998Y1544262D02*
Y1547462D01*
G01X1673198Y1544262D02*
X1666998D01*
G01Y1547462D02*
X1673198D01*
G01X1666998Y1543462D02*
X1673198D01*
G01X1666998Y1540262D02*
Y1543462D01*
G01X1673198Y1540262D02*
X1666998D01*
G01Y1555157D02*
X1673198D01*
G01X1666998Y1551957D02*
Y1555157D01*
G01X1673198Y1551957D02*
X1666998D01*
G01X1667073Y1567157D02*
X1673273D01*
G01X1667073Y1563957D02*
Y1567157D01*
G01X1673273Y1563957D02*
X1667073D01*
G01Y1559957D02*
Y1563157D01*
G01X1673273Y1559957D02*
X1667073D01*
G01Y1563157D02*
X1673273D01*
G01X1666998Y1555957D02*
Y1559157D01*
G01X1673198Y1555957D02*
X1666998D01*
G01Y1559157D02*
X1673198D01*
G01X1667073Y1579721D02*
Y1582921D01*
G01X1673273Y1579721D02*
X1667073D01*
G01Y1582921D02*
X1673273D01*
G01X1667073Y1583721D02*
Y1586921D01*
G01X1673273Y1583721D02*
X1667073D01*
G01Y1586921D02*
X1673273D01*
G01X1682004Y51096D02*
X1686472D01*
G01X1674856D02*
X1679356D01*
G01X1688103Y103599D02*
Y106699D01*
X1687643Y106079D01*
G01Y103599D02*
X1688563D01*
G01X1691663D02*
Y106699D01*
X1690245Y104477D01*
X1692161D01*
G01X1678103Y103599D02*
Y106699D01*
X1677643Y106079D01*
G01Y103599D02*
X1678563D01*
G01X1680360Y104219D02*
X1680590Y103857D01*
X1680896Y103651D01*
X1681241Y103599D01*
X1681548Y103651D01*
X1681855Y103909D01*
X1682046Y104219D01*
X1682085Y104529D01*
X1682008Y104891D01*
X1681740Y105149D01*
X1681471Y105252D01*
X1681126D01*
G01X1681471D02*
X1681701Y105407D01*
X1681893Y105666D01*
X1681970Y105976D01*
X1681893Y106286D01*
X1681701Y106544D01*
X1681356Y106699D01*
X1681011Y106647D01*
X1680666Y106441D01*
G01X1674803Y110669D02*
X1694489D01*
G01X1674803Y180669D02*
Y110669D01*
G01X1684719Y186416D02*
X1684911Y186106D01*
X1685141Y185899D01*
X1685409Y185796D01*
X1685716Y185899D01*
X1685946Y186106D01*
X1686176Y186416D01*
X1686253Y186829D01*
Y188896D01*
G01X1688586Y185796D02*
Y188896D01*
X1688126Y188276D01*
G01Y185796D02*
X1689046D01*
G01X1691686Y188896D02*
X1691379Y188793D01*
X1691149Y188534D01*
X1690996Y188224D01*
X1690881Y187811D01*
X1690843Y187346D01*
X1690881Y186881D01*
X1690996Y186468D01*
X1691149Y186158D01*
X1691379Y185899D01*
X1691686Y185796D01*
X1691993Y185899D01*
X1692223Y186158D01*
X1692376Y186468D01*
X1692491Y186881D01*
X1692529Y187346D01*
X1692491Y187811D01*
X1692376Y188224D01*
X1692223Y188534D01*
X1691993Y188793D01*
X1691686Y188896D01*
G01X1695246Y185796D02*
Y188896D01*
X1693828Y186674D01*
X1695744D01*
G01X1694489Y180669D02*
X1674803D01*
G01X1677536Y376048D02*
X1675110D01*
G01X1680046Y391346D02*
Y379850D01*
G01X1712071Y379616D02*
X1680271D01*
Y393416D01*
X1712071D01*
Y379616D01*
G01X1686904Y406160D02*
X1690104D01*
G01X1686904Y399960D02*
Y406160D01*
G01X1690104Y399960D02*
X1686904D01*
G01X1676850Y425672D02*
Y437672D01*
G01X1682850Y425672D02*
X1676850D01*
G01X1682850Y437672D02*
Y425672D01*
G01X1675472Y426545D02*
X1672272D01*
G01X1675472Y432745D02*
Y426545D01*
G01X1672272D02*
Y432745D01*
G01X1687754Y427085D02*
X1684554D01*
G01X1687754Y433285D02*
Y427085D01*
G01X1684554D02*
Y433285D01*
G01X1685533Y426294D02*
X1691733D01*
G01X1685533Y423094D02*
Y426294D01*
G01X1691733Y423094D02*
X1685533D01*
G01X1676850Y437672D02*
X1682850D01*
G01X1672272Y432745D02*
X1675472D01*
G01X1684554Y433285D02*
X1687754D01*
G01X1684395Y475478D02*
X1690595D01*
G01X1684395Y472278D02*
Y475478D01*
G01X1690595Y472278D02*
X1684395D01*
G01Y471478D02*
X1690595D01*
G01X1684395Y468278D02*
Y471478D01*
G01X1690595Y468278D02*
X1684395D01*
G01X1682831Y477190D02*
Y480390D01*
G01X1689031Y477190D02*
X1682831D01*
G01X1690620Y464340D02*
X1684420D01*
Y467540D01*
X1690620D01*
Y464340D01*
G01X1682831Y480390D02*
X1689031D01*
G01X1682831Y484390D02*
X1689031D01*
G01X1682831Y481190D02*
Y484390D01*
G01X1689031Y481190D02*
X1682831D01*
G01Y489890D02*
X1689031D01*
G01X1682831Y486690D02*
Y489890D01*
G01X1689031Y486690D02*
X1682831D01*
G01X1678388Y493390D02*
X1684588D01*
G01D02*
Y490190D01*
G01X1678388D02*
Y493390D01*
G01X1684588Y490190D02*
X1678388D01*
G01X1682831Y493690D02*
Y496890D01*
G01X1689031Y493690D02*
X1682831D01*
G01Y496890D02*
X1689031D01*
G01X1682831Y497690D02*
Y500890D01*
G01X1689031Y497690D02*
X1682831D01*
G01Y500890D02*
X1689031D01*
G01X1685204Y522142D02*
Y524642D01*
X1684884Y524142D01*
G01Y522142D02*
X1685524D01*
G01X1687404Y524642D02*
X1687191Y524559D01*
X1687031Y524350D01*
X1686924Y524100D01*
X1686844Y523767D01*
X1686817Y523392D01*
X1686844Y523017D01*
X1686924Y522684D01*
X1687031Y522434D01*
X1687191Y522225D01*
X1687404Y522142D01*
X1687617Y522225D01*
X1687777Y522434D01*
X1687884Y522684D01*
X1687964Y523017D01*
X1687991Y523392D01*
X1687964Y523767D01*
X1687884Y524100D01*
X1687777Y524350D01*
X1687617Y524559D01*
X1687404Y524642D01*
G01X1683104Y522665D02*
Y525665D01*
G01X1675304Y524215D02*
Y525715D01*
G01X1688440Y527502D02*
Y530002D01*
X1688120Y529502D01*
G01Y527502D02*
X1688760D01*
G01X1690640D02*
Y530002D01*
X1690320Y529502D01*
G01Y527502D02*
X1690960D01*
G01X1685847Y529128D02*
Y527222D01*
G01D02*
X1683951D01*
G01X1687354Y536265D02*
X1688854D01*
G01X1688169Y550641D02*
X1681969D01*
G01D02*
Y553841D01*
G01D02*
X1688169D01*
G01D02*
Y550641D01*
G01X1684573Y559963D02*
X1684733Y560213D01*
X1684920Y560338D01*
X1685133Y560380D01*
X1685400Y560297D01*
X1685587Y560088D01*
X1685640Y559838D01*
X1685613Y559588D01*
X1685507Y559380D01*
X1684973Y558963D01*
X1684733Y558672D01*
X1684573Y558255D01*
X1684520Y557880D01*
X1685640D01*
G01X1687280D02*
Y560380D01*
X1686960Y559880D01*
G01Y557880D02*
X1687600D01*
G01X1687643Y547303D02*
X1687803Y547553D01*
X1687990Y547678D01*
X1688203Y547720D01*
X1688470Y547637D01*
X1688657Y547428D01*
X1688710Y547178D01*
X1688683Y546928D01*
X1688577Y546720D01*
X1688043Y546303D01*
X1687803Y546012D01*
X1687643Y545595D01*
X1687590Y545220D01*
X1688710D01*
G01X1690350Y547720D02*
X1690137Y547637D01*
X1689977Y547428D01*
X1689870Y547178D01*
X1689790Y546845D01*
X1689763Y546470D01*
X1689790Y546095D01*
X1689870Y545762D01*
X1689977Y545512D01*
X1690137Y545303D01*
X1690350Y545220D01*
X1690563Y545303D01*
X1690723Y545512D01*
X1690830Y545762D01*
X1690910Y546095D01*
X1690937Y546470D01*
X1690910Y546845D01*
X1690830Y547178D01*
X1690723Y547428D01*
X1690563Y547637D01*
X1690350Y547720D01*
G01X1683941Y546908D02*
X1685847D01*
G01D02*
Y545002D01*
G01X1690304Y544065D02*
X1687304D01*
G01X1676804Y548415D02*
Y549915D01*
G01X1677640Y562552D02*
X1674440D01*
G01X1677640Y568752D02*
Y562552D01*
G01X1674440Y568752D02*
X1677640D01*
G01X1674440Y562552D02*
Y568752D01*
G01X1681640Y562552D02*
X1678440D01*
G01X1681640Y568752D02*
Y562552D01*
G01X1678440Y568752D02*
X1681640D01*
G01X1678440Y562552D02*
Y568752D01*
G01X1673640D02*
Y562552D01*
G01X1674306Y593556D02*
Y581556D01*
G01X1673393Y603182D02*
Y606282D01*
X1674313D01*
X1674620Y606127D01*
X1674850Y605765D01*
X1674927Y605352D01*
X1674850Y604939D01*
X1674658Y604629D01*
X1674313Y604474D01*
X1673393D01*
G01X1676417Y606282D02*
Y604060D01*
X1676570Y603595D01*
X1676877Y603285D01*
X1677260Y603182D01*
X1677643Y603285D01*
X1677950Y603595D01*
X1678103Y604060D01*
Y606282D01*
G01X1680820Y603182D02*
Y606282D01*
X1679402Y604060D01*
X1681318D01*
G01X1682732Y605765D02*
X1682962Y606075D01*
X1683230Y606230D01*
X1683537Y606282D01*
X1683920Y606179D01*
X1684188Y605920D01*
X1684265Y605610D01*
X1684227Y605300D01*
X1684073Y605042D01*
X1683307Y604525D01*
X1682962Y604164D01*
X1682732Y603647D01*
X1682655Y603182D01*
X1684265D01*
G01X1698906Y639885D02*
X1681190D01*
G01D02*
Y643293D01*
G01Y654193D02*
Y657601D01*
G01D02*
X1698906D01*
G01X1685767Y697211D02*
X1711357D01*
G01X1685767Y1335007D02*
Y697211D01*
G01X1681657D02*
Y707592D01*
G01X1686697Y708705D02*
Y720705D01*
G01X1692697Y708705D02*
X1686697D01*
G01Y720705D02*
X1692697D01*
G01X1678797Y708705D02*
Y720705D01*
G01X1684797Y708705D02*
X1678797D01*
G01X1684797Y720705D02*
Y708705D01*
G01X1678797Y720705D02*
X1684797D01*
G01X1711357Y732644D02*
X1685767D01*
G01X1681657Y722302D02*
Y1335007D01*
G01X1711357Y1299574D02*
X1685767D01*
G01X1684445Y1336996D02*
X1684637Y1336686D01*
X1684867Y1336479D01*
X1685135Y1336376D01*
X1685442Y1336479D01*
X1685672Y1336686D01*
X1685902Y1336996D01*
X1685979Y1337409D01*
Y1339476D01*
G01X1688312Y1336376D02*
Y1339476D01*
X1687852Y1338856D01*
G01Y1336376D02*
X1688772D01*
G01X1691412D02*
Y1339476D01*
X1690952Y1338856D01*
G01Y1336376D02*
X1691872D01*
G01X1711357Y1335007D02*
X1685767D01*
G01X1693859Y1358336D02*
G03I-10827J0D01*
G01X1691326Y1371311D02*
X1685412D01*
G01X1693859Y1358336D02*
X1672205D01*
G01X1686413Y1413731D02*
X1685620D01*
G01X1686413Y1416331D02*
Y1413731D01*
G01X1685412Y1410681D02*
X1691326D01*
G01X1686413Y1437353D02*
Y1435162D01*
G01X1685680Y1437353D02*
X1686413D01*
G01X1682001Y1446766D02*
X1685201D01*
G01X1682001Y1440566D02*
Y1446766D01*
G01X1685201Y1440566D02*
X1682001D01*
G01X1685201Y1446766D02*
Y1440566D01*
G01X1674586Y1447394D02*
Y1444194D01*
G01X1681159Y1440566D02*
X1677959D01*
G01X1681159Y1446766D02*
Y1440566D01*
G01X1677959Y1446766D02*
X1681159D01*
G01X1677959Y1440566D02*
Y1446766D01*
G01X1675022Y1450269D02*
Y1477041D01*
G01X1680501Y1496531D02*
Y1505193D01*
G01X1690995Y1496531D02*
X1680501D01*
G01X1673198Y1498962D02*
Y1495762D01*
G01Y1494962D02*
Y1491762D01*
G01Y1502962D02*
Y1499762D01*
G01X1689300Y1507412D02*
X1688993Y1507464D01*
X1688725Y1507670D01*
X1688495Y1507980D01*
X1688342Y1508342D01*
X1688265Y1508755D01*
Y1509169D01*
X1688342Y1509582D01*
X1688495Y1509944D01*
X1688725Y1510254D01*
X1688993Y1510460D01*
X1689300Y1510512D01*
X1689607Y1510460D01*
X1689875Y1510254D01*
X1690105Y1509944D01*
X1690258Y1509582D01*
X1690335Y1509169D01*
Y1508755D01*
X1690258Y1508342D01*
X1690105Y1507980D01*
X1689875Y1507670D01*
X1689607Y1507464D01*
X1689300Y1507412D01*
G01X1689607Y1508239D02*
X1690067Y1507412D01*
G01X1691672Y1508704D02*
X1691940Y1509065D01*
X1692170Y1509272D01*
X1692477Y1509375D01*
X1692745Y1509272D01*
X1692937Y1509065D01*
X1693090Y1508755D01*
X1693128Y1508394D01*
X1693090Y1508084D01*
X1692937Y1507774D01*
X1692707Y1507515D01*
X1692438Y1507412D01*
X1692132Y1507515D01*
X1691863Y1507825D01*
X1691710Y1508290D01*
X1691672Y1508807D01*
X1691748Y1509479D01*
X1691863Y1509840D01*
X1692055Y1510202D01*
X1692323Y1510460D01*
X1692592Y1510512D01*
X1692860Y1510409D01*
X1693052Y1510150D01*
G01X1694848Y1507774D02*
X1695117Y1507515D01*
X1695423Y1507412D01*
X1695730Y1507515D01*
X1695998Y1507825D01*
X1696190Y1508290D01*
X1696267Y1508755D01*
Y1509324D01*
X1696190Y1509789D01*
X1695998Y1510202D01*
X1695768Y1510409D01*
X1695500Y1510512D01*
X1695193Y1510409D01*
X1694963Y1510202D01*
X1694810Y1509892D01*
X1694733Y1509479D01*
X1694810Y1509117D01*
X1695002Y1508755D01*
X1695232Y1508549D01*
X1695500Y1508497D01*
X1695807Y1508600D01*
X1696037Y1508859D01*
X1696267Y1509324D01*
G01X1687648Y1505193D02*
X1690995D01*
G01X1685748Y1502993D02*
X1687648Y1505193D01*
G01X1683848D02*
X1685748Y1502993D01*
G01X1680501Y1505193D02*
X1683848D01*
G01X1680501Y1516031D02*
Y1524693D01*
G01X1690995Y1516031D02*
X1680501D01*
G01X1673198Y1514462D02*
Y1511262D01*
G01Y1518462D02*
Y1515262D01*
G01Y1506962D02*
Y1503762D01*
G01X1689050Y1527502D02*
X1688743Y1527554D01*
X1688475Y1527760D01*
X1688245Y1528070D01*
X1688092Y1528432D01*
X1688015Y1528845D01*
Y1529259D01*
X1688092Y1529672D01*
X1688245Y1530034D01*
X1688475Y1530344D01*
X1688743Y1530550D01*
X1689050Y1530602D01*
X1689357Y1530550D01*
X1689625Y1530344D01*
X1689855Y1530034D01*
X1690008Y1529672D01*
X1690085Y1529259D01*
Y1528845D01*
X1690008Y1528432D01*
X1689855Y1528070D01*
X1689625Y1527760D01*
X1689357Y1527554D01*
X1689050Y1527502D01*
G01X1689357Y1528329D02*
X1689817Y1527502D01*
G01X1692073D02*
X1692150Y1528174D01*
X1692265Y1528742D01*
X1692418Y1529259D01*
X1692610Y1529827D01*
X1692917Y1530602D01*
X1691383D01*
G01X1695250Y1527502D02*
Y1530602D01*
X1694790Y1529982D01*
G01Y1527502D02*
X1695710D01*
G01X1687648Y1524693D02*
X1690995D01*
G01X1685748Y1522493D02*
X1687648Y1524693D01*
G01X1683848D02*
X1685748Y1522493D01*
G01X1680501Y1524693D02*
X1683848D01*
G01X1673198Y1535462D02*
Y1532262D01*
G01Y1526462D02*
Y1523262D01*
G01Y1522462D02*
Y1519262D01*
G01X1688720Y1547592D02*
X1688413Y1547644D01*
X1688145Y1547850D01*
X1687915Y1548160D01*
X1687762Y1548522D01*
X1687685Y1548935D01*
Y1549349D01*
X1687762Y1549762D01*
X1687915Y1550124D01*
X1688145Y1550434D01*
X1688413Y1550640D01*
X1688720Y1550692D01*
X1689027Y1550640D01*
X1689295Y1550434D01*
X1689525Y1550124D01*
X1689678Y1549762D01*
X1689755Y1549349D01*
Y1548935D01*
X1689678Y1548522D01*
X1689525Y1548160D01*
X1689295Y1547850D01*
X1689027Y1547644D01*
X1688720Y1547592D01*
G01X1689027Y1548419D02*
X1689487Y1547592D01*
G01X1691743D02*
X1691820Y1548264D01*
X1691935Y1548832D01*
X1692088Y1549349D01*
X1692280Y1549917D01*
X1692587Y1550692D01*
X1691053D01*
G01X1694920D02*
X1694613Y1550589D01*
X1694383Y1550330D01*
X1694230Y1550020D01*
X1694115Y1549607D01*
X1694077Y1549142D01*
X1694115Y1548677D01*
X1694230Y1548264D01*
X1694383Y1547954D01*
X1694613Y1547695D01*
X1694920Y1547592D01*
X1695227Y1547695D01*
X1695457Y1547954D01*
X1695610Y1548264D01*
X1695725Y1548677D01*
X1695763Y1549142D01*
X1695725Y1549607D01*
X1695610Y1550020D01*
X1695457Y1550330D01*
X1695227Y1550589D01*
X1694920Y1550692D01*
G01X1680501Y1537031D02*
Y1545693D01*
G01X1690995Y1537031D02*
X1680501D01*
G01X1687648Y1545693D02*
X1690995D01*
G01X1685748Y1543493D02*
X1687648Y1545693D01*
G01X1683848D02*
X1685748Y1543493D01*
G01X1680501Y1545693D02*
X1683848D01*
G01X1673198Y1539462D02*
Y1536262D01*
G01Y1547462D02*
Y1544262D01*
G01Y1543462D02*
Y1540262D01*
G01X1687210Y1566702D02*
X1686903Y1566754D01*
X1686635Y1566960D01*
X1686405Y1567270D01*
X1686252Y1567632D01*
X1686175Y1568045D01*
Y1568459D01*
X1686252Y1568872D01*
X1686405Y1569234D01*
X1686635Y1569544D01*
X1686903Y1569750D01*
X1687210Y1569802D01*
X1687517Y1569750D01*
X1687785Y1569544D01*
X1688015Y1569234D01*
X1688168Y1568872D01*
X1688245Y1568459D01*
Y1568045D01*
X1688168Y1567632D01*
X1688015Y1567270D01*
X1687785Y1566960D01*
X1687517Y1566754D01*
X1687210Y1566702D01*
G01X1687517Y1567529D02*
X1687977Y1566702D01*
G01X1690310D02*
Y1569802D01*
X1689850Y1569182D01*
G01Y1566702D02*
X1690770D01*
G01X1693410Y1569802D02*
X1693103Y1569699D01*
X1692873Y1569440D01*
X1692720Y1569130D01*
X1692605Y1568717D01*
X1692567Y1568252D01*
X1692605Y1567787D01*
X1692720Y1567374D01*
X1692873Y1567064D01*
X1693103Y1566805D01*
X1693410Y1566702D01*
X1693717Y1566805D01*
X1693947Y1567064D01*
X1694100Y1567374D01*
X1694215Y1567787D01*
X1694253Y1568252D01*
X1694215Y1568717D01*
X1694100Y1569130D01*
X1693947Y1569440D01*
X1693717Y1569699D01*
X1693410Y1569802D01*
G01X1696970Y1566702D02*
Y1569802D01*
X1695552Y1567580D01*
X1697468D01*
G01X1680501Y1556490D02*
Y1565152D01*
G01X1690995Y1556490D02*
X1680501D01*
G01X1687648Y1565152D02*
X1690995D01*
G01X1685748Y1562952D02*
X1687648Y1565152D01*
G01X1683848D02*
X1685748Y1562952D01*
G01X1680501Y1565152D02*
X1683848D01*
G01X1673198Y1555157D02*
Y1551957D01*
G01X1673273Y1567157D02*
Y1563957D01*
G01Y1563157D02*
Y1559957D01*
G01X1673198Y1559157D02*
Y1555957D01*
G01X1680501Y1576990D02*
Y1585652D01*
G01X1690995Y1576990D02*
X1680501D01*
G01X1685748Y1583452D02*
X1687648Y1585652D01*
G01X1683848D02*
X1685748Y1583452D01*
G01X1673273Y1582921D02*
Y1579721D01*
G01Y1586921D02*
Y1583721D01*
G01X1682680Y1593322D02*
X1682373Y1593374D01*
X1682105Y1593580D01*
X1681875Y1593890D01*
X1681722Y1594252D01*
X1681645Y1594665D01*
Y1595079D01*
X1681722Y1595492D01*
X1681875Y1595854D01*
X1682105Y1596164D01*
X1682373Y1596370D01*
X1682680Y1596422D01*
X1682987Y1596370D01*
X1683255Y1596164D01*
X1683485Y1595854D01*
X1683638Y1595492D01*
X1683715Y1595079D01*
Y1594665D01*
X1683638Y1594252D01*
X1683485Y1593890D01*
X1683255Y1593580D01*
X1682987Y1593374D01*
X1682680Y1593322D01*
G01X1682987Y1594149D02*
X1683447Y1593322D01*
G01X1685780D02*
Y1596422D01*
X1685320Y1595802D01*
G01Y1593322D02*
X1686240D01*
G01X1688880Y1596422D02*
X1688573Y1596319D01*
X1688343Y1596060D01*
X1688190Y1595750D01*
X1688075Y1595337D01*
X1688037Y1594872D01*
X1688075Y1594407D01*
X1688190Y1593994D01*
X1688343Y1593684D01*
X1688573Y1593425D01*
X1688880Y1593322D01*
X1689187Y1593425D01*
X1689417Y1593684D01*
X1689570Y1593994D01*
X1689685Y1594407D01*
X1689723Y1594872D01*
X1689685Y1595337D01*
X1689570Y1595750D01*
X1689417Y1596060D01*
X1689187Y1596319D01*
X1688880Y1596422D01*
G01X1691252Y1594614D02*
X1691520Y1594975D01*
X1691750Y1595182D01*
X1692057Y1595285D01*
X1692325Y1595182D01*
X1692517Y1594975D01*
X1692670Y1594665D01*
X1692708Y1594304D01*
X1692670Y1593994D01*
X1692517Y1593684D01*
X1692287Y1593425D01*
X1692018Y1593322D01*
X1691712Y1593425D01*
X1691443Y1593735D01*
X1691290Y1594200D01*
X1691252Y1594717D01*
X1691328Y1595389D01*
X1691443Y1595750D01*
X1691635Y1596112D01*
X1691903Y1596370D01*
X1692172Y1596422D01*
X1692440Y1596319D01*
X1692632Y1596060D01*
G01X1687648Y1585652D02*
X1690995D01*
G01X1680501D02*
X1683848D01*
G01X1697354Y51096D02*
X1698620D01*
G01X1689025D02*
X1693333D01*
G01X1694489Y110669D02*
Y180669D01*
G01X1697282Y182645D02*
X1697512Y182955D01*
X1697780Y183110D01*
X1698087Y183162D01*
X1698470Y183059D01*
X1698738Y182800D01*
X1698815Y182490D01*
X1698777Y182180D01*
X1698623Y181922D01*
X1697857Y181405D01*
X1697512Y181044D01*
X1697282Y180527D01*
X1697205Y180062D01*
X1698815D01*
G01X1695170Y222482D02*
Y234482D01*
G01X1701170Y222482D02*
X1695170D01*
G01X1701170Y234482D02*
Y222482D01*
G01X1705532Y224919D02*
X1702332D01*
G01Y231119D02*
X1705532D01*
G01X1702332Y224919D02*
Y231119D01*
G01X1695170Y234482D02*
X1701170D01*
G01X1700194Y368173D02*
Y371373D01*
G01X1706394Y368173D02*
X1700194D01*
G01Y371373D02*
X1706394D01*
G01X1700194Y372173D02*
Y375373D01*
G01X1706394Y372173D02*
X1700194D01*
G01Y375373D02*
X1706394D01*
G01X1696020Y407687D02*
X1704208D01*
G01X1696020Y421663D02*
Y407687D01*
G01X1704208D02*
Y421663D01*
G01X1698284Y399885D02*
Y403085D01*
G01X1704484Y399885D02*
X1698284D01*
G01X1704484Y403085D02*
Y399885D01*
G01X1698284Y403085D02*
X1704484D01*
G01X1697104D02*
Y399885D01*
G01X1690904Y403085D02*
X1697104D01*
G01X1690904Y399885D02*
Y403085D01*
G01X1697104Y399885D02*
X1690904D01*
G01X1690104Y406160D02*
Y399960D01*
G01X1704208Y421663D02*
X1696020D01*
G01X1692714Y427055D02*
Y433255D01*
G01X1695914Y427055D02*
X1692714D01*
G01X1695914Y433255D02*
Y427055D01*
G01X1706224Y426575D02*
X1703024D01*
G01D02*
Y432775D01*
G01X1688554Y427085D02*
Y433285D01*
G01X1691754Y427085D02*
X1688554D01*
G01X1691754Y433285D02*
Y427085D01*
G01X1702724Y426575D02*
X1699524D01*
G01X1702724Y432775D02*
Y426575D01*
G01X1699524D02*
Y432775D01*
G01X1691733Y426294D02*
Y423094D01*
G01X1692714Y433255D02*
X1695914D01*
G01X1703024Y432775D02*
X1706224D01*
G01X1688554Y433285D02*
X1691754D01*
G01X1699524Y432775D02*
X1702724D01*
G01X1696730Y460202D02*
Y462702D01*
X1695743Y460910D01*
X1697077D01*
G01X1698610Y462702D02*
X1698397Y462619D01*
X1698237Y462410D01*
X1698130Y462160D01*
X1698050Y461827D01*
X1698023Y461452D01*
X1698050Y461077D01*
X1698130Y460744D01*
X1698237Y460494D01*
X1698397Y460285D01*
X1698610Y460202D01*
X1698823Y460285D01*
X1698983Y460494D01*
X1699090Y460744D01*
X1699170Y461077D01*
X1699197Y461452D01*
X1699170Y461827D01*
X1699090Y462160D01*
X1698983Y462410D01*
X1698823Y462619D01*
X1698610Y462702D01*
G01X1690595Y475478D02*
Y472278D01*
G01Y471478D02*
Y468278D01*
G01X1689031Y480390D02*
Y477190D01*
G01X1692048Y470876D02*
X1695248D01*
G01X1692048Y464676D02*
Y470876D01*
G01X1695248Y464676D02*
X1692048D01*
G01X1695248Y470876D02*
Y464676D01*
G01X1696048Y470876D02*
X1699248D01*
G01X1696048Y464676D02*
Y470876D01*
G01X1699248Y464676D02*
X1696048D01*
G01X1699248Y470876D02*
Y464676D01*
G01X1691460Y477107D02*
X1688460D01*
G01X1694823Y474364D02*
X1692917D01*
G01D02*
Y476270D01*
G01X1702060Y471357D02*
Y472857D01*
G01X1689031Y484390D02*
Y481190D01*
G01Y489890D02*
Y486690D01*
G01X1692917Y492144D02*
Y494050D01*
G01D02*
X1694823D01*
G01X1690010Y484907D02*
X1691510D01*
G01X1689031Y496890D02*
Y493690D01*
G01X1697713Y497500D02*
X1697873Y497208D01*
X1698087Y497042D01*
X1698327Y497000D01*
X1698540Y497042D01*
X1698753Y497250D01*
X1698887Y497500D01*
X1698913Y497750D01*
X1698860Y498042D01*
X1698673Y498250D01*
X1698487Y498333D01*
X1698247D01*
G01X1698487D02*
X1698647Y498458D01*
X1698780Y498667D01*
X1698833Y498917D01*
X1698780Y499167D01*
X1698647Y499375D01*
X1698407Y499500D01*
X1698167Y499458D01*
X1697927Y499292D01*
G01X1700500Y499500D02*
X1700287Y499417D01*
X1700127Y499208D01*
X1700020Y498958D01*
X1699940Y498625D01*
X1699913Y498250D01*
X1699940Y497875D01*
X1700020Y497542D01*
X1700127Y497292D01*
X1700287Y497083D01*
X1700500Y497000D01*
X1700713Y497083D01*
X1700873Y497292D01*
X1700980Y497542D01*
X1701060Y497875D01*
X1701087Y498250D01*
X1701060Y498625D01*
X1700980Y498958D01*
X1700873Y499208D01*
X1700713Y499417D01*
X1700500Y499500D01*
G01X1690773Y496132D02*
X1690933Y495840D01*
X1691147Y495674D01*
X1691387Y495632D01*
X1691600Y495674D01*
X1691813Y495882D01*
X1691947Y496132D01*
X1691973Y496382D01*
X1691920Y496674D01*
X1691733Y496882D01*
X1691547Y496965D01*
X1691307D01*
G01X1691547D02*
X1691707Y497090D01*
X1691840Y497299D01*
X1691893Y497549D01*
X1691840Y497799D01*
X1691707Y498007D01*
X1691467Y498132D01*
X1691227Y498090D01*
X1690987Y497924D01*
G01X1693560Y495632D02*
Y498132D01*
X1693240Y497632D01*
G01Y495632D02*
X1693880D01*
G01X1704923Y499447D02*
X1705083Y499697D01*
X1705270Y499822D01*
X1705483Y499864D01*
X1705750Y499781D01*
X1705937Y499572D01*
X1705990Y499322D01*
X1705963Y499072D01*
X1705857Y498864D01*
X1705323Y498447D01*
X1705083Y498156D01*
X1704923Y497739D01*
X1704870Y497364D01*
X1705990D01*
G01X1707630D02*
Y499864D01*
X1707310Y499364D01*
G01Y497364D02*
X1707950D01*
G01X1695760Y495507D02*
Y498507D01*
G01X1703560Y495557D02*
Y497057D01*
G01X1702120Y508462D02*
X1705320D01*
G01Y502262D02*
X1702120D01*
G01D02*
Y508462D01*
G01X1697120D02*
X1700320D01*
G01Y502262D02*
X1697120D01*
G01X1700320Y508462D02*
Y502262D01*
G01X1697120D02*
Y508462D01*
G01X1689031Y500890D02*
Y497690D01*
G01X1698376Y527107D02*
Y523907D01*
G01X1692176D02*
Y527107D01*
G01X1698376Y523907D02*
X1692176D01*
G01X1698376Y519707D02*
Y516507D01*
G01X1692176Y519707D02*
X1698376D01*
G01X1692176Y516507D02*
Y519707D01*
G01X1698376Y516507D02*
X1692176D01*
G01X1698376Y514707D02*
Y511507D01*
G01X1692176Y514707D02*
X1698376D01*
G01X1692176Y511507D02*
Y514707D01*
G01X1698376Y511507D02*
X1692176D01*
G01Y527107D02*
X1698376D01*
G01Y531107D02*
Y527907D01*
G01X1692176D02*
Y531107D01*
G01X1698376Y527907D02*
X1692176D01*
G01Y531107D02*
X1698376D01*
G01Y543107D02*
Y539907D01*
G01X1692176D02*
Y543107D01*
G01X1698376Y539907D02*
X1692176D01*
G01X1698376Y539107D02*
Y535907D01*
G01X1692176Y539107D02*
X1698376D01*
G01X1692176Y535907D02*
Y539107D01*
G01X1698376Y535907D02*
X1692176D01*
G01X1702360Y542403D02*
Y548603D01*
G01X1705560Y542403D02*
X1702360D01*
G01X1703920Y534872D02*
X1700720D01*
G01X1703920Y541072D02*
Y534872D01*
G01X1700720Y541072D02*
X1703920D01*
G01X1700720Y534872D02*
Y541072D01*
G01X1702935Y533213D02*
X1709135D01*
G01X1702935Y530013D02*
Y533213D01*
G01X1709135Y530013D02*
X1702935D01*
G01X1698376Y535107D02*
Y531907D01*
G01X1692176D02*
Y535107D01*
G01X1698376Y531907D02*
X1692176D01*
G01Y535107D02*
X1698376D01*
G01X1692176Y551107D02*
X1698376D01*
G01Y547907D02*
X1692176D01*
G01D02*
Y551107D01*
G01X1698376D02*
Y547907D01*
G01X1692176Y543107D02*
X1698376D01*
G01Y547107D02*
Y543907D01*
G01X1692176Y547107D02*
X1698376D01*
G01X1692176Y543907D02*
Y547107D01*
G01X1698376Y543907D02*
X1692176D01*
G01X1702360Y548603D02*
X1705560D01*
G01X1698376Y551927D02*
X1692176D01*
G01D02*
Y555127D01*
G01D02*
X1698376D01*
G01D02*
Y551927D01*
G01X1691680Y556857D02*
Y550657D01*
G01D02*
X1688480D01*
G01D02*
Y556857D01*
G01D02*
X1691680D01*
G01X1695443Y567712D02*
Y570812D01*
X1696363D01*
X1696670Y570657D01*
X1696900Y570295D01*
X1696977Y569882D01*
X1696900Y569469D01*
X1696708Y569159D01*
X1696363Y569004D01*
X1695443D01*
G01X1698543Y568332D02*
X1698735Y568022D01*
X1698965Y567815D01*
X1699233Y567712D01*
X1699540Y567815D01*
X1699770Y568022D01*
X1700000Y568332D01*
X1700077Y568745D01*
Y570812D01*
G01X1702870Y567712D02*
Y570812D01*
X1701452Y568590D01*
X1703368D01*
G01X1704667Y568177D02*
X1704897Y567919D01*
X1705165Y567764D01*
X1705510Y567712D01*
X1705855Y567815D01*
X1706123Y568022D01*
X1706315Y568384D01*
X1706353Y568797D01*
X1706277Y569210D01*
X1706085Y569469D01*
X1705817Y569675D01*
X1705548Y569727D01*
X1705280Y569675D01*
X1704935Y569469D01*
X1705050Y570812D01*
X1706085D01*
G01X1698906Y643293D02*
Y639885D01*
G01Y657601D02*
Y654193D01*
G01X1701927Y653541D02*
Y656741D01*
G01X1708127Y653541D02*
X1701927D01*
G01Y656741D02*
X1708127D01*
G01X1700041Y662014D02*
Y665114D01*
X1700961D01*
X1701268Y664959D01*
X1701498Y664597D01*
X1701575Y664184D01*
X1701498Y663771D01*
X1701306Y663461D01*
X1700961Y663306D01*
X1700041D01*
G01X1703141Y665114D02*
Y662014D01*
X1704675D01*
G01X1706280Y663306D02*
X1706548Y663667D01*
X1706778Y663874D01*
X1707085Y663977D01*
X1707353Y663874D01*
X1707545Y663667D01*
X1707698Y663357D01*
X1707736Y662996D01*
X1707698Y662686D01*
X1707545Y662376D01*
X1707315Y662117D01*
X1707046Y662014D01*
X1706740Y662117D01*
X1706471Y662427D01*
X1706318Y662892D01*
X1706280Y663409D01*
X1706356Y664081D01*
X1706471Y664442D01*
X1706663Y664804D01*
X1706931Y665062D01*
X1707200Y665114D01*
X1707468Y665011D01*
X1707660Y664752D01*
G01X1699320Y686530D02*
Y689730D01*
G01X1705520Y686530D02*
X1699320D01*
G01Y689730D02*
X1705520D01*
G01X1693846Y702418D02*
Y708618D01*
G01X1697046Y702418D02*
X1693846D01*
G01X1697046Y708618D02*
Y702418D01*
G01X1699320Y690130D02*
Y693330D01*
G01X1705520Y690130D02*
X1699320D01*
G01Y693330D02*
X1705520D01*
G01X1702168Y703506D02*
X1705368D01*
G01X1702168Y697306D02*
Y703506D01*
G01X1705368Y697306D02*
X1702168D01*
G01X1699320Y693730D02*
Y696930D01*
G01X1705520Y693730D02*
X1699320D01*
G01Y696930D02*
X1705520D01*
G01X1692697Y720705D02*
Y708705D01*
G01X1697043Y711745D02*
X1693843D01*
G01X1697043Y717945D02*
Y711745D01*
G01X1693843Y717945D02*
X1697043D01*
G01X1693843Y711745D02*
Y717945D01*
G01X1700367Y721405D02*
Y724605D01*
G01X1706567Y721405D02*
X1700367D01*
G01X1700263Y717442D02*
Y718607D01*
G01D02*
X1702413D01*
G01Y706403D02*
X1700263D01*
G01D02*
Y707568D01*
G01X1693846Y708618D02*
X1697046D01*
G01X1700367Y724605D02*
X1706567D01*
G01X1700360Y724952D02*
Y728152D01*
G01X1706560Y724952D02*
X1700360D01*
G01Y728152D02*
X1706560D01*
G01X1691326Y1410681D02*
Y1371311D01*
G01X1694013Y1405032D02*
Y1408132D01*
X1694933D01*
X1695240Y1407977D01*
X1695470Y1407615D01*
X1695547Y1407202D01*
X1695470Y1406789D01*
X1695278Y1406479D01*
X1694933Y1406324D01*
X1694013D01*
G01X1697113Y1408132D02*
Y1405032D01*
X1698647D01*
G01X1700252Y1407615D02*
X1700482Y1407925D01*
X1700750Y1408080D01*
X1701057Y1408132D01*
X1701440Y1408029D01*
X1701708Y1407770D01*
X1701785Y1407460D01*
X1701747Y1407150D01*
X1701593Y1406892D01*
X1700827Y1406375D01*
X1700482Y1406014D01*
X1700252Y1405497D01*
X1700175Y1405032D01*
X1701785D01*
G01X1704557Y1438332D02*
Y1432332D01*
G01X1692557D02*
Y1438332D01*
G01X1704557Y1432332D02*
X1692557D01*
G01X1693572Y1429020D02*
X1696772D01*
G01X1693572Y1422820D02*
Y1429020D01*
G01X1696772Y1422820D02*
X1693572D01*
G01X1696772Y1429020D02*
Y1422820D01*
G01X1689275Y1429020D02*
X1692475D01*
G01X1689275Y1422820D02*
Y1429020D01*
G01X1692475Y1422820D02*
X1689275D01*
G01X1692475Y1429020D02*
Y1422820D01*
G01X1692557Y1438332D02*
X1704557D01*
G01X1691097Y1448935D02*
Y1454935D01*
G01X1703097Y1448935D02*
X1691097D01*
G01X1703097Y1454935D02*
Y1448935D01*
G01X1690817Y1446505D02*
X1702817D01*
G01X1690817Y1440505D02*
Y1446505D01*
G01X1702817Y1440505D02*
X1690817D01*
G01X1702817Y1446505D02*
Y1440505D01*
G01X1691097Y1454935D02*
X1703097D01*
G01X1690995Y1505193D02*
Y1496531D01*
G01X1703848Y1502462D02*
Y1499262D01*
G01X1697648Y1502462D02*
X1703848D01*
G01X1697648Y1499262D02*
Y1502462D01*
G01X1703848Y1499262D02*
X1697648D01*
G01X1690995Y1524693D02*
Y1516031D01*
G01X1703848Y1521962D02*
Y1518762D01*
G01X1697648D02*
Y1521962D01*
G01X1703848Y1518762D02*
X1697648D01*
G01Y1521962D02*
X1703848D01*
G01X1690995Y1545693D02*
Y1537031D01*
G01X1703848Y1542962D02*
Y1539762D01*
G01X1697648Y1542962D02*
X1703848D01*
G01X1697648Y1539762D02*
Y1542962D01*
G01X1703848Y1539762D02*
X1697648D01*
G01X1690995Y1565152D02*
Y1556490D01*
G01X1704128Y1565657D02*
Y1562457D01*
G01X1697928Y1565657D02*
X1704128D01*
G01X1697928Y1562457D02*
Y1565657D01*
G01X1704128Y1562457D02*
X1697928D01*
G01X1690995Y1585652D02*
Y1576990D01*
G01X1698648Y1582221D02*
Y1585421D01*
G01X1704848Y1582221D02*
X1698648D01*
G01Y1585421D02*
X1704848D01*
G01X1705470Y51096D02*
X1753310D01*
G01X1715275Y67069D02*
X1718475D01*
G01X1715275Y60869D02*
Y67069D01*
G01X1718475Y60869D02*
X1715275D01*
G01X1718475Y67069D02*
Y60869D01*
G01X1710232Y66833D02*
X1713432D01*
G01X1710232Y60633D02*
Y66833D01*
G01X1713432Y60633D02*
X1710232D01*
G01X1713432Y66833D02*
Y60633D01*
G01X1719295Y67069D02*
X1722495D01*
G01X1719295Y60869D02*
Y67069D01*
G01X1722495Y60869D02*
X1719295D01*
G01X1710232Y80321D02*
X1713432D01*
G01X1710232Y74121D02*
Y80321D01*
G01X1713432Y74121D02*
X1710232D01*
G01X1713432Y80321D02*
Y74121D01*
G01X1715365Y80309D02*
X1718565D01*
G01X1715365Y74109D02*
Y80309D01*
G01X1718565Y74109D02*
X1715365D01*
G01X1718565Y80309D02*
Y74109D01*
G01X1716830Y100592D02*
Y103092D01*
X1716510Y102592D01*
G01Y100592D02*
X1717150D01*
G01X1719030D02*
Y103092D01*
X1718710Y102592D01*
G01Y100592D02*
X1719350D01*
G01X1720818Y118467D02*
X1727018D01*
G01X1720818Y115267D02*
Y118467D01*
G01X1727018Y115267D02*
X1720818D01*
G01X1720208Y104284D02*
X1717008D01*
G01X1720208Y110484D02*
Y104284D01*
G01X1717008Y110484D02*
X1720208D01*
G01X1717008Y104284D02*
Y110484D01*
G01X1720818Y111267D02*
Y114467D01*
G01X1727018Y111267D02*
X1720818D01*
G01Y114467D02*
X1727018D01*
G01X1715018Y129767D02*
Y123567D01*
X1711818D01*
Y129767D01*
X1715018D01*
G01X1714943Y126642D02*
X1708743D01*
Y129842D01*
X1714943D01*
Y126642D01*
G01X1719018Y123567D02*
X1715818D01*
G01X1719018Y129767D02*
Y123567D01*
G01X1715818Y129767D02*
X1719018D01*
G01X1715818Y123567D02*
Y129767D01*
G01X1723018Y123567D02*
X1719818D01*
G01Y129767D02*
X1723018D01*
G01X1719818Y123567D02*
Y129767D01*
G01X1716380Y167509D02*
Y164309D01*
G01X1710180Y167509D02*
X1716380D01*
G01X1710180Y164309D02*
Y167509D01*
G01X1716380Y164309D02*
X1710180D01*
G01X1716380Y171926D02*
Y168726D01*
G01X1710180D02*
Y171926D01*
G01X1716380Y168726D02*
X1710180D01*
G01X1716429Y163500D02*
Y160300D01*
G01X1710229Y163500D02*
X1716429D01*
G01X1710229Y160300D02*
Y163500D01*
G01X1716429Y160300D02*
X1710229D01*
G01X1716429Y159492D02*
Y156292D01*
G01X1710229Y159492D02*
X1716429D01*
G01X1710229Y156292D02*
Y159492D01*
G01X1716429Y156292D02*
X1710229D01*
G01X1710180Y171926D02*
X1716380D01*
G01X1710117Y173370D02*
Y176570D01*
G01X1716317Y173370D02*
X1710117D01*
G01X1716317Y176570D02*
Y173370D01*
G01X1710117Y176570D02*
X1716317D01*
G01X1716468Y201447D02*
X1716161Y201499D01*
X1715893Y201705D01*
X1715663Y202015D01*
X1715510Y202377D01*
X1715433Y202790D01*
Y203204D01*
X1715510Y203617D01*
X1715663Y203979D01*
X1715893Y204289D01*
X1716161Y204495D01*
X1716468Y204547D01*
X1716775Y204495D01*
X1717043Y204289D01*
X1717273Y203979D01*
X1717426Y203617D01*
X1717503Y203204D01*
Y202790D01*
X1717426Y202377D01*
X1717273Y202015D01*
X1717043Y201705D01*
X1716775Y201499D01*
X1716468Y201447D01*
G01X1716775Y202274D02*
X1717235Y201447D01*
G01X1718725Y201912D02*
X1718955Y201654D01*
X1719223Y201499D01*
X1719568Y201447D01*
X1719913Y201550D01*
X1720181Y201757D01*
X1720373Y202119D01*
X1720411Y202532D01*
X1720335Y202945D01*
X1720143Y203204D01*
X1719875Y203410D01*
X1719606Y203462D01*
X1719338Y203410D01*
X1718993Y203204D01*
X1719108Y204547D01*
X1720143D01*
G01X1721940Y202739D02*
X1722208Y203100D01*
X1722438Y203307D01*
X1722745Y203410D01*
X1723013Y203307D01*
X1723205Y203100D01*
X1723358Y202790D01*
X1723396Y202429D01*
X1723358Y202119D01*
X1723205Y201809D01*
X1722975Y201550D01*
X1722706Y201447D01*
X1722400Y201550D01*
X1722131Y201860D01*
X1721978Y202325D01*
X1721940Y202842D01*
X1722016Y203514D01*
X1722131Y203875D01*
X1722323Y204237D01*
X1722591Y204495D01*
X1722860Y204547D01*
X1723128Y204444D01*
X1723320Y204185D01*
G01X1713518Y207147D02*
Y208080D01*
G01X1732022Y207147D02*
X1713518D01*
G01Y228013D02*
X1732022D01*
G01X1713518Y227180D02*
Y228013D01*
G01X1705532Y231119D02*
Y224919D01*
G01X1719290Y366562D02*
Y363362D01*
G01D02*
X1713090D01*
G01D02*
Y366562D01*
G01D02*
X1719290D01*
G01X1724100Y367262D02*
X1720900D01*
G01Y373462D02*
X1724100D01*
G01X1720900Y367262D02*
Y373462D01*
G01X1706394Y371373D02*
Y368173D01*
G01Y375373D02*
Y372173D01*
G01X1707222Y400154D02*
Y403254D01*
X1708142D01*
X1708449Y403099D01*
X1708679Y402737D01*
X1708756Y402324D01*
X1708679Y401911D01*
X1708487Y401601D01*
X1708142Y401446D01*
X1707222D01*
G01X1710246Y403254D02*
Y401032D01*
X1710399Y400567D01*
X1710706Y400257D01*
X1711089Y400154D01*
X1711472Y400257D01*
X1711779Y400567D01*
X1711932Y401032D01*
Y403254D01*
G01X1713461Y402737D02*
X1713691Y403047D01*
X1713959Y403202D01*
X1714266Y403254D01*
X1714649Y403151D01*
X1714917Y402892D01*
X1714994Y402582D01*
X1714956Y402272D01*
X1714802Y402014D01*
X1714036Y401497D01*
X1713691Y401136D01*
X1713461Y400619D01*
X1713384Y400154D01*
X1714994D01*
G01X1717289Y403254D02*
X1716982Y403151D01*
X1716752Y402892D01*
X1716599Y402582D01*
X1716484Y402169D01*
X1716446Y401704D01*
X1716484Y401239D01*
X1716599Y400826D01*
X1716752Y400516D01*
X1716982Y400257D01*
X1717289Y400154D01*
X1717596Y400257D01*
X1717826Y400516D01*
X1717979Y400826D01*
X1718094Y401239D01*
X1718132Y401704D01*
X1718094Y402169D01*
X1717979Y402582D01*
X1717826Y402892D01*
X1717596Y403151D01*
X1717289Y403254D01*
G01X1719661Y402737D02*
X1719891Y403047D01*
X1720159Y403202D01*
X1720466Y403254D01*
X1720849Y403151D01*
X1721117Y402892D01*
X1721194Y402582D01*
X1721156Y402272D01*
X1721002Y402014D01*
X1720236Y401497D01*
X1719891Y401136D01*
X1719661Y400619D01*
X1719584Y400154D01*
X1721194D01*
G01X1708826Y412263D02*
X1712026D01*
G01X1708826Y406063D02*
Y412263D01*
G01X1712026Y406063D02*
X1708826D01*
G01X1712026Y412263D02*
Y406063D01*
G01X1716644Y405445D02*
X1713444D01*
G01X1716644Y411645D02*
Y405445D01*
G01X1713444Y411645D02*
X1716644D01*
G01X1713444Y405445D02*
Y411645D01*
G01X1720531Y405437D02*
X1717331D01*
G01X1720531Y411637D02*
Y405437D01*
G01X1717331Y411637D02*
X1720531D01*
G01X1717331Y405437D02*
Y411637D01*
G01X1712008Y418845D02*
X1708808D01*
G01X1712008Y425045D02*
Y418845D01*
G01X1708808Y425045D02*
X1712008D01*
G01X1708808Y418845D02*
Y425045D01*
G01X1719627Y425940D02*
Y422740D01*
G01X1713427Y425940D02*
X1719627D01*
G01X1713427Y422740D02*
Y425940D01*
G01X1719627Y422740D02*
X1713427D01*
G01X1706224Y432775D02*
Y426575D01*
G01X1719627Y421940D02*
Y418740D01*
G01X1713427Y421940D02*
X1719627D01*
G01X1713427Y418740D02*
Y421940D01*
G01X1719627Y418740D02*
X1713427D01*
G01X1718329Y476459D02*
X1724529D01*
G01X1718329Y473259D02*
Y476459D01*
G01X1724529Y473259D02*
X1718329D01*
G01X1714980Y474462D02*
Y476962D01*
X1714660Y476462D01*
G01Y474462D02*
X1715300D01*
G01X1717180D02*
Y476962D01*
X1716860Y476462D01*
G01Y474462D02*
X1717500D01*
G01X1711640Y470874D02*
Y473374D01*
X1711320Y472874D01*
G01Y470874D02*
X1711960D01*
G01X1713840Y473374D02*
X1713627Y473291D01*
X1713467Y473082D01*
X1713360Y472832D01*
X1713280Y472499D01*
X1713253Y472124D01*
X1713280Y471749D01*
X1713360Y471416D01*
X1713467Y471166D01*
X1713627Y470957D01*
X1713840Y470874D01*
X1714053Y470957D01*
X1714213Y471166D01*
X1714320Y471416D01*
X1714400Y471749D01*
X1714427Y472124D01*
X1714400Y472499D01*
X1714320Y472832D01*
X1714213Y473082D01*
X1714053Y473291D01*
X1713840Y473374D01*
G01X1712603Y476270D02*
Y474364D01*
G01D02*
X1710707D01*
G01X1709860Y469807D02*
Y472807D01*
G01X1710577Y463704D02*
X1707377D01*
G01X1710577Y469904D02*
Y463704D01*
G01X1707377Y469904D02*
X1710577D01*
G01X1707377Y463704D02*
Y469904D01*
G01X1715577Y463704D02*
X1712377D01*
G01X1715577Y469904D02*
Y463704D01*
G01X1712377Y469904D02*
X1715577D01*
G01X1712377Y463704D02*
Y469904D01*
G01X1718329Y477269D02*
Y480469D01*
G01X1724529Y477269D02*
X1718329D01*
G01X1713873Y496095D02*
X1714033Y496345D01*
X1714220Y496470D01*
X1714433Y496512D01*
X1714700Y496429D01*
X1714887Y496220D01*
X1714940Y495970D01*
X1714913Y495720D01*
X1714807Y495512D01*
X1714273Y495095D01*
X1714033Y494804D01*
X1713873Y494387D01*
X1713820Y494012D01*
X1714940D01*
G01X1716580Y496512D02*
X1716367Y496429D01*
X1716207Y496220D01*
X1716100Y495970D01*
X1716020Y495637D01*
X1715993Y495262D01*
X1716020Y494887D01*
X1716100Y494554D01*
X1716207Y494304D01*
X1716367Y494095D01*
X1716580Y494012D01*
X1716793Y494095D01*
X1716953Y494304D01*
X1717060Y494554D01*
X1717140Y494887D01*
X1717167Y495262D01*
X1717140Y495637D01*
X1717060Y495970D01*
X1716953Y496220D01*
X1716793Y496429D01*
X1716580Y496512D01*
G01X1710697Y494050D02*
X1712603D01*
G01D02*
Y492144D01*
G01X1717060Y491207D02*
X1714060D01*
G01X1714110Y483407D02*
X1715610D01*
G01X1718329Y480469D02*
X1724529D01*
G01X1718329Y492469D02*
X1724529D01*
G01X1718329Y489269D02*
Y492469D01*
G01X1724529Y489269D02*
X1718329D01*
G01Y488469D02*
X1724529D01*
G01X1718329Y485269D02*
Y488469D01*
G01X1724529Y485269D02*
X1718329D01*
G01Y484469D02*
X1724529D01*
G01X1718329Y481269D02*
Y484469D01*
G01X1724529Y481269D02*
X1718329D01*
G01Y493269D02*
Y496469D01*
G01X1724529Y493269D02*
X1718329D01*
G01X1718553Y510960D02*
Y514060D01*
X1719473D01*
X1719780Y513905D01*
X1720010Y513543D01*
X1720087Y513130D01*
X1720010Y512717D01*
X1719818Y512407D01*
X1719473Y512252D01*
X1718553D01*
G01X1721653Y511580D02*
X1721845Y511270D01*
X1722075Y511063D01*
X1722343Y510960D01*
X1722650Y511063D01*
X1722880Y511270D01*
X1723110Y511580D01*
X1723187Y511993D01*
Y514060D01*
G01X1724677Y511425D02*
X1724907Y511167D01*
X1725175Y511012D01*
X1725520Y510960D01*
X1725865Y511063D01*
X1726133Y511270D01*
X1726325Y511632D01*
X1726363Y512045D01*
X1726287Y512458D01*
X1726095Y512717D01*
X1725827Y512923D01*
X1725558Y512975D01*
X1725290Y512923D01*
X1724945Y512717D01*
X1725060Y514060D01*
X1726095D01*
G01X1729080Y510960D02*
Y514060D01*
X1727662Y511838D01*
X1729578D01*
G01X1715180Y501012D02*
Y497812D01*
G01X1708980Y501012D02*
X1715180D01*
G01X1708980Y497812D02*
Y501012D01*
G01X1715180Y497812D02*
X1708980D01*
G01X1705320Y508462D02*
Y502262D01*
G01X1718329Y496469D02*
X1724529D01*
G01X1719286Y504077D02*
Y497877D01*
G01D02*
X1716086D01*
G01D02*
Y504077D01*
G01D02*
X1719286D01*
G01X1705560Y548603D02*
Y542403D01*
G01X1709135Y533213D02*
Y530013D01*
G01X1762606Y605455D02*
G03I-22900J0D01*
G01X1708127Y656741D02*
Y653541D01*
G01X1709630Y686652D02*
X1706430D01*
G01X1709630Y692852D02*
Y686652D01*
G01X1706430D02*
Y692852D01*
G01X1705520Y689730D02*
Y686530D01*
G01X1718750Y680402D02*
Y683502D01*
X1719670D01*
X1719977Y683347D01*
X1720207Y682985D01*
X1720284Y682572D01*
X1720207Y682159D01*
X1720015Y681849D01*
X1719670Y681694D01*
X1718750D01*
G01X1721774Y683502D02*
Y681280D01*
X1721927Y680815D01*
X1722234Y680505D01*
X1722617Y680402D01*
X1723000Y680505D01*
X1723307Y680815D01*
X1723460Y681280D01*
Y683502D01*
G01X1725717Y680402D02*
X1725985Y680454D01*
X1726292Y680609D01*
X1726484Y680867D01*
X1726560Y681229D01*
X1726484Y681590D01*
X1726254Y681900D01*
X1725909Y682055D01*
X1725525D01*
X1725295Y682159D01*
X1725104Y682417D01*
X1725027Y682779D01*
X1725142Y683140D01*
X1725410Y683399D01*
X1725717Y683502D01*
X1726024Y683399D01*
X1726292Y683140D01*
X1726407Y682779D01*
X1726330Y682417D01*
X1726139Y682159D01*
X1725909Y682055D01*
X1725525D01*
X1725180Y681900D01*
X1724950Y681590D01*
X1724874Y681229D01*
X1724950Y680867D01*
X1725142Y680609D01*
X1725449Y680454D01*
X1725717Y680402D01*
G01X1728817D02*
Y683502D01*
X1728357Y682882D01*
G01Y680402D02*
X1729277D01*
G01X1711559Y686675D02*
Y692875D01*
X1714759D01*
Y686675D01*
X1711559D01*
G01X1720295Y695166D02*
Y701155D01*
G01X1749035Y695166D02*
X1720295D01*
G01X1715467Y697211D02*
X1741057D01*
G01X1715467Y700432D02*
Y697211D01*
G01X1711357D02*
Y698482D01*
G01Y703642D02*
Y1335007D01*
G01X1706430Y692852D02*
X1709630D01*
G01X1712020Y702662D02*
Y699462D01*
G01X1705820Y702662D02*
X1712020D01*
G01X1705820Y699462D02*
Y702662D01*
G01X1712020Y699462D02*
X1705820D01*
G01X1715920Y703162D02*
X1712720D01*
G01X1715920Y709362D02*
Y703162D01*
G01X1712720D02*
Y709362D01*
G01X1705520Y693330D02*
Y690130D01*
G01X1705368Y703506D02*
Y697306D01*
G01X1705520Y696930D02*
Y693730D01*
G01X1720295Y715455D02*
Y721544D01*
G01X1720265D02*
X1749035D01*
G01X1715467Y1335007D02*
Y719592D01*
G01X1706567Y724605D02*
Y721405D01*
G01X1715898Y710015D02*
X1712698D01*
G01X1715898Y716215D02*
Y710015D01*
G01X1712698Y716215D02*
X1715898D01*
G01X1712698Y710015D02*
Y716215D01*
G01X1708531Y707568D02*
Y706403D01*
G01D02*
X1706381D01*
G01Y718607D02*
X1708531D01*
G01D02*
Y717442D01*
G01X1712720Y709362D02*
X1715920D01*
G01X1710707Y720685D02*
X1707507D01*
G01X1710707Y726885D02*
Y720685D01*
G01X1707507D02*
Y726885D01*
G01X1741057Y732644D02*
X1715467D01*
G01X1706560Y728152D02*
Y724952D01*
G01X1707507Y726885D02*
X1710707D01*
G01X1741057Y1299574D02*
X1715467D01*
G01X1714145Y1336996D02*
X1714337Y1336686D01*
X1714567Y1336479D01*
X1714835Y1336376D01*
X1715142Y1336479D01*
X1715372Y1336686D01*
X1715602Y1336996D01*
X1715679Y1337409D01*
Y1339476D01*
G01X1718012Y1336376D02*
Y1339476D01*
X1717552Y1338856D01*
G01Y1336376D02*
X1718472D01*
G01X1721572D02*
Y1339476D01*
X1720154Y1337254D01*
X1722070D01*
G01X1741057Y1335007D02*
X1715467D01*
G01X1710183Y1432952D02*
Y1436052D01*
X1711103D01*
X1711410Y1435897D01*
X1711640Y1435535D01*
X1711717Y1435122D01*
X1711640Y1434709D01*
X1711448Y1434399D01*
X1711103Y1434244D01*
X1710183D01*
G01X1713207Y1436052D02*
Y1433830D01*
X1713360Y1433365D01*
X1713667Y1433055D01*
X1714050Y1432952D01*
X1714433Y1433055D01*
X1714740Y1433365D01*
X1714893Y1433830D01*
Y1436052D01*
G01X1717073Y1432952D02*
X1717150Y1433624D01*
X1717265Y1434192D01*
X1717418Y1434709D01*
X1717610Y1435277D01*
X1717917Y1436052D01*
X1716383D01*
G01X1720250Y1432952D02*
Y1436052D01*
X1719790Y1435432D01*
G01Y1432952D02*
X1720710D01*
G01X1722200Y1431919D02*
X1724500D01*
G01X1725683Y1432952D02*
Y1436052D01*
X1726603D01*
X1726910Y1435897D01*
X1727140Y1435535D01*
X1727217Y1435122D01*
X1727140Y1434709D01*
X1726948Y1434399D01*
X1726603Y1434244D01*
X1725683D01*
G01X1729550Y1436052D02*
X1729243Y1435949D01*
X1729013Y1435690D01*
X1728860Y1435380D01*
X1728745Y1434967D01*
X1728707Y1434502D01*
X1728745Y1434037D01*
X1728860Y1433624D01*
X1729013Y1433314D01*
X1729243Y1433055D01*
X1729550Y1432952D01*
X1729857Y1433055D01*
X1730087Y1433314D01*
X1730240Y1433624D01*
X1730355Y1434037D01*
X1730393Y1434502D01*
X1730355Y1434967D01*
X1730240Y1435380D01*
X1730087Y1435690D01*
X1729857Y1435949D01*
X1729550Y1436052D01*
G01X1731500Y1431919D02*
X1733800D01*
G01X1734907Y1433572D02*
X1735137Y1433210D01*
X1735443Y1433004D01*
X1735788Y1432952D01*
X1736095Y1433004D01*
X1736402Y1433262D01*
X1736593Y1433572D01*
X1736632Y1433882D01*
X1736555Y1434244D01*
X1736287Y1434502D01*
X1736018Y1434605D01*
X1735673D01*
G01X1736018D02*
X1736248Y1434760D01*
X1736440Y1435019D01*
X1736517Y1435329D01*
X1736440Y1435639D01*
X1736248Y1435897D01*
X1735903Y1436052D01*
X1735558Y1436000D01*
X1735213Y1435794D01*
G01X1714050Y1475742D02*
X1713743Y1475794D01*
X1713475Y1476000D01*
X1713245Y1476310D01*
X1713092Y1476672D01*
X1713015Y1477085D01*
Y1477499D01*
X1713092Y1477912D01*
X1713245Y1478274D01*
X1713475Y1478584D01*
X1713743Y1478790D01*
X1714050Y1478842D01*
X1714357Y1478790D01*
X1714625Y1478584D01*
X1714855Y1478274D01*
X1715008Y1477912D01*
X1715085Y1477499D01*
Y1477085D01*
X1715008Y1476672D01*
X1714855Y1476310D01*
X1714625Y1476000D01*
X1714357Y1475794D01*
X1714050Y1475742D01*
G01X1714357Y1476569D02*
X1714817Y1475742D01*
G01X1716307Y1476207D02*
X1716537Y1475949D01*
X1716805Y1475794D01*
X1717150Y1475742D01*
X1717495Y1475845D01*
X1717763Y1476052D01*
X1717955Y1476414D01*
X1717993Y1476827D01*
X1717917Y1477240D01*
X1717725Y1477499D01*
X1717457Y1477705D01*
X1717188Y1477757D01*
X1716920Y1477705D01*
X1716575Y1477499D01*
X1716690Y1478842D01*
X1717725D01*
G01X1720173Y1475742D02*
X1720250Y1476414D01*
X1720365Y1476982D01*
X1720518Y1477499D01*
X1720710Y1478067D01*
X1721017Y1478842D01*
X1719483D01*
G01X1728149Y1498870D02*
X1716149D01*
G01D02*
Y1504870D01*
G01X1719049Y1497870D02*
X1725249D01*
G01X1719049Y1494670D02*
Y1497870D01*
G01X1725249Y1494670D02*
X1719049D01*
G01X1716149Y1504870D02*
X1728149D01*
G01Y1506920D02*
X1716149D01*
G01Y1512920D02*
X1728149D01*
G01X1716149Y1506920D02*
Y1512920D01*
G01X1711322Y1521998D02*
Y1514871D01*
G01D02*
X1729976D01*
G01X1711322Y1536525D02*
Y1529398D01*
G01X1729976Y1536525D02*
X1711322D01*
G01X1720280Y1558570D02*
X1714280D01*
Y1564570D01*
G01X1704848Y1585421D02*
Y1582221D01*
G01X1724446Y1592639D02*
X1724819Y1593014D01*
X1725099Y1593639D01*
X1725286Y1594514D01*
X1725099Y1595264D01*
X1724726Y1595764D01*
X1724072Y1596139D01*
X1721552D01*
Y1588639D01*
X1724632D01*
X1725286Y1589139D01*
X1725659Y1589889D01*
X1725846Y1590764D01*
X1725659Y1591639D01*
X1725099Y1592389D01*
X1724446Y1592639D01*
X1721552D01*
G01X1730079Y1596139D02*
X1732319D01*
G01X1731199D02*
Y1588639D01*
G01X1730079D02*
X1732319D01*
G01X1738699D02*
X1737952Y1588764D01*
X1737299Y1589264D01*
X1736739Y1590014D01*
X1736366Y1590889D01*
X1736179Y1591889D01*
Y1592889D01*
X1736366Y1593889D01*
X1736739Y1594764D01*
X1737299Y1595514D01*
X1737952Y1596014D01*
X1738699Y1596139D01*
X1739446Y1596014D01*
X1740099Y1595514D01*
X1740659Y1594764D01*
X1741032Y1593889D01*
X1741219Y1592889D01*
Y1591889D01*
X1741032Y1590889D01*
X1740659Y1590014D01*
X1740099Y1589264D01*
X1739446Y1588764D01*
X1738699Y1588639D01*
G01X1744239Y1589639D02*
X1744986Y1589014D01*
X1745826Y1588639D01*
X1746572D01*
X1747319Y1589014D01*
X1747879Y1589639D01*
X1748159Y1590514D01*
X1747972Y1591389D01*
X1747506Y1592139D01*
X1746666Y1592639D01*
X1745546Y1592889D01*
X1744892Y1593389D01*
X1744612Y1594264D01*
X1744799Y1595139D01*
X1745266Y1595764D01*
X1745919Y1596139D01*
X1746572D01*
X1747226Y1595889D01*
X1747786Y1595264D01*
G01X1714280Y1593909D02*
Y1599909D01*
X1720280D01*
G01X1710180Y1652244D02*
Y1660244D01*
X1712680D01*
X1713480Y1659844D01*
X1713980Y1659311D01*
X1714180Y1658244D01*
X1713980Y1657177D01*
X1713380Y1656511D01*
X1712680Y1656111D01*
X1710180D01*
G01X1712680D02*
X1714180Y1652244D01*
G01X1718680Y1655844D02*
X1721880D01*
X1721580Y1656777D01*
X1721080Y1657311D01*
X1720380Y1657577D01*
X1719680Y1657444D01*
X1719080Y1657044D01*
X1718680Y1656111D01*
X1718480Y1655310D01*
Y1654511D01*
X1718680Y1653711D01*
X1719180Y1652911D01*
X1719780Y1652377D01*
X1720480Y1652244D01*
X1721180Y1652511D01*
X1721880Y1653310D01*
G01X1726380Y1657577D02*
X1728180Y1652244D01*
X1729980Y1657577D01*
G01X1736180Y1651977D02*
X1735980Y1652111D01*
Y1652377D01*
X1736180Y1652511D01*
X1736380Y1652377D01*
Y1652111D01*
X1736180Y1651977D01*
G01Y1655577D02*
X1735980Y1655711D01*
Y1655977D01*
X1736180Y1656111D01*
X1736380Y1655977D01*
Y1655711D01*
X1736180Y1655577D01*
G01X1742180Y1653844D02*
X1742680Y1653044D01*
X1743280Y1652511D01*
X1743980Y1652244D01*
X1744780Y1652511D01*
X1745380Y1653044D01*
X1745980Y1653844D01*
X1746180Y1654911D01*
Y1660244D01*
G01X1710213Y1664041D02*
Y1671541D01*
X1712453D01*
X1713200Y1671166D01*
X1713760Y1670291D01*
X1713947Y1669291D01*
X1713760Y1668291D01*
X1713293Y1667541D01*
X1712453Y1667166D01*
X1710213D01*
G01X1717900Y1663791D02*
X1721260Y1671541D01*
G01X1724933Y1664041D02*
Y1671541D01*
X1729227Y1664041D01*
Y1671541D01*
G01X1734580Y1663791D02*
X1734393Y1663916D01*
Y1664166D01*
X1734580Y1664291D01*
X1734767Y1664166D01*
Y1663916D01*
X1734580Y1663791D01*
G01Y1667166D02*
X1734393Y1667291D01*
Y1667541D01*
X1734580Y1667666D01*
X1734767Y1667541D01*
Y1667291D01*
X1734580Y1667166D01*
G01X1740027Y1664041D02*
Y1671541D01*
X1741893D01*
X1742640Y1671166D01*
X1743200Y1670666D01*
X1743667Y1669916D01*
X1744040Y1669041D01*
X1744133Y1667791D01*
X1744040Y1666541D01*
X1743667Y1665666D01*
X1743200Y1664916D01*
X1742640Y1664416D01*
X1741893Y1664041D01*
X1740027D01*
G01X1747247D02*
X1749580Y1671541D01*
X1751913Y1664041D01*
G01X1751073Y1666666D02*
X1748087D01*
G01X1757080Y1671541D02*
X1756333Y1671291D01*
X1755773Y1670666D01*
X1755400Y1669916D01*
X1755120Y1668916D01*
X1755027Y1667791D01*
X1755120Y1666666D01*
X1755400Y1665666D01*
X1755773Y1664916D01*
X1756333Y1664291D01*
X1757080Y1664041D01*
X1757827Y1664291D01*
X1758387Y1664916D01*
X1758760Y1665666D01*
X1759040Y1666666D01*
X1759133Y1667791D01*
X1759040Y1668916D01*
X1758760Y1669916D01*
X1758387Y1670666D01*
X1757827Y1671291D01*
X1757080Y1671541D01*
G01X1762807Y1664041D02*
Y1671541D01*
X1766353D01*
G01X1765047Y1667916D02*
X1762807D01*
G01X1772080Y1671541D02*
X1771333Y1671291D01*
X1770773Y1670666D01*
X1770400Y1669916D01*
X1770120Y1668916D01*
X1770027Y1667791D01*
X1770120Y1666666D01*
X1770400Y1665666D01*
X1770773Y1664916D01*
X1771333Y1664291D01*
X1772080Y1664041D01*
X1772827Y1664291D01*
X1773387Y1664916D01*
X1773760Y1665666D01*
X1774040Y1666666D01*
X1774133Y1667791D01*
X1774040Y1668916D01*
X1773760Y1669916D01*
X1773387Y1670666D01*
X1772827Y1671291D01*
X1772080Y1671541D01*
G01X1779580D02*
Y1664041D01*
G01X1777433Y1671541D02*
X1781727D01*
G01X1784653Y1664041D02*
Y1671541D01*
X1787080Y1665291D01*
X1789507Y1671541D01*
Y1664041D01*
G01X1795327Y1668041D02*
X1795700Y1668416D01*
X1795980Y1669041D01*
X1796167Y1669916D01*
X1795980Y1670666D01*
X1795607Y1671166D01*
X1794953Y1671541D01*
X1792433D01*
Y1664041D01*
X1795513D01*
X1796167Y1664541D01*
X1796540Y1665291D01*
X1796727Y1666166D01*
X1796540Y1667041D01*
X1795980Y1667791D01*
X1795327Y1668041D01*
X1792433D01*
G01X1800960Y1671541D02*
X1803200D01*
G01X1802080D02*
Y1664041D01*
G01X1800960D02*
X1803200D01*
G01X1807713Y1665541D02*
X1808180Y1664791D01*
X1808740Y1664291D01*
X1809393Y1664041D01*
X1810140Y1664291D01*
X1810700Y1664791D01*
X1811260Y1665541D01*
X1811447Y1666541D01*
Y1671541D01*
G01X1817080D02*
X1816333Y1671291D01*
X1815773Y1670666D01*
X1815400Y1669916D01*
X1815120Y1668916D01*
X1815027Y1667791D01*
X1815120Y1666666D01*
X1815400Y1665666D01*
X1815773Y1664916D01*
X1816333Y1664291D01*
X1817080Y1664041D01*
X1817827Y1664291D01*
X1818387Y1664916D01*
X1818760Y1665666D01*
X1819040Y1666666D01*
X1819133Y1667791D01*
X1819040Y1668916D01*
X1818760Y1669916D01*
X1818387Y1670666D01*
X1817827Y1671291D01*
X1817080Y1671541D01*
G01X1749781Y43779D02*
X1734981D01*
G01X1738826Y68930D02*
X1726826D01*
G01D02*
Y74930D01*
G01X1736894Y63239D02*
Y60039D01*
G01X1730694Y63239D02*
X1736894D01*
G01X1730694Y60039D02*
Y63239D01*
G01X1736894Y60039D02*
X1730694D01*
G01X1736942Y67349D02*
Y64149D01*
G01X1730742Y67349D02*
X1736942D01*
G01X1730742Y64149D02*
Y67349D01*
G01X1736942Y64149D02*
X1730742D01*
G01X1736897Y59054D02*
Y55854D01*
G01X1730697Y59054D02*
X1736897D01*
G01X1730697Y55854D02*
Y59054D01*
G01X1736897Y55854D02*
X1730697D01*
G01X1723920Y66962D02*
X1727120D01*
G01X1723920Y60762D02*
Y66962D01*
G01X1727120Y60762D02*
X1723920D01*
G01X1727120Y66962D02*
Y60762D01*
G01X1722495Y67069D02*
Y60869D01*
G01X1726826Y74930D02*
X1738826D01*
G01X1738600Y77474D02*
X1726600D01*
G01Y83474D02*
X1738600D01*
G01X1726600Y77474D02*
Y83474D01*
G01X1731518Y87187D02*
Y90387D01*
G01X1737718Y87187D02*
X1731518D01*
G01X1724408Y91557D02*
Y96157D01*
G01X1734608Y91557D02*
X1724408D01*
G01X1734608Y96157D02*
Y91557D01*
G01X1724408Y96157D02*
X1734608D01*
G01X1729508Y96457D02*
Y101057D01*
G01X1734608D02*
Y96457D01*
G01X1724408Y101057D02*
X1734608D01*
G01X1724408Y96457D02*
Y101057D01*
G01X1734608Y96457D02*
X1724408D01*
G01X1738040Y94202D02*
Y96702D01*
X1737720Y96202D01*
G01Y94202D02*
X1738360D01*
G01X1739733Y96285D02*
X1739893Y96535D01*
X1740080Y96660D01*
X1740293Y96702D01*
X1740560Y96619D01*
X1740747Y96410D01*
X1740800Y96160D01*
X1740773Y95910D01*
X1740667Y95702D01*
X1740133Y95285D01*
X1739893Y94994D01*
X1739733Y94577D01*
X1739680Y94202D01*
X1740800D01*
G01X1731518Y90387D02*
X1737718D01*
G01X1728920Y119492D02*
Y121992D01*
X1728600Y121492D01*
G01Y119492D02*
X1729240D01*
G01X1731120Y121992D02*
X1730907Y121909D01*
X1730747Y121700D01*
X1730640Y121450D01*
X1730560Y121117D01*
X1730533Y120742D01*
X1730560Y120367D01*
X1730640Y120034D01*
X1730747Y119784D01*
X1730907Y119575D01*
X1731120Y119492D01*
X1731333Y119575D01*
X1731493Y119784D01*
X1731600Y120034D01*
X1731680Y120367D01*
X1731707Y120742D01*
X1731680Y121117D01*
X1731600Y121450D01*
X1731493Y121700D01*
X1731333Y121909D01*
X1731120Y121992D01*
G01X1735537Y119964D02*
X1735723Y119755D01*
X1735937Y119672D01*
X1736150Y119755D01*
X1736337Y120005D01*
X1736470Y120380D01*
X1736523Y120755D01*
Y121214D01*
X1736470Y121589D01*
X1736337Y121922D01*
X1736177Y122089D01*
X1735990Y122172D01*
X1735777Y122089D01*
X1735617Y121922D01*
X1735510Y121672D01*
X1735457Y121339D01*
X1735510Y121047D01*
X1735643Y120755D01*
X1735803Y120589D01*
X1735990Y120547D01*
X1736203Y120630D01*
X1736363Y120839D01*
X1736523Y121214D01*
G01X1731509Y117029D02*
Y113895D01*
G01X1732674Y117029D02*
X1731509D01*
G01Y111895D02*
Y109959D01*
G01Y104825D02*
X1732674D01*
G01X1731509Y107959D02*
Y104825D01*
G01X1727018Y118467D02*
Y115267D01*
G01X1724208Y104284D02*
X1721008D01*
G01X1724208Y110484D02*
Y104284D01*
G01X1721008Y110484D02*
X1724208D01*
G01X1721008Y104284D02*
Y110484D01*
G01X1725008D02*
X1728208D01*
G01X1725008Y104284D02*
Y110484D01*
G01X1728208Y104284D02*
X1725008D01*
G01X1728208Y110484D02*
Y104284D01*
G01X1727018Y114467D02*
Y111267D01*
G01X1738018Y123567D02*
X1734818D01*
G01Y129767D02*
X1738018D01*
G01X1734818Y123567D02*
Y129767D01*
G01X1731018Y123567D02*
X1727818D01*
G01X1731018Y129767D02*
Y123567D01*
G01X1727818Y129767D02*
X1731018D01*
G01X1727818Y123567D02*
Y129767D01*
G01X1723018D02*
Y123567D01*
G01X1727018D02*
X1723818D01*
G01X1727018Y129767D02*
Y123567D01*
G01X1723818Y129767D02*
X1727018D01*
G01X1723818Y123567D02*
Y129767D01*
G01X1737157Y185654D02*
Y183432D01*
X1737310Y182967D01*
X1737617Y182657D01*
X1738000Y182554D01*
X1738383Y182657D01*
X1738690Y182967D01*
X1738843Y183432D01*
Y185654D01*
G01X1740372Y185137D02*
X1740602Y185447D01*
X1740870Y185602D01*
X1741177Y185654D01*
X1741560Y185551D01*
X1741828Y185292D01*
X1741905Y184982D01*
X1741867Y184672D01*
X1741713Y184414D01*
X1740947Y183897D01*
X1740602Y183536D01*
X1740372Y183019D01*
X1740295Y182554D01*
X1741905D01*
G01X1743357Y183174D02*
X1743587Y182812D01*
X1743893Y182606D01*
X1744238Y182554D01*
X1744545Y182606D01*
X1744852Y182864D01*
X1745043Y183174D01*
X1745082Y183484D01*
X1745005Y183846D01*
X1744737Y184104D01*
X1744468Y184207D01*
X1744123D01*
G01X1744468D02*
X1744698Y184362D01*
X1744890Y184621D01*
X1744967Y184931D01*
X1744890Y185241D01*
X1744698Y185499D01*
X1744353Y185654D01*
X1744008Y185602D01*
X1743663Y185396D01*
G01X1746572Y183846D02*
X1746840Y184207D01*
X1747070Y184414D01*
X1747377Y184517D01*
X1747645Y184414D01*
X1747837Y184207D01*
X1747990Y183897D01*
X1748028Y183536D01*
X1747990Y183226D01*
X1747837Y182916D01*
X1747607Y182657D01*
X1747338Y182554D01*
X1747032Y182657D01*
X1746763Y182967D01*
X1746610Y183432D01*
X1746572Y183949D01*
X1746648Y184621D01*
X1746763Y184982D01*
X1746955Y185344D01*
X1747223Y185602D01*
X1747492Y185654D01*
X1747760Y185551D01*
X1747952Y185292D01*
G01X1731134Y182834D02*
Y179634D01*
G01X1724934Y182834D02*
X1731134D01*
G01X1724934Y179634D02*
Y182834D01*
G01X1731134Y179634D02*
X1724934D01*
G01X1730965Y178672D02*
Y175472D01*
G01X1724765Y178672D02*
X1730965D01*
G01X1724765Y175472D02*
Y178672D01*
G01X1730965Y175472D02*
X1724765D01*
G01X1730965Y174672D02*
Y171472D01*
G01X1724765Y174672D02*
X1730965D01*
G01X1724765Y171472D02*
Y174672D01*
G01X1730965Y171472D02*
X1724765D01*
G01X1737120Y195092D02*
Y207092D01*
G01X1743120Y195092D02*
X1737120D01*
G01Y207092D02*
X1743120D01*
G01X1732022Y207780D02*
Y207147D01*
G01Y228013D02*
Y227380D01*
G01X1731333Y290202D02*
Y293302D01*
X1732253D01*
X1732560Y293147D01*
X1732790Y292785D01*
X1732867Y292372D01*
X1732790Y291959D01*
X1732598Y291649D01*
X1732253Y291494D01*
X1731333D01*
G01X1734357Y293302D02*
Y291080D01*
X1734510Y290615D01*
X1734817Y290305D01*
X1735200Y290202D01*
X1735583Y290305D01*
X1735890Y290615D01*
X1736043Y291080D01*
Y293302D01*
G01X1737648Y290564D02*
X1737917Y290305D01*
X1738223Y290202D01*
X1738530Y290305D01*
X1738798Y290615D01*
X1738990Y291080D01*
X1739067Y291545D01*
Y292114D01*
X1738990Y292579D01*
X1738798Y292992D01*
X1738568Y293199D01*
X1738300Y293302D01*
X1737993Y293199D01*
X1737763Y292992D01*
X1737610Y292682D01*
X1737533Y292269D01*
X1737610Y291907D01*
X1737802Y291545D01*
X1738032Y291339D01*
X1738300Y291287D01*
X1738607Y291390D01*
X1738837Y291649D01*
X1739067Y292114D01*
G01X1728625Y383557D02*
Y381335D01*
X1728778Y380870D01*
X1729085Y380560D01*
X1729468Y380457D01*
X1729851Y380560D01*
X1730158Y380870D01*
X1730311Y381335D01*
Y383557D01*
G01X1731840Y383040D02*
X1732070Y383350D01*
X1732338Y383505D01*
X1732645Y383557D01*
X1733028Y383454D01*
X1733296Y383195D01*
X1733373Y382885D01*
X1733335Y382575D01*
X1733181Y382317D01*
X1732415Y381800D01*
X1732070Y381439D01*
X1731840Y380922D01*
X1731763Y380457D01*
X1733373D01*
G01X1734940Y381749D02*
X1735208Y382110D01*
X1735438Y382317D01*
X1735745Y382420D01*
X1736013Y382317D01*
X1736205Y382110D01*
X1736358Y381800D01*
X1736396Y381439D01*
X1736358Y381129D01*
X1736205Y380819D01*
X1735975Y380560D01*
X1735706Y380457D01*
X1735400Y380560D01*
X1735131Y380870D01*
X1734978Y381335D01*
X1734940Y381852D01*
X1735016Y382524D01*
X1735131Y382885D01*
X1735323Y383247D01*
X1735591Y383505D01*
X1735860Y383557D01*
X1736128Y383454D01*
X1736320Y383195D01*
G01X1738040Y381749D02*
X1738308Y382110D01*
X1738538Y382317D01*
X1738845Y382420D01*
X1739113Y382317D01*
X1739305Y382110D01*
X1739458Y381800D01*
X1739496Y381439D01*
X1739458Y381129D01*
X1739305Y380819D01*
X1739075Y380560D01*
X1738806Y380457D01*
X1738500Y380560D01*
X1738231Y380870D01*
X1738078Y381335D01*
X1738040Y381852D01*
X1738116Y382524D01*
X1738231Y382885D01*
X1738423Y383247D01*
X1738691Y383505D01*
X1738960Y383557D01*
X1739228Y383454D01*
X1739420Y383195D01*
G01X1729086Y364478D02*
Y366431D01*
G01X1731039Y364478D02*
X1729086D01*
G01Y376290D02*
X1731039D01*
G01X1729086Y374337D02*
Y376290D01*
G01X1727100Y376262D02*
X1723900D01*
G01X1727100Y382462D02*
Y376262D01*
G01X1723900D02*
Y382462D01*
G01X1724100Y373462D02*
Y367262D01*
G01X1723900Y382462D02*
X1727100D01*
G01X1732180Y391670D02*
Y397870D01*
X1735380D01*
Y391670D01*
X1732180D01*
G01X1728210D02*
Y397870D01*
X1731410D01*
Y391670D01*
X1728210D01*
G01X1736060D02*
Y397870D01*
X1739260D01*
Y391670D01*
X1736060D01*
G01X1723227Y401661D02*
X1725449D01*
X1725914Y401814D01*
X1726224Y402121D01*
X1726327Y402504D01*
X1726224Y402887D01*
X1725914Y403194D01*
X1725449Y403347D01*
X1723227D01*
G01X1725707Y404761D02*
X1726069Y404991D01*
X1726275Y405297D01*
X1726327Y405642D01*
X1726275Y405949D01*
X1726017Y406256D01*
X1725707Y406447D01*
X1725397Y406486D01*
X1725035Y406409D01*
X1724777Y406141D01*
X1724674Y405872D01*
Y405527D01*
G01Y405872D02*
X1724519Y406102D01*
X1724260Y406294D01*
X1723950Y406371D01*
X1723640Y406294D01*
X1723382Y406102D01*
X1723227Y405757D01*
X1723279Y405412D01*
X1723485Y405067D01*
G01X1725707Y407861D02*
X1726069Y408091D01*
X1726275Y408397D01*
X1726327Y408742D01*
X1726275Y409049D01*
X1726017Y409356D01*
X1725707Y409547D01*
X1725397Y409586D01*
X1725035Y409509D01*
X1724777Y409241D01*
X1724674Y408972D01*
Y408627D01*
G01Y408972D02*
X1724519Y409202D01*
X1724260Y409394D01*
X1723950Y409471D01*
X1723640Y409394D01*
X1723382Y409202D01*
X1723227Y408857D01*
X1723279Y408512D01*
X1723485Y408167D01*
G01X1726327Y412264D02*
X1723227D01*
X1725449Y410846D01*
Y412762D01*
G01X1730194Y406854D02*
X1727592Y404252D01*
Y400030D01*
X1739796D01*
Y413678D01*
X1727592D01*
Y409456D01*
X1730194Y406854D01*
G01X1728690Y415740D02*
Y421940D01*
X1731890D01*
Y415740D01*
X1728690D01*
G01X1739890Y421940D02*
Y415740D01*
X1736690D01*
Y421940D01*
X1739890D01*
G01X1732690Y415740D02*
Y421940D01*
X1735890D01*
Y415740D01*
X1732690D01*
G01X1724529Y476459D02*
Y473259D01*
G01Y480469D02*
Y477269D01*
G01X1738211Y489167D02*
X1735011D01*
G01D02*
Y495367D01*
G01X1734601Y485237D02*
Y488437D01*
G01X1740801Y485237D02*
X1734601D01*
G01Y488437D02*
X1740801D01*
G01X1724529Y492469D02*
Y489269D01*
G01Y488469D02*
Y485269D01*
G01Y484469D02*
Y481269D01*
G01Y496469D02*
Y493269D01*
G01X1726279Y492469D02*
X1732479D01*
G01D02*
Y489269D01*
G01X1726279D02*
Y492469D01*
G01X1732479Y489269D02*
X1726279D01*
G01X1732479Y488469D02*
Y485269D01*
G01X1726279Y488469D02*
X1732479D01*
G01X1726279Y485269D02*
Y488469D01*
G01X1732479Y485269D02*
X1726279D01*
G01X1732479Y482269D02*
Y479069D01*
G01X1726279Y482269D02*
X1732479D01*
G01X1726279Y479069D02*
Y482269D01*
G01X1732479Y479069D02*
X1726279D01*
G01X1735011Y495367D02*
X1738211D01*
G01X1736931Y632815D02*
Y635915D01*
G01X1738541D02*
Y632815D01*
G01Y634365D02*
X1736931D01*
G01X1740836Y632815D02*
Y635915D01*
X1740376Y635295D01*
G01Y632815D02*
X1741296D01*
G01X1743208Y635398D02*
X1743438Y635708D01*
X1743706Y635863D01*
X1744013Y635915D01*
X1744396Y635812D01*
X1744664Y635553D01*
X1744741Y635243D01*
X1744703Y634933D01*
X1744549Y634675D01*
X1743783Y634158D01*
X1743438Y633797D01*
X1743208Y633280D01*
X1743131Y632815D01*
X1744741D01*
G01X1747036Y635915D02*
X1746729Y635812D01*
X1746499Y635553D01*
X1746346Y635243D01*
X1746231Y634830D01*
X1746193Y634365D01*
X1746231Y633900D01*
X1746346Y633487D01*
X1746499Y633177D01*
X1746729Y632918D01*
X1747036Y632815D01*
X1747343Y632918D01*
X1747573Y633177D01*
X1747726Y633487D01*
X1747841Y633900D01*
X1747879Y634365D01*
X1747841Y634830D01*
X1747726Y635243D01*
X1747573Y635553D01*
X1747343Y635812D01*
X1747036Y635915D01*
G01X1734818Y689665D02*
Y692765D01*
X1735738D01*
X1736045Y692610D01*
X1736275Y692248D01*
X1736352Y691835D01*
X1736275Y691422D01*
X1736083Y691112D01*
X1735738Y690957D01*
X1734818D01*
G01X1737918Y692765D02*
Y689665D01*
X1739452D01*
G01X1741785D02*
Y692765D01*
X1741325Y692145D01*
G01Y689665D02*
X1742245D01*
G01X1744157Y692248D02*
X1744387Y692558D01*
X1744655Y692713D01*
X1744962Y692765D01*
X1745345Y692662D01*
X1745613Y692403D01*
X1745690Y692093D01*
X1745652Y691783D01*
X1745498Y691525D01*
X1744732Y691008D01*
X1744387Y690647D01*
X1744157Y690130D01*
X1744080Y689665D01*
X1745690D01*
G01X1747985Y692765D02*
X1747678Y692662D01*
X1747448Y692403D01*
X1747295Y692093D01*
X1747180Y691680D01*
X1747142Y691215D01*
X1747180Y690750D01*
X1747295Y690337D01*
X1747448Y690027D01*
X1747678Y689768D01*
X1747985Y689665D01*
X1748292Y689768D01*
X1748522Y690027D01*
X1748675Y690337D01*
X1748790Y690750D01*
X1748828Y691215D01*
X1748790Y691680D01*
X1748675Y692093D01*
X1748522Y692403D01*
X1748292Y692662D01*
X1747985Y692765D01*
G01X1721055Y689811D02*
X1727255D01*
Y686611D01*
X1721055D01*
Y689811D01*
G01X1727178Y1469735D02*
Y1488239D01*
G01X1728011Y1469735D02*
X1727178D01*
G01X1728149Y1504870D02*
Y1498870D01*
G01X1727178Y1488239D02*
X1727811D01*
G01X1725249Y1497870D02*
Y1494670D01*
G01X1728149Y1512920D02*
Y1506920D01*
G01X1729976Y1514871D02*
X1732976Y1517871D01*
G01D02*
Y1521998D01*
G01Y1529398D02*
Y1533525D01*
G01D02*
X1729976Y1536525D01*
G01X1726896Y1566539D02*
X1727269Y1566914D01*
X1727549Y1567539D01*
X1727736Y1568414D01*
X1727549Y1569164D01*
X1727176Y1569664D01*
X1726522Y1570039D01*
X1724002D01*
Y1562539D01*
X1727082D01*
X1727736Y1563039D01*
X1728109Y1563789D01*
X1728296Y1564664D01*
X1728109Y1565539D01*
X1727549Y1566289D01*
X1726896Y1566539D01*
X1724002D01*
G01X1731222Y1562539D02*
Y1570039D01*
X1733649Y1563789D01*
X1736076Y1570039D01*
Y1562539D01*
G01X1743202Y1569414D02*
X1742642Y1569789D01*
X1741989Y1570039D01*
X1741242D01*
X1740402Y1569664D01*
X1739749Y1569039D01*
X1739282Y1568289D01*
X1738909Y1567039D01*
X1738816Y1565914D01*
X1739002Y1564789D01*
X1739282Y1564039D01*
X1739842Y1563289D01*
X1740496Y1562789D01*
X1741149Y1562539D01*
X1741802D01*
X1742456Y1562789D01*
X1743016Y1563164D01*
X1743482Y1563664D01*
G01X1736349Y1574839D02*
X1731682Y1582339D01*
Y1583589D01*
X1732616Y1584839D01*
X1733549D01*
X1734482Y1583589D01*
Y1582339D01*
X1733549Y1581089D01*
X1731682Y1579839D01*
X1730749Y1578589D01*
Y1576089D01*
X1731682Y1574839D01*
X1734482D01*
X1736349Y1577339D01*
G01X1737290Y1605149D02*
X1737520Y1605459D01*
X1737788Y1605614D01*
X1738095Y1605666D01*
X1738478Y1605563D01*
X1738746Y1605304D01*
X1738823Y1604994D01*
X1738785Y1604684D01*
X1738631Y1604426D01*
X1737865Y1603909D01*
X1737520Y1603548D01*
X1737290Y1603031D01*
X1737213Y1602566D01*
X1738823D01*
G01X1743720Y1603599D02*
X1744716D01*
G01X1749575Y1603186D02*
X1749805Y1602824D01*
X1750111Y1602618D01*
X1750456Y1602566D01*
X1750763Y1602618D01*
X1751070Y1602876D01*
X1751261Y1603186D01*
X1751300Y1603496D01*
X1751223Y1603858D01*
X1750955Y1604116D01*
X1750686Y1604219D01*
X1750341D01*
G01X1750686D02*
X1750916Y1604374D01*
X1751108Y1604633D01*
X1751185Y1604943D01*
X1751108Y1605253D01*
X1750916Y1605511D01*
X1750571Y1605666D01*
X1750226Y1605614D01*
X1749881Y1605408D01*
G01X1753518Y1602463D02*
X1753441Y1602514D01*
Y1602618D01*
X1753518Y1602669D01*
X1753595Y1602618D01*
Y1602514D01*
X1753518Y1602463D01*
G01Y1603858D02*
X1753441Y1603909D01*
Y1604013D01*
X1753518Y1604064D01*
X1753595Y1604013D01*
Y1603909D01*
X1753518Y1603858D01*
G01X1760561Y1605408D02*
X1760331Y1605563D01*
X1760063Y1605666D01*
X1759756D01*
X1759411Y1605511D01*
X1759143Y1605253D01*
X1758951Y1604943D01*
X1758798Y1604426D01*
X1758760Y1603961D01*
X1758836Y1603496D01*
X1758951Y1603186D01*
X1759181Y1602876D01*
X1759450Y1602669D01*
X1759718Y1602566D01*
X1759986D01*
X1760255Y1602669D01*
X1760485Y1602824D01*
X1760676Y1603031D01*
G01X1762051Y1602566D02*
Y1605666D01*
X1762971D01*
X1763278Y1605511D01*
X1763508Y1605149D01*
X1763585Y1604736D01*
X1763508Y1604323D01*
X1763316Y1604013D01*
X1762971Y1603858D01*
X1762051D01*
G01X1765075Y1605666D02*
Y1603444D01*
X1765228Y1602979D01*
X1765535Y1602669D01*
X1765918Y1602566D01*
X1766301Y1602669D01*
X1766608Y1602979D01*
X1766761Y1603444D01*
Y1605666D01*
G01X1769018Y1602566D02*
Y1605666D01*
X1768558Y1605046D01*
G01Y1602566D02*
X1769478D01*
G01X1774451D02*
Y1605666D01*
X1775371D01*
X1775678Y1605511D01*
X1775908Y1605149D01*
X1775985Y1604736D01*
X1775908Y1604323D01*
X1775716Y1604013D01*
X1775371Y1603858D01*
X1774451D01*
G01X1779161Y1605408D02*
X1778931Y1605563D01*
X1778663Y1605666D01*
X1778356D01*
X1778011Y1605511D01*
X1777743Y1605253D01*
X1777551Y1604943D01*
X1777398Y1604426D01*
X1777360Y1603961D01*
X1777436Y1603496D01*
X1777551Y1603186D01*
X1777781Y1602876D01*
X1778050Y1602669D01*
X1778318Y1602566D01*
X1778586D01*
X1778855Y1602669D01*
X1779085Y1602824D01*
X1779276Y1603031D01*
G01X1780958Y1605666D02*
X1781878D01*
G01X1781418D02*
Y1602566D01*
G01X1780958D02*
X1781878D01*
G01X1785285D02*
X1783751D01*
Y1605666D01*
X1785285D01*
G01X1784671Y1604168D02*
X1783751D01*
G01X1789760Y1602566D02*
X1790718Y1605666D01*
X1791676Y1602566D01*
G01X1791331Y1603651D02*
X1790105D01*
G01X1793051Y1605666D02*
Y1602566D01*
X1794585D01*
G01X1797685D02*
X1796151D01*
Y1605666D01*
X1797685D01*
G01X1797071Y1604168D02*
X1796151D01*
G01X1799251Y1602566D02*
Y1605666D01*
X1800210D01*
X1800516Y1605511D01*
X1800708Y1605304D01*
X1800785Y1604891D01*
X1800708Y1604478D01*
X1800478Y1604219D01*
X1800210Y1604064D01*
X1799251D01*
G01X1800210D02*
X1800785Y1602566D01*
G01X1803118Y1605666D02*
Y1602566D01*
G01X1802236Y1605666D02*
X1804000D01*
G01X1738018Y1606466D02*
Y1609566D01*
X1737558Y1608946D01*
G01Y1606466D02*
X1738478D01*
G01X1743720Y1607499D02*
X1744716D01*
G01X1749690Y1609049D02*
X1749920Y1609359D01*
X1750188Y1609514D01*
X1750495Y1609566D01*
X1750878Y1609463D01*
X1751146Y1609204D01*
X1751223Y1608894D01*
X1751185Y1608584D01*
X1751031Y1608326D01*
X1750265Y1607809D01*
X1749920Y1607448D01*
X1749690Y1606931D01*
X1749613Y1606466D01*
X1751223D01*
G01X1753518Y1606363D02*
X1753441Y1606414D01*
Y1606518D01*
X1753518Y1606569D01*
X1753595Y1606518D01*
Y1606414D01*
X1753518Y1606363D01*
G01Y1607758D02*
X1753441Y1607809D01*
Y1607913D01*
X1753518Y1607964D01*
X1753595Y1607913D01*
Y1607809D01*
X1753518Y1607758D01*
G01X1760561Y1609308D02*
X1760331Y1609463D01*
X1760063Y1609566D01*
X1759756D01*
X1759411Y1609411D01*
X1759143Y1609153D01*
X1758951Y1608843D01*
X1758798Y1608326D01*
X1758760Y1607861D01*
X1758836Y1607396D01*
X1758951Y1607086D01*
X1759181Y1606776D01*
X1759450Y1606569D01*
X1759718Y1606466D01*
X1759986D01*
X1760255Y1606569D01*
X1760485Y1606724D01*
X1760676Y1606931D01*
G01X1762051Y1606466D02*
Y1609566D01*
X1762971D01*
X1763278Y1609411D01*
X1763508Y1609049D01*
X1763585Y1608636D01*
X1763508Y1608223D01*
X1763316Y1607913D01*
X1762971Y1607758D01*
X1762051D01*
G01X1765075Y1609566D02*
Y1607344D01*
X1765228Y1606879D01*
X1765535Y1606569D01*
X1765918Y1606466D01*
X1766301Y1606569D01*
X1766608Y1606879D01*
X1766761Y1607344D01*
Y1609566D01*
G01X1769018D02*
X1768711Y1609463D01*
X1768481Y1609204D01*
X1768328Y1608894D01*
X1768213Y1608481D01*
X1768175Y1608016D01*
X1768213Y1607551D01*
X1768328Y1607138D01*
X1768481Y1606828D01*
X1768711Y1606569D01*
X1769018Y1606466D01*
X1769325Y1606569D01*
X1769555Y1606828D01*
X1769708Y1607138D01*
X1769823Y1607551D01*
X1769861Y1608016D01*
X1769823Y1608481D01*
X1769708Y1608894D01*
X1769555Y1609204D01*
X1769325Y1609463D01*
X1769018Y1609566D01*
G01X1774451Y1606466D02*
Y1609566D01*
X1775371D01*
X1775678Y1609411D01*
X1775908Y1609049D01*
X1775985Y1608636D01*
X1775908Y1608223D01*
X1775716Y1607913D01*
X1775371Y1607758D01*
X1774451D01*
G01X1779161Y1609308D02*
X1778931Y1609463D01*
X1778663Y1609566D01*
X1778356D01*
X1778011Y1609411D01*
X1777743Y1609153D01*
X1777551Y1608843D01*
X1777398Y1608326D01*
X1777360Y1607861D01*
X1777436Y1607396D01*
X1777551Y1607086D01*
X1777781Y1606776D01*
X1778050Y1606569D01*
X1778318Y1606466D01*
X1778586D01*
X1778855Y1606569D01*
X1779085Y1606724D01*
X1779276Y1606931D01*
G01X1780958Y1609566D02*
X1781878D01*
G01X1781418D02*
Y1606466D01*
G01X1780958D02*
X1781878D01*
G01X1785285D02*
X1783751D01*
Y1609566D01*
X1785285D01*
G01X1784671Y1608068D02*
X1783751D01*
G01X1789760Y1606466D02*
X1790718Y1609566D01*
X1791676Y1606466D01*
G01X1791331Y1607551D02*
X1790105D01*
G01X1793051Y1609566D02*
Y1606466D01*
X1794585D01*
G01X1797685D02*
X1796151D01*
Y1609566D01*
X1797685D01*
G01X1797071Y1608068D02*
X1796151D01*
G01X1799251Y1606466D02*
Y1609566D01*
X1800210D01*
X1800516Y1609411D01*
X1800708Y1609204D01*
X1800785Y1608791D01*
X1800708Y1608378D01*
X1800478Y1608119D01*
X1800210Y1607964D01*
X1799251D01*
G01X1800210D02*
X1800785Y1606466D01*
G01X1803118Y1609566D02*
Y1606466D01*
G01X1802236Y1609566D02*
X1804000D01*
G01X1738826Y74930D02*
Y68930D01*
G01X1738600Y83474D02*
Y77474D01*
G01X1737718Y90387D02*
Y87187D01*
G01X1753463Y105645D02*
X1753623Y105895D01*
X1753810Y106020D01*
X1754023Y106062D01*
X1754290Y105979D01*
X1754477Y105770D01*
X1754530Y105520D01*
X1754503Y105270D01*
X1754397Y105062D01*
X1753863Y104645D01*
X1753623Y104354D01*
X1753463Y103937D01*
X1753410Y103562D01*
X1754530D01*
G01X1756170Y106062D02*
X1755957Y105979D01*
X1755797Y105770D01*
X1755690Y105520D01*
X1755610Y105187D01*
X1755583Y104812D01*
X1755610Y104437D01*
X1755690Y104104D01*
X1755797Y103854D01*
X1755957Y103645D01*
X1756170Y103562D01*
X1756383Y103645D01*
X1756543Y103854D01*
X1756650Y104104D01*
X1756730Y104437D01*
X1756757Y104812D01*
X1756730Y105187D01*
X1756650Y105520D01*
X1756543Y105770D01*
X1756383Y105979D01*
X1756170Y106062D01*
G01X1747288Y98707D02*
Y101907D01*
G01X1753488Y98707D02*
X1747288D01*
G01X1753488Y101907D02*
Y98707D01*
G01X1747288Y101907D02*
X1753488D01*
G01X1753323Y113975D02*
X1753483Y114225D01*
X1753670Y114350D01*
X1753883Y114392D01*
X1754150Y114309D01*
X1754337Y114100D01*
X1754390Y113850D01*
X1754363Y113600D01*
X1754257Y113392D01*
X1753723Y112975D01*
X1753483Y112684D01*
X1753323Y112267D01*
X1753270Y111892D01*
X1754390D01*
G01X1756030D02*
Y114392D01*
X1755710Y113892D01*
G01Y111892D02*
X1756350D01*
G01X1757430Y111059D02*
X1759030D01*
G01X1759923Y113975D02*
X1760083Y114225D01*
X1760270Y114350D01*
X1760483Y114392D01*
X1760750Y114309D01*
X1760937Y114100D01*
X1760990Y113850D01*
X1760963Y113600D01*
X1760857Y113392D01*
X1760323Y112975D01*
X1760083Y112684D01*
X1759923Y112267D01*
X1759870Y111892D01*
X1760990D01*
G01X1762123Y113975D02*
X1762283Y114225D01*
X1762470Y114350D01*
X1762683Y114392D01*
X1762950Y114309D01*
X1763137Y114100D01*
X1763190Y113850D01*
X1763163Y113600D01*
X1763057Y113392D01*
X1762523Y112975D01*
X1762283Y112684D01*
X1762123Y112267D01*
X1762070Y111892D01*
X1763190D01*
G01X1751587Y104825D02*
Y107966D01*
G01Y117029D02*
X1750414D01*
G01X1751587Y113888D02*
Y117029D01*
G01X1750422Y104825D02*
X1751587D01*
G01Y109977D02*
Y111877D01*
G01X1738018Y129767D02*
Y123567D01*
G01X1748518D02*
X1745318D01*
G01X1748518Y129767D02*
Y123567D01*
G01X1745318Y129767D02*
X1748518D01*
G01X1745318Y123567D02*
Y129767D01*
G01X1749318D02*
X1752518D01*
G01X1749318Y123567D02*
Y129767D01*
G01X1752518Y123567D02*
X1749318D01*
G01X1752518Y129767D02*
Y123567D01*
G01X1745018Y127067D02*
X1741818D01*
G01X1745018Y133267D02*
Y127067D01*
G01X1741818Y133267D02*
X1745018D01*
G01X1741818Y127067D02*
Y133267D01*
G01X1746658Y149460D02*
X1756162D01*
G01X1746658Y161664D02*
Y149460D01*
G01X1742317Y166129D02*
Y163907D01*
X1742470Y163442D01*
X1742777Y163132D01*
X1743160Y163029D01*
X1743543Y163132D01*
X1743850Y163442D01*
X1744003Y163907D01*
Y166129D01*
G01X1745532Y165612D02*
X1745762Y165922D01*
X1746030Y166077D01*
X1746337Y166129D01*
X1746720Y166026D01*
X1746988Y165767D01*
X1747065Y165457D01*
X1747027Y165147D01*
X1746873Y164889D01*
X1746107Y164372D01*
X1745762Y164011D01*
X1745532Y163494D01*
X1745455Y163029D01*
X1747065D01*
G01X1749820D02*
Y166129D01*
X1748402Y163907D01*
X1750318D01*
G01X1752460Y166129D02*
X1752153Y166026D01*
X1751923Y165767D01*
X1751770Y165457D01*
X1751655Y165044D01*
X1751617Y164579D01*
X1751655Y164114D01*
X1751770Y163701D01*
X1751923Y163391D01*
X1752153Y163132D01*
X1752460Y163029D01*
X1752767Y163132D01*
X1752997Y163391D01*
X1753150Y163701D01*
X1753265Y164114D01*
X1753303Y164579D01*
X1753265Y165044D01*
X1753150Y165457D01*
X1752997Y165767D01*
X1752767Y166026D01*
X1752460Y166129D01*
G01X1754412Y161664D02*
X1751410Y158062D01*
G01X1748408Y161664D02*
X1746658D01*
G01X1751410Y158062D02*
X1748408Y161664D01*
G01X1745708Y169765D02*
Y181969D01*
G01X1757232Y169765D02*
X1745708D01*
G01X1751470Y178867D02*
X1754470Y181969D01*
G01X1748368D02*
X1751470Y178867D01*
G01X1745708Y181969D02*
X1748368D01*
G01X1750050Y207022D02*
Y195022D01*
G01X1744050D02*
Y207022D01*
G01X1750050Y195022D02*
X1744050D01*
G01X1743120Y207092D02*
Y195092D01*
G01X1750724Y198892D02*
Y205092D01*
G01X1753924Y198892D02*
X1750724D01*
G01X1749559Y189109D02*
X1755759D01*
G01X1749559Y185909D02*
Y189109D01*
G01X1755759Y185909D02*
X1749559D01*
G01X1744050Y207022D02*
X1750050D01*
G01X1741484Y216024D02*
Y272324D01*
G01X1756478Y216024D02*
X1741484D01*
G01X1750724Y205092D02*
X1753924D01*
G01X1748547Y277963D02*
Y288163D01*
G01X1753147Y277963D02*
X1748547D01*
G01X1753147Y288163D02*
Y277963D01*
G01X1741484Y272324D02*
X1756478D01*
G01X1747966Y281932D02*
X1744766D01*
G01X1747966Y288132D02*
Y281932D01*
G01X1744766D02*
Y288132D01*
G01X1742700Y293862D02*
X1747300D01*
G01Y288762D02*
X1742700D01*
G01X1747300Y298962D02*
Y288762D01*
G01X1742700D02*
Y298962D01*
G01X1748200Y294762D02*
Y304962D01*
X1752800D01*
Y294762D01*
X1748200D01*
G01X1753147Y283063D02*
X1748547D01*
G01Y288163D02*
X1753147D01*
G01X1744766Y288132D02*
X1747966D01*
G01X1742700Y298962D02*
X1747300D01*
G01X1748200Y299862D02*
X1752800D01*
G01X1756563Y303317D02*
X1753363D01*
G01Y309517D02*
X1756563D01*
G01X1753363Y303317D02*
Y309517D01*
G01X1749487Y362448D02*
Y365648D01*
G01X1755687Y362448D02*
X1749487D01*
G01X1740898Y364478D02*
X1738945D01*
G01X1740898Y366431D02*
Y364478D01*
G01Y376290D02*
Y374337D01*
G01X1738945Y376290D02*
X1740898D01*
G01X1749487Y365648D02*
X1755687D01*
G01X1749620Y379052D02*
X1755820D01*
G01X1749620Y375852D02*
Y379052D01*
G01X1755820Y375852D02*
X1749620D01*
G01Y370852D02*
Y374052D01*
G01X1755820Y370852D02*
X1749620D01*
G01Y374052D02*
X1755820D01*
G01X1749487Y369648D02*
X1755687D01*
G01X1749487Y366448D02*
Y369648D01*
G01X1755687Y366448D02*
X1749487D01*
G01X1749620Y384552D02*
X1755820D01*
G01X1749620Y381352D02*
Y384552D01*
G01X1755820Y381352D02*
X1749620D01*
G01X1741570Y403700D02*
Y409900D01*
X1744770D01*
Y403700D01*
X1741570D01*
G01X1750447Y453259D02*
Y451037D01*
X1750600Y450572D01*
X1750907Y450262D01*
X1751290Y450159D01*
X1751673Y450262D01*
X1751980Y450572D01*
X1752133Y451037D01*
Y453259D01*
G01X1753662Y452742D02*
X1753892Y453052D01*
X1754160Y453207D01*
X1754467Y453259D01*
X1754850Y453156D01*
X1755118Y452897D01*
X1755195Y452587D01*
X1755157Y452277D01*
X1755003Y452019D01*
X1754237Y451502D01*
X1753892Y451141D01*
X1753662Y450624D01*
X1753585Y450159D01*
X1755195D01*
G01X1757490Y453259D02*
X1757183Y453156D01*
X1756953Y452897D01*
X1756800Y452587D01*
X1756685Y452174D01*
X1756647Y451709D01*
X1756685Y451244D01*
X1756800Y450831D01*
X1756953Y450521D01*
X1757183Y450262D01*
X1757490Y450159D01*
X1757797Y450262D01*
X1758027Y450521D01*
X1758180Y450831D01*
X1758295Y451244D01*
X1758333Y451709D01*
X1758295Y452174D01*
X1758180Y452587D01*
X1758027Y452897D01*
X1757797Y453156D01*
X1757490Y453259D01*
G01X1760590Y450159D02*
X1760858Y450211D01*
X1761165Y450366D01*
X1761357Y450624D01*
X1761433Y450986D01*
X1761357Y451347D01*
X1761127Y451657D01*
X1760782Y451812D01*
X1760398D01*
X1760168Y451916D01*
X1759977Y452174D01*
X1759900Y452536D01*
X1760015Y452897D01*
X1760283Y453156D01*
X1760590Y453259D01*
X1760897Y453156D01*
X1761165Y452897D01*
X1761280Y452536D01*
X1761203Y452174D01*
X1761012Y451916D01*
X1760782Y451812D01*
X1760398D01*
X1760053Y451657D01*
X1759823Y451347D01*
X1759747Y450986D01*
X1759823Y450624D01*
X1760015Y450366D01*
X1760322Y450211D01*
X1760590Y450159D01*
G01X1738211Y495367D02*
Y489167D01*
G01X1740801Y488437D02*
Y485237D01*
G01X1752977Y702940D02*
X1764977D01*
G01X1752977Y696940D02*
Y702940D01*
G01X1764977Y696940D02*
X1752977D01*
G01X1752771Y705121D02*
Y711121D01*
G01X1764771Y705121D02*
X1752771D01*
G01X1749035Y701255D02*
Y695166D01*
G01X1745167Y700542D02*
Y697211D01*
G01D02*
X1748140D01*
G01X1750810D02*
X1752120D01*
G01X1741057D02*
Y1310442D01*
G01X1752819Y721523D02*
Y727523D01*
G01X1764819Y721523D02*
X1752819D01*
G01X1752795Y719472D02*
X1764795D01*
G01X1752795Y713472D02*
Y719472D01*
G01X1764795Y713472D02*
X1752795D01*
G01X1752771Y711121D02*
X1764771D01*
G01X1749035Y721544D02*
Y715455D01*
G01X1745167Y1310742D02*
Y716702D01*
G01X1752819Y727523D02*
X1764819D01*
G01X1770757Y732644D02*
X1745167D01*
G01X1770757Y1299574D02*
X1745167D01*
G01X1740342Y1313764D02*
X1756032D01*
G01X1740342Y1325772D02*
Y1313764D01*
G01X1746444Y1331185D02*
Y1328963D01*
X1746597Y1328498D01*
X1746904Y1328188D01*
X1747287Y1328085D01*
X1747670Y1328188D01*
X1747977Y1328498D01*
X1748130Y1328963D01*
Y1331185D01*
G01X1750387Y1328085D02*
Y1331185D01*
X1749927Y1330565D01*
G01Y1328085D02*
X1750847D01*
G01X1753487Y1331185D02*
X1753180Y1331082D01*
X1752950Y1330823D01*
X1752797Y1330513D01*
X1752682Y1330100D01*
X1752644Y1329635D01*
X1752682Y1329170D01*
X1752797Y1328757D01*
X1752950Y1328447D01*
X1753180Y1328188D01*
X1753487Y1328085D01*
X1753794Y1328188D01*
X1754024Y1328447D01*
X1754177Y1328757D01*
X1754292Y1329170D01*
X1754330Y1329635D01*
X1754292Y1330100D01*
X1754177Y1330513D01*
X1754024Y1330823D01*
X1753794Y1331082D01*
X1753487Y1331185D01*
G01X1755859Y1330668D02*
X1756089Y1330978D01*
X1756357Y1331133D01*
X1756664Y1331185D01*
X1757047Y1331082D01*
X1757315Y1330823D01*
X1757392Y1330513D01*
X1757354Y1330203D01*
X1757200Y1329945D01*
X1756434Y1329428D01*
X1756089Y1329067D01*
X1755859Y1328550D01*
X1755782Y1328085D01*
X1757392D01*
G01X1756032Y1325772D02*
X1740342D01*
G01X1743845Y1336996D02*
X1744037Y1336686D01*
X1744267Y1336479D01*
X1744535Y1336376D01*
X1744842Y1336479D01*
X1745072Y1336686D01*
X1745302Y1336996D01*
X1745379Y1337409D01*
Y1339476D01*
G01X1747712Y1336376D02*
Y1339476D01*
X1747252Y1338856D01*
G01Y1336376D02*
X1748172D01*
G01X1749969Y1336996D02*
X1750199Y1336634D01*
X1750505Y1336428D01*
X1750850Y1336376D01*
X1751157Y1336428D01*
X1751464Y1336686D01*
X1751655Y1336996D01*
X1751694Y1337306D01*
X1751617Y1337668D01*
X1751349Y1337926D01*
X1751080Y1338029D01*
X1750735D01*
G01X1751080D02*
X1751310Y1338184D01*
X1751502Y1338443D01*
X1751579Y1338753D01*
X1751502Y1339063D01*
X1751310Y1339321D01*
X1750965Y1339476D01*
X1750620Y1339424D01*
X1750275Y1339218D01*
G01X1760290Y1335007D02*
X1745167D01*
G01D02*
Y1331922D01*
G01X1741057Y1332122D02*
Y1335007D01*
G01X1739835Y1450241D02*
Y1453441D01*
G01X1746035Y1450241D02*
X1739835D01*
G01X1746035Y1453441D02*
Y1450241D01*
G01X1739835Y1453441D02*
X1746035D01*
G01X1737745Y1460671D02*
X1749745D01*
G01X1737745Y1454671D02*
Y1460671D01*
G01X1749745Y1454671D02*
X1737745D01*
G01X1749745Y1460671D02*
Y1454671D01*
G01X1748044Y1469735D02*
X1747111D01*
G01X1748044Y1488239D02*
Y1469735D01*
G01X1750645Y1486371D02*
Y1492371D01*
G01X1762645Y1486371D02*
X1750645D01*
G01Y1485171D02*
X1762645D01*
G01X1750645Y1479171D02*
Y1485171D01*
G01X1762645Y1479171D02*
X1750645D01*
G01X1752925Y1474351D02*
Y1477551D01*
G01X1759125Y1474351D02*
X1752925D01*
G01Y1477551D02*
X1759125D01*
G01X1750645Y1492371D02*
X1762645D01*
G01X1747411Y1488239D02*
X1748044D01*
G01X1740881Y1509011D02*
Y1495935D01*
G01D02*
X1784881D01*
G01X1740881Y1536487D02*
Y1523311D01*
G01X1784881Y1536487D02*
X1740881D01*
G01X1749619Y1558570D02*
X1755619D01*
Y1564570D01*
G01Y1593909D02*
Y1599909D01*
X1749619D01*
G01X1751844Y1724217D02*
Y1727317D01*
G01X1753454D02*
Y1724217D01*
G01Y1725767D02*
X1751844D01*
G01X1755097Y1724579D02*
X1755366Y1724320D01*
X1755672Y1724217D01*
X1755979Y1724320D01*
X1756247Y1724630D01*
X1756439Y1725095D01*
X1756516Y1725560D01*
Y1726129D01*
X1756439Y1726594D01*
X1756247Y1727007D01*
X1756017Y1727214D01*
X1755749Y1727317D01*
X1755442Y1727214D01*
X1755212Y1727007D01*
X1755059Y1726697D01*
X1754982Y1726284D01*
X1755059Y1725922D01*
X1755251Y1725560D01*
X1755481Y1725354D01*
X1755749Y1725302D01*
X1756056Y1725405D01*
X1756286Y1725664D01*
X1756516Y1726129D01*
G01X1758849Y1727317D02*
X1758542Y1727214D01*
X1758312Y1726955D01*
X1758159Y1726645D01*
X1758044Y1726232D01*
X1758006Y1725767D01*
X1758044Y1725302D01*
X1758159Y1724889D01*
X1758312Y1724579D01*
X1758542Y1724320D01*
X1758849Y1724217D01*
X1759156Y1724320D01*
X1759386Y1724579D01*
X1759539Y1724889D01*
X1759654Y1725302D01*
X1759692Y1725767D01*
X1759654Y1726232D01*
X1759539Y1726645D01*
X1759386Y1726955D01*
X1759156Y1727214D01*
X1758849Y1727317D01*
G01X1760350Y51096D02*
X1796341D01*
G01X1766038Y68016D02*
Y74216D01*
G01X1769238Y68016D02*
X1766038D01*
G01X1769238Y74216D02*
Y68016D01*
G01X1758938Y71037D02*
Y74237D01*
G01X1765138Y71037D02*
X1758938D01*
G01X1765138Y74237D02*
Y71037D01*
G01Y70237D02*
Y67037D01*
G01X1758938Y70237D02*
X1765138D01*
G01X1758938Y67037D02*
Y70237D01*
G01X1765138Y67037D02*
X1758938D01*
G01X1758968Y75197D02*
Y78397D01*
G01X1765168Y75197D02*
X1758968D01*
G01X1765168Y78397D02*
Y75197D01*
G01X1758968Y78397D02*
X1765168D01*
G01X1766038Y74216D02*
X1769238D01*
G01X1765648Y85207D02*
Y82007D01*
G01X1759448Y85207D02*
X1765648D01*
G01X1759448Y82007D02*
Y85207D01*
G01X1765648Y82007D02*
X1759448D01*
G01X1765648Y88707D02*
Y85507D01*
G01X1759448D02*
Y88707D01*
G01X1765648Y85507D02*
X1759448D01*
G01X1758938Y74237D02*
X1765138D01*
G01X1758628Y103597D02*
Y106697D01*
X1759548D01*
X1759855Y106542D01*
X1760085Y106180D01*
X1760162Y105767D01*
X1760085Y105354D01*
X1759893Y105044D01*
X1759548Y104889D01*
X1758628D01*
G01X1761652Y106697D02*
Y104475D01*
X1761805Y104010D01*
X1762112Y103700D01*
X1762495Y103597D01*
X1762878Y103700D01*
X1763185Y104010D01*
X1763338Y104475D01*
Y106697D01*
G01X1764867Y106180D02*
X1765097Y106490D01*
X1765365Y106645D01*
X1765672Y106697D01*
X1766055Y106594D01*
X1766323Y106335D01*
X1766400Y106025D01*
X1766362Y105715D01*
X1766208Y105457D01*
X1765442Y104940D01*
X1765097Y104579D01*
X1764867Y104062D01*
X1764790Y103597D01*
X1766400D01*
G01X1768695Y106697D02*
X1768388Y106594D01*
X1768158Y106335D01*
X1768005Y106025D01*
X1767890Y105612D01*
X1767852Y105147D01*
X1767890Y104682D01*
X1768005Y104269D01*
X1768158Y103959D01*
X1768388Y103700D01*
X1768695Y103597D01*
X1769002Y103700D01*
X1769232Y103959D01*
X1769385Y104269D01*
X1769500Y104682D01*
X1769538Y105147D01*
X1769500Y105612D01*
X1769385Y106025D01*
X1769232Y106335D01*
X1769002Y106594D01*
X1768695Y106697D01*
G01X1772255Y103597D02*
Y106697D01*
X1770837Y104475D01*
X1772753D01*
G01X1766291Y101920D02*
X1769491D01*
G01X1766291Y95720D02*
Y101920D01*
G01X1769491Y95720D02*
X1766291D01*
G01X1769491Y101920D02*
Y95720D01*
G01X1767178Y94491D02*
X1773378D01*
G01X1767178Y91291D02*
Y94491D01*
G01X1773378Y91291D02*
X1767178D01*
G01X1759448Y88707D02*
X1765648D01*
G01X1766078Y115527D02*
X1762878D01*
G01X1766078Y121727D02*
Y115527D01*
G01X1762878D02*
Y121727D01*
G01D02*
X1766078D01*
G01X1756162Y149460D02*
Y161664D01*
G01D02*
X1754412D01*
G01X1761910Y162762D02*
Y165962D01*
G01X1768110Y162762D02*
X1761910D01*
G01X1768110Y165962D02*
Y162762D01*
G01X1761910Y165962D02*
X1768110D01*
G01X1757232Y181969D02*
Y169765D01*
G01X1754470Y181969D02*
X1757232D01*
G01X1753924Y205092D02*
Y198892D01*
G01X1755759Y189109D02*
Y185909D01*
G01X1756404Y199711D02*
X1783176D01*
G01D02*
G03I-13386J0D01*
G01X1755390Y277710D02*
Y275502D01*
G01D02*
X1757629D01*
G01X1755390Y299518D02*
Y297430D01*
G01X1757429Y299518D02*
X1755390D01*
G01X1770830Y303317D02*
X1767630D01*
G01Y309517D02*
X1770830D01*
G01X1767630Y303317D02*
Y309517D01*
G01X1760163Y303317D02*
X1756963D01*
G01X1760163Y309517D02*
Y303317D01*
G01X1756963Y309517D02*
X1760163D01*
G01X1756963Y303317D02*
Y309517D01*
G01X1767263Y303317D02*
X1764063D01*
G01X1767263Y309517D02*
Y303317D01*
G01X1764063Y309517D02*
X1767263D01*
G01X1764063Y303317D02*
Y309517D01*
G01X1763763Y303317D02*
X1760563D01*
G01X1763763Y309517D02*
Y303317D01*
G01X1760563Y309517D02*
X1763763D01*
G01X1760563Y303317D02*
Y309517D01*
G01X1756563D02*
Y303317D01*
G01X1755687Y365648D02*
Y362448D01*
G01X1769527Y365748D02*
Y362548D01*
G01X1763327D02*
Y365748D01*
G01X1769527Y362548D02*
X1763327D01*
G01X1769320Y374052D02*
Y370852D01*
G01X1763120Y374052D02*
X1769320D01*
G01X1763120Y370852D02*
Y374052D01*
G01X1769320Y370852D02*
X1763120D01*
G01X1763327Y365748D02*
X1769527D01*
G01X1755820Y379052D02*
Y375852D01*
G01Y374052D02*
Y370852D01*
G01X1755687Y369648D02*
Y366448D01*
G01X1769527Y369748D02*
Y366548D01*
G01X1763327Y369748D02*
X1769527D01*
G01X1763327Y366548D02*
Y369748D01*
G01X1769527Y366548D02*
X1763327D01*
G01X1769320Y379052D02*
Y375852D01*
G01X1763120Y379052D02*
X1769320D01*
G01X1763120Y375852D02*
Y379052D01*
G01X1769320Y375852D02*
X1763120D01*
G01X1755820Y384552D02*
Y381352D01*
G01X1765806Y425188D02*
Y422966D01*
X1765959Y422501D01*
X1766266Y422191D01*
X1766649Y422088D01*
X1767032Y422191D01*
X1767339Y422501D01*
X1767492Y422966D01*
Y425188D01*
G01X1770209Y422088D02*
Y425188D01*
X1768791Y422966D01*
X1770707D01*
G01X1772197Y422450D02*
X1772466Y422191D01*
X1772772Y422088D01*
X1773079Y422191D01*
X1773347Y422501D01*
X1773539Y422966D01*
X1773616Y423431D01*
Y424000D01*
X1773539Y424465D01*
X1773347Y424878D01*
X1773117Y425085D01*
X1772849Y425188D01*
X1772542Y425085D01*
X1772312Y424878D01*
X1772159Y424568D01*
X1772082Y424155D01*
X1772159Y423793D01*
X1772351Y423431D01*
X1772581Y423225D01*
X1772849Y423173D01*
X1773156Y423276D01*
X1773386Y423535D01*
X1773616Y424000D01*
G01X1766174Y427651D02*
Y440132D01*
G01X1781528Y427454D02*
X1766174D01*
G01Y440132D02*
X1781528D01*
G01X1763308Y456086D02*
Y442438D01*
G01D02*
X1775512D01*
G01X1755541Y431621D02*
Y434821D01*
G01X1761741Y431621D02*
X1755541D01*
G01X1761741Y434821D02*
Y431621D01*
G01X1755541Y434821D02*
X1761741D01*
G01X1775512Y456086D02*
X1763308D01*
G01X1768451Y459793D02*
Y462993D01*
G01X1774651Y459793D02*
X1768451D01*
G01X1758641D02*
Y462993D01*
G01X1764841Y459793D02*
X1758641D01*
G01X1764841Y462993D02*
Y459793D01*
G01X1768451Y462993D02*
X1774651D01*
G01X1758641D02*
X1764841D01*
G01X1768451Y467493D02*
X1774651D01*
G01X1768451Y464293D02*
Y467493D01*
G01X1774651Y464293D02*
X1768451D01*
G01X1758751D02*
Y467493D01*
G01X1764951Y464293D02*
X1758751D01*
G01X1764951Y467493D02*
Y464293D01*
G01X1758751Y467493D02*
X1764951D01*
G01X1768451Y471793D02*
X1774651D01*
G01X1768451Y468593D02*
Y471793D01*
G01X1774651Y468593D02*
X1768451D01*
G01X1764977Y702940D02*
Y696940D01*
G01X1764771Y711121D02*
Y705121D01*
G01X1766470Y697211D02*
X1770757D01*
G01X1756156Y691142D02*
Y694342D01*
G01X1762356Y691142D02*
X1756156D01*
G01X1762356Y694342D02*
Y691142D01*
G01X1756156Y694342D02*
X1762356D01*
G01X1764819Y727523D02*
Y721523D01*
G01X1764795Y719472D02*
Y713472D01*
G01X1762197Y1304811D02*
Y1336611D01*
G01X1775997Y1304811D02*
X1762197D01*
G01X1756032Y1313764D02*
Y1325772D01*
G01X1762197Y1336611D02*
X1775997D01*
G01X1762645Y1492371D02*
Y1486371D01*
G01Y1485171D02*
Y1479171D01*
G01X1759125Y1477551D02*
Y1474351D01*
G01X1767766Y1614657D02*
X1767958Y1614347D01*
X1768188Y1614140D01*
X1768456Y1614037D01*
X1768763Y1614140D01*
X1768993Y1614347D01*
X1769223Y1614657D01*
X1769300Y1615070D01*
Y1617137D01*
G01X1770866Y1614037D02*
Y1617137D01*
X1771786D01*
X1772093Y1616982D01*
X1772323Y1616620D01*
X1772400Y1616207D01*
X1772323Y1615794D01*
X1772131Y1615484D01*
X1771786Y1615329D01*
X1770866D01*
G01X1774656Y1614037D02*
X1774733Y1614709D01*
X1774848Y1615277D01*
X1775001Y1615794D01*
X1775193Y1616362D01*
X1775500Y1617137D01*
X1773966D01*
G01X1766536Y1619449D02*
Y1649843D01*
G01X1776378Y1619449D02*
X1766536D01*
G01Y1649843D02*
X1776378D01*
G01X1777279Y1714960D02*
G02I-10350J0D01*
G01X1794181Y43779D02*
X1783031D01*
G01X1772525Y61337D02*
X1774951D01*
G01X1776065Y55289D02*
Y66785D01*
G01X1805624Y55289D02*
X1776065D01*
G01Y66785D02*
X1805624D01*
G01X1784536Y78503D02*
Y86691D01*
G01X1770560Y78503D02*
X1784536D01*
G01X1770560Y86691D02*
Y78503D01*
G01X1784536Y86691D02*
X1770560D01*
G01X1785743Y104302D02*
Y107402D01*
X1786663D01*
X1786970Y107247D01*
X1787200Y106885D01*
X1787277Y106472D01*
X1787200Y106059D01*
X1787008Y105749D01*
X1786663Y105594D01*
X1785743D01*
G01X1788767Y107402D02*
Y105180D01*
X1788920Y104715D01*
X1789227Y104405D01*
X1789610Y104302D01*
X1789993Y104405D01*
X1790300Y104715D01*
X1790453Y105180D01*
Y107402D01*
G01X1791982Y106885D02*
X1792212Y107195D01*
X1792480Y107350D01*
X1792787Y107402D01*
X1793170Y107299D01*
X1793438Y107040D01*
X1793515Y106730D01*
X1793477Y106420D01*
X1793323Y106162D01*
X1792557Y105645D01*
X1792212Y105284D01*
X1791982Y104767D01*
X1791905Y104302D01*
X1793515D01*
G01X1795810Y107402D02*
X1795503Y107299D01*
X1795273Y107040D01*
X1795120Y106730D01*
X1795005Y106317D01*
X1794967Y105852D01*
X1795005Y105387D01*
X1795120Y104974D01*
X1795273Y104664D01*
X1795503Y104405D01*
X1795810Y104302D01*
X1796117Y104405D01*
X1796347Y104664D01*
X1796500Y104974D01*
X1796615Y105387D01*
X1796653Y105852D01*
X1796615Y106317D01*
X1796500Y106730D01*
X1796347Y107040D01*
X1796117Y107299D01*
X1795810Y107402D01*
G01X1798067Y104922D02*
X1798297Y104560D01*
X1798603Y104354D01*
X1798948Y104302D01*
X1799255Y104354D01*
X1799562Y104612D01*
X1799753Y104922D01*
X1799792Y105232D01*
X1799715Y105594D01*
X1799447Y105852D01*
X1799178Y105955D01*
X1798833D01*
G01X1799178D02*
X1799408Y106110D01*
X1799600Y106369D01*
X1799677Y106679D01*
X1799600Y106989D01*
X1799408Y107247D01*
X1799063Y107402D01*
X1798718Y107350D01*
X1798373Y107144D01*
G01X1773378Y94491D02*
Y91291D01*
G01X1780578Y98527D02*
X1786778D01*
G01X1780578Y95327D02*
Y98527D01*
G01X1786778Y95327D02*
X1780578D01*
G01Y91327D02*
Y94527D01*
G01X1786778Y91327D02*
X1780578D01*
G01Y94527D02*
X1786778D01*
G01X1780536Y102539D02*
X1786736D01*
G01X1780536Y99339D02*
Y102539D01*
G01X1786736Y99339D02*
X1780536D01*
G01X1770291Y101920D02*
X1773491D01*
G01X1770291Y95720D02*
Y101920D01*
G01X1773491Y95720D02*
X1770291D01*
G01X1773491Y101920D02*
Y95720D01*
G01X1785103Y118842D02*
Y121942D01*
X1786023D01*
X1786330Y121787D01*
X1786560Y121425D01*
X1786637Y121012D01*
X1786560Y120599D01*
X1786368Y120289D01*
X1786023Y120134D01*
X1785103D01*
G01X1788127Y118842D02*
Y121942D01*
X1788893D01*
X1789200Y121787D01*
X1789430Y121580D01*
X1789622Y121270D01*
X1789775Y120909D01*
X1789813Y120392D01*
X1789775Y119875D01*
X1789622Y119514D01*
X1789430Y119204D01*
X1789200Y118997D01*
X1788893Y118842D01*
X1788127D01*
G01X1792070D02*
Y121942D01*
X1791610Y121322D01*
G01Y118842D02*
X1792530D01*
G01X1795170Y121942D02*
X1794863Y121839D01*
X1794633Y121580D01*
X1794480Y121270D01*
X1794365Y120857D01*
X1794327Y120392D01*
X1794365Y119927D01*
X1794480Y119514D01*
X1794633Y119204D01*
X1794863Y118945D01*
X1795170Y118842D01*
X1795477Y118945D01*
X1795707Y119204D01*
X1795860Y119514D01*
X1795975Y119927D01*
X1796013Y120392D01*
X1795975Y120857D01*
X1795860Y121270D01*
X1795707Y121580D01*
X1795477Y121839D01*
X1795170Y121942D01*
G01X1798270Y118842D02*
Y121942D01*
X1797810Y121322D01*
G01Y118842D02*
X1798730D01*
G01X1776878Y108490D02*
Y106064D01*
G01X1780815Y109318D02*
Y128536D01*
G01X1772941Y109318D02*
X1780815D01*
G01X1772941Y128536D02*
Y109318D01*
G01X1777078Y118177D02*
Y117177D01*
G01X1778578Y121177D02*
X1777078Y118177D01*
G01D02*
X1775578Y121177D01*
G01X1778578Y118177D02*
X1775578D01*
G01X1776500Y135859D02*
Y133619D01*
G01X1778125Y134832D02*
X1774875D01*
G01X1780815Y128536D02*
X1772941D01*
G01X1777078Y121177D02*
Y122277D01*
G01X1775578Y121177D02*
X1778578D01*
G01X1786355Y162170D02*
Y159948D01*
X1786508Y159483D01*
X1786815Y159173D01*
X1787198Y159070D01*
X1787581Y159173D01*
X1787888Y159483D01*
X1788041Y159948D01*
Y162170D01*
G01X1790221Y159070D02*
X1790298Y159742D01*
X1790413Y160310D01*
X1790566Y160827D01*
X1790758Y161395D01*
X1791065Y162170D01*
X1789531D01*
G01X1792555Y159535D02*
X1792785Y159277D01*
X1793053Y159122D01*
X1793398Y159070D01*
X1793743Y159173D01*
X1794011Y159380D01*
X1794203Y159742D01*
X1794241Y160155D01*
X1794165Y160568D01*
X1793973Y160827D01*
X1793705Y161033D01*
X1793436Y161085D01*
X1793168Y161033D01*
X1792823Y160827D01*
X1792938Y162170D01*
X1793973D01*
G01X1770275Y168303D02*
Y171503D01*
G01X1776475Y168303D02*
X1770275D01*
G01X1776475Y171503D02*
Y168303D01*
G01Y175503D02*
Y172303D01*
G01X1770275Y175503D02*
X1776475D01*
G01X1770275Y172303D02*
Y175503D01*
G01X1776475Y172303D02*
X1770275D01*
G01X1776475Y180003D02*
Y176803D01*
G01X1770275Y180003D02*
X1776475D01*
G01X1770275Y176803D02*
Y180003D01*
G01X1776475Y176803D02*
X1770275D01*
G01Y171503D02*
X1776475D01*
G01X1785964Y199711D02*
X1812736D01*
G01D02*
G03I-13386J0D01*
G01X1777278Y216024D02*
X1792272D01*
G01X1781826Y274496D02*
Y286496D01*
G01X1787826Y274496D02*
X1781826D01*
G01X1775468Y275502D02*
Y277710D01*
G01X1773229Y275502D02*
X1775468D01*
G01X1792272Y272324D02*
X1777278D01*
G01X1777626Y276504D02*
Y282704D01*
G01X1780826Y276504D02*
X1777626D01*
G01X1780826Y282704D02*
Y276504D01*
G01X1781826Y286496D02*
X1787826D01*
G01X1775468Y297430D02*
Y299518D01*
G01X1777626Y282704D02*
X1780826D01*
G01X1778328Y290276D02*
Y293476D01*
G01X1784528Y290276D02*
X1778328D01*
G01X1784528Y293476D02*
Y290276D01*
G01X1778328Y293476D02*
X1784528D01*
G01X1778343Y294043D02*
Y297243D01*
G01X1784543Y294043D02*
X1778343D01*
G01X1784543Y297243D02*
Y294043D01*
G01X1778343Y297243D02*
X1784543D01*
G01X1778343Y297643D02*
Y300843D01*
G01X1784543Y297643D02*
X1778343D01*
G01X1784543Y300843D02*
Y297643D01*
G01X1775468Y299518D02*
X1773429D01*
G01X1770830Y309517D02*
Y303317D01*
G01X1778343Y300843D02*
X1784543D01*
G01X1774463Y303317D02*
X1771263D01*
G01X1774463Y309517D02*
Y303317D01*
G01X1771263Y309517D02*
X1774463D01*
G01X1771263Y303317D02*
Y309517D01*
G01X1783199Y402332D02*
Y405532D01*
G01X1789399Y402332D02*
X1783199D01*
G01Y405532D02*
X1789399D01*
G01X1783199Y408832D02*
Y412032D01*
G01X1789399Y408832D02*
X1783199D01*
G01Y412032D02*
X1789399D01*
G01X1781528Y440132D02*
Y427454D01*
G01X1783199Y417332D02*
Y420532D01*
G01X1789399Y417332D02*
X1783199D01*
G01Y420532D02*
X1789399D01*
G01X1783199Y423832D02*
Y427032D01*
G01X1789399Y423832D02*
X1783199D01*
G01Y427032D02*
X1789399D01*
G01X1775512Y442438D02*
Y446660D01*
G01X1777210Y442462D02*
Y448662D01*
G01X1780410Y442462D02*
X1777210D01*
G01X1780410Y448662D02*
Y442462D01*
G01X1772910Y449262D02*
X1775512Y451864D01*
G01D02*
Y456086D01*
G01Y446660D02*
X1772910Y449262D01*
G01X1777210Y448662D02*
X1780410D01*
G01X1774651Y462993D02*
Y459793D01*
G01X1777210Y450540D02*
Y456740D01*
X1780410D01*
Y450540D01*
X1777210D01*
G01X1774651Y467493D02*
Y464293D01*
G01Y471793D02*
Y468593D01*
G01X1774867Y697211D02*
X1800457D01*
G01X1774867Y1302872D02*
Y697211D01*
G01X1770757D02*
Y1302822D01*
G01X1800457Y732644D02*
X1774867D01*
G01X1800457Y1299574D02*
X1774867D01*
G01X1775997Y1336611D02*
Y1304811D01*
G01X1774867Y1328112D02*
Y1313662D01*
G01X1770757Y1314742D02*
Y1328172D01*
G01X1800457Y1335007D02*
X1779150D01*
G01X1784881Y1495935D02*
Y1508911D01*
G01Y1523411D02*
Y1536487D01*
G01X1772933Y1538272D02*
Y1541372D01*
X1773853D01*
X1774160Y1541217D01*
X1774390Y1540855D01*
X1774467Y1540442D01*
X1774390Y1540029D01*
X1774198Y1539719D01*
X1773853Y1539564D01*
X1772933D01*
G01X1776033Y1541372D02*
Y1538272D01*
X1777567D01*
G01X1779172Y1539564D02*
X1779440Y1539925D01*
X1779670Y1540132D01*
X1779977Y1540235D01*
X1780245Y1540132D01*
X1780437Y1539925D01*
X1780590Y1539615D01*
X1780628Y1539254D01*
X1780590Y1538944D01*
X1780437Y1538634D01*
X1780207Y1538375D01*
X1779938Y1538272D01*
X1779632Y1538375D01*
X1779363Y1538685D01*
X1779210Y1539150D01*
X1779172Y1539667D01*
X1779248Y1540339D01*
X1779363Y1540700D01*
X1779555Y1541062D01*
X1779823Y1541320D01*
X1780092Y1541372D01*
X1780360Y1541269D01*
X1780552Y1541010D01*
G01X1782157Y1538737D02*
X1782387Y1538479D01*
X1782655Y1538324D01*
X1783000Y1538272D01*
X1783345Y1538375D01*
X1783613Y1538582D01*
X1783805Y1538944D01*
X1783843Y1539357D01*
X1783767Y1539770D01*
X1783575Y1540029D01*
X1783307Y1540235D01*
X1783038Y1540287D01*
X1782770Y1540235D01*
X1782425Y1540029D01*
X1782540Y1541372D01*
X1783575D01*
G01X1785637Y1589722D02*
Y1592822D01*
G01X1787247D02*
Y1589722D01*
G01Y1591272D02*
X1785637D01*
G01X1788814Y1592305D02*
X1789044Y1592615D01*
X1789312Y1592770D01*
X1789619Y1592822D01*
X1790002Y1592719D01*
X1790270Y1592460D01*
X1790347Y1592150D01*
X1790309Y1591840D01*
X1790155Y1591582D01*
X1789389Y1591065D01*
X1789044Y1590704D01*
X1788814Y1590187D01*
X1788737Y1589722D01*
X1790347D01*
G01X1792565D02*
X1792642Y1590394D01*
X1792757Y1590962D01*
X1792910Y1591479D01*
X1793102Y1592047D01*
X1793409Y1592822D01*
X1791875D01*
G01X1776378Y1649843D02*
Y1619449D01*
G01X1777717Y1644253D02*
X1777947Y1643891D01*
X1778253Y1643685D01*
X1778598Y1643633D01*
X1778905Y1643685D01*
X1779212Y1643943D01*
X1779403Y1644253D01*
X1779442Y1644563D01*
X1779365Y1644925D01*
X1779097Y1645183D01*
X1778828Y1645286D01*
X1778483D01*
G01X1778828D02*
X1779058Y1645441D01*
X1779250Y1645700D01*
X1779327Y1646010D01*
X1779250Y1646320D01*
X1779058Y1646578D01*
X1778713Y1646733D01*
X1778368Y1646681D01*
X1778023Y1646475D01*
G01X1801675Y51104D02*
Y54204D01*
X1802595D01*
X1802902Y54049D01*
X1803132Y53687D01*
X1803209Y53274D01*
X1803132Y52861D01*
X1802940Y52551D01*
X1802595Y52396D01*
X1801675D01*
G01X1804699Y51104D02*
Y54204D01*
X1805465D01*
X1805772Y54049D01*
X1806002Y53842D01*
X1806194Y53532D01*
X1806347Y53171D01*
X1806385Y52654D01*
X1806347Y52137D01*
X1806194Y51776D01*
X1806002Y51466D01*
X1805772Y51259D01*
X1805465Y51104D01*
X1804699D01*
G01X1808642D02*
Y54204D01*
X1808182Y53584D01*
G01Y51104D02*
X1809102D01*
G01X1811742Y54204D02*
X1811435Y54101D01*
X1811205Y53842D01*
X1811052Y53532D01*
X1810937Y53119D01*
X1810899Y52654D01*
X1810937Y52189D01*
X1811052Y51776D01*
X1811205Y51466D01*
X1811435Y51207D01*
X1811742Y51104D01*
X1812049Y51207D01*
X1812279Y51466D01*
X1812432Y51776D01*
X1812547Y52189D01*
X1812585Y52654D01*
X1812547Y53119D01*
X1812432Y53532D01*
X1812279Y53842D01*
X1812049Y54101D01*
X1811742Y54204D01*
G01X1814114Y53687D02*
X1814344Y53997D01*
X1814612Y54152D01*
X1814919Y54204D01*
X1815302Y54101D01*
X1815570Y53842D01*
X1815647Y53532D01*
X1815609Y53222D01*
X1815455Y52964D01*
X1814689Y52447D01*
X1814344Y52086D01*
X1814114Y51569D01*
X1814037Y51104D01*
X1815647D01*
G01X1796307Y51142D02*
X1795800D01*
G01X1786063Y69387D02*
Y72587D01*
G01X1792263Y69387D02*
X1786063D01*
G01X1792263Y72587D02*
Y69387D01*
G01X1786063Y72587D02*
X1792263D01*
G01X1789138Y79587D02*
X1792338D01*
G01X1789138Y73387D02*
Y79587D01*
G01X1792338Y73387D02*
X1789138D01*
G01X1792338Y79587D02*
Y73387D01*
G01Y80767D02*
X1789138D01*
G01X1792338Y86967D02*
Y80767D01*
G01X1789138Y86967D02*
X1792338D01*
G01X1789138Y80767D02*
Y86967D01*
G01X1786778Y98527D02*
Y95327D01*
G01Y94527D02*
Y91327D01*
G01X1786736Y102539D02*
Y99339D01*
G01X1799725Y157732D02*
Y148874D01*
G01D02*
X1786371D01*
G01D02*
Y157732D01*
G01D02*
X1799725D01*
G01X1801690Y154957D02*
Y158157D01*
G01X1807890Y154957D02*
X1801690D01*
G01Y158157D02*
X1807890D01*
G01X1804399Y159865D02*
X1798199D01*
Y163065D01*
X1804399D01*
Y159865D01*
G01X1798165Y167165D02*
X1804365D01*
Y163965D01*
X1798165D01*
Y167165D01*
G01X1792272Y216024D02*
Y272324D01*
G01X1795753Y255742D02*
Y258842D01*
X1796673D01*
X1796980Y258687D01*
X1797210Y258325D01*
X1797287Y257912D01*
X1797210Y257499D01*
X1797018Y257189D01*
X1796673Y257034D01*
X1795753D01*
G01X1798853Y258842D02*
Y255742D01*
X1800387D01*
G01X1801992Y257034D02*
X1802260Y257395D01*
X1802490Y257602D01*
X1802797Y257705D01*
X1803065Y257602D01*
X1803257Y257395D01*
X1803410Y257085D01*
X1803448Y256724D01*
X1803410Y256414D01*
X1803257Y256104D01*
X1803027Y255845D01*
X1802758Y255742D01*
X1802452Y255845D01*
X1802183Y256155D01*
X1802030Y256620D01*
X1801992Y257137D01*
X1802068Y257809D01*
X1802183Y258170D01*
X1802375Y258532D01*
X1802643Y258790D01*
X1802912Y258842D01*
X1803180Y258739D01*
X1803372Y258480D01*
G01X1805092Y257034D02*
X1805360Y257395D01*
X1805590Y257602D01*
X1805897Y257705D01*
X1806165Y257602D01*
X1806357Y257395D01*
X1806510Y257085D01*
X1806548Y256724D01*
X1806510Y256414D01*
X1806357Y256104D01*
X1806127Y255845D01*
X1805858Y255742D01*
X1805552Y255845D01*
X1805283Y256155D01*
X1805130Y256620D01*
X1805092Y257137D01*
X1805168Y257809D01*
X1805283Y258170D01*
X1805475Y258532D01*
X1805743Y258790D01*
X1806012Y258842D01*
X1806280Y258739D01*
X1806472Y258480D01*
G01X1787826Y286496D02*
Y274496D01*
G01X1801926Y282596D02*
Y270596D01*
G01X1795926Y282596D02*
X1801926D01*
G01X1795926Y270596D02*
Y282596D01*
G01X1801926Y270596D02*
X1795926D01*
G01X1794826Y286496D02*
Y274496D01*
G01X1788826D02*
Y286496D01*
G01X1794826Y274496D02*
X1788826D01*
G01X1787326Y295528D02*
Y307528D01*
G01X1793326Y295528D02*
X1787326D01*
G01X1793326Y307528D02*
Y295528D01*
G01X1794326D02*
Y307528D01*
G01X1800326Y295528D02*
X1794326D01*
G01X1800326Y307528D02*
Y295528D01*
G01X1788826Y286496D02*
X1794826D01*
G01X1801326Y295528D02*
Y307528D01*
G01X1807326Y295528D02*
X1801326D01*
G01X1787326Y307528D02*
X1793326D01*
G01X1794326D02*
X1800326D01*
G01X1801326D02*
X1807326D01*
G01X1802616Y377379D02*
Y375157D01*
X1802769Y374692D01*
X1803076Y374382D01*
X1803459Y374279D01*
X1803842Y374382D01*
X1804149Y374692D01*
X1804302Y375157D01*
Y377379D01*
G01X1805831Y376862D02*
X1806061Y377172D01*
X1806329Y377327D01*
X1806636Y377379D01*
X1807019Y377276D01*
X1807287Y377017D01*
X1807364Y376707D01*
X1807326Y376397D01*
X1807172Y376139D01*
X1806406Y375622D01*
X1806061Y375261D01*
X1805831Y374744D01*
X1805754Y374279D01*
X1807364D01*
G01X1808931Y376862D02*
X1809161Y377172D01*
X1809429Y377327D01*
X1809736Y377379D01*
X1810119Y377276D01*
X1810387Y377017D01*
X1810464Y376707D01*
X1810426Y376397D01*
X1810272Y376139D01*
X1809506Y375622D01*
X1809161Y375261D01*
X1808931Y374744D01*
X1808854Y374279D01*
X1810464D01*
G01X1813219D02*
Y377379D01*
X1811801Y375157D01*
X1813717D01*
G01X1790671Y366266D02*
Y369466D01*
G01X1796871Y366266D02*
X1790671D01*
G01X1796871Y369466D02*
Y366266D01*
G01X1790671Y369466D02*
X1796871D01*
G01X1794336Y397469D02*
Y395247D01*
X1794489Y394782D01*
X1794796Y394472D01*
X1795179Y394369D01*
X1795562Y394472D01*
X1795869Y394782D01*
X1796022Y395247D01*
Y397469D01*
G01X1797551Y395661D02*
X1797819Y396022D01*
X1798049Y396229D01*
X1798356Y396332D01*
X1798624Y396229D01*
X1798816Y396022D01*
X1798969Y395712D01*
X1799007Y395351D01*
X1798969Y395041D01*
X1798816Y394731D01*
X1798586Y394472D01*
X1798317Y394369D01*
X1798011Y394472D01*
X1797742Y394782D01*
X1797589Y395247D01*
X1797551Y395764D01*
X1797627Y396436D01*
X1797742Y396797D01*
X1797934Y397159D01*
X1798202Y397417D01*
X1798471Y397469D01*
X1798739Y397366D01*
X1798931Y397107D01*
G01X1800651Y395661D02*
X1800919Y396022D01*
X1801149Y396229D01*
X1801456Y396332D01*
X1801724Y396229D01*
X1801916Y396022D01*
X1802069Y395712D01*
X1802107Y395351D01*
X1802069Y395041D01*
X1801916Y394731D01*
X1801686Y394472D01*
X1801417Y394369D01*
X1801111Y394472D01*
X1800842Y394782D01*
X1800689Y395247D01*
X1800651Y395764D01*
X1800727Y396436D01*
X1800842Y396797D01*
X1801034Y397159D01*
X1801302Y397417D01*
X1801571Y397469D01*
X1801839Y397366D01*
X1802031Y397107D01*
G01X1789969Y388652D02*
Y391852D01*
G01X1796169Y388652D02*
X1789969D01*
G01X1796169Y391852D02*
Y388652D01*
G01X1789969Y391852D02*
X1796169D01*
G01X1796357Y416222D02*
Y414000D01*
X1796510Y413535D01*
X1796817Y413225D01*
X1797200Y413122D01*
X1797583Y413225D01*
X1797890Y413535D01*
X1798043Y414000D01*
Y416222D01*
G01X1799572Y415705D02*
X1799802Y416015D01*
X1800070Y416170D01*
X1800377Y416222D01*
X1800760Y416119D01*
X1801028Y415860D01*
X1801105Y415550D01*
X1801067Y415240D01*
X1800913Y414982D01*
X1800147Y414465D01*
X1799802Y414104D01*
X1799572Y413587D01*
X1799495Y413122D01*
X1801105D01*
G01X1803400D02*
Y416222D01*
X1802940Y415602D01*
G01Y413122D02*
X1803860D01*
G01X1805772Y415705D02*
X1806002Y416015D01*
X1806270Y416170D01*
X1806577Y416222D01*
X1806960Y416119D01*
X1807228Y415860D01*
X1807305Y415550D01*
X1807267Y415240D01*
X1807113Y414982D01*
X1806347Y414465D01*
X1806002Y414104D01*
X1805772Y413587D01*
X1805695Y413122D01*
X1807305D01*
G01X1804250Y412387D02*
X1801919Y410056D01*
G01X1796479Y403725D02*
X1807359D01*
G01X1796479Y412387D02*
Y403725D01*
G01X1799588Y412387D02*
X1796479D01*
G01X1801919Y410056D02*
X1799588Y412387D01*
G01X1789399Y405532D02*
Y402332D01*
G01Y412032D02*
Y408832D01*
G01X1796415Y430001D02*
Y427779D01*
X1796568Y427314D01*
X1796875Y427004D01*
X1797258Y426901D01*
X1797641Y427004D01*
X1797948Y427314D01*
X1798101Y427779D01*
Y430001D01*
G01X1799630Y429484D02*
X1799860Y429794D01*
X1800128Y429949D01*
X1800435Y430001D01*
X1800818Y429898D01*
X1801086Y429639D01*
X1801163Y429329D01*
X1801125Y429019D01*
X1800971Y428761D01*
X1800205Y428244D01*
X1799860Y427883D01*
X1799630Y427366D01*
X1799553Y426901D01*
X1801163D01*
G01X1803458D02*
Y430001D01*
X1802998Y429381D01*
G01Y426901D02*
X1803918D01*
G01X1806558D02*
Y430001D01*
X1806098Y429381D01*
G01Y426901D02*
X1807018D01*
G01X1804239Y425665D02*
X1801908Y423334D01*
G01X1796468Y417003D02*
X1807348D01*
G01X1796468Y425665D02*
Y417003D01*
G01X1799577Y425665D02*
X1796468D01*
G01X1801908Y423334D02*
X1799577Y425665D01*
G01X1789399Y420532D02*
Y417332D01*
G01Y427032D02*
Y423832D01*
G01X1802062Y462624D02*
X1796511Y468175D01*
X1793804D01*
Y437073D01*
X1810320D01*
Y468175D01*
X1807613D01*
X1802062Y462624D01*
G01X1799007Y473420D02*
Y471198D01*
X1799160Y470733D01*
X1799467Y470423D01*
X1799850Y470320D01*
X1800233Y470423D01*
X1800540Y470733D01*
X1800693Y471198D01*
Y473420D01*
G01X1802222Y472903D02*
X1802452Y473213D01*
X1802720Y473368D01*
X1803027Y473420D01*
X1803410Y473317D01*
X1803678Y473058D01*
X1803755Y472748D01*
X1803717Y472438D01*
X1803563Y472180D01*
X1802797Y471663D01*
X1802452Y471302D01*
X1802222Y470785D01*
X1802145Y470320D01*
X1803755D01*
G01X1806050Y473420D02*
X1805743Y473317D01*
X1805513Y473058D01*
X1805360Y472748D01*
X1805245Y472335D01*
X1805207Y471870D01*
X1805245Y471405D01*
X1805360Y470992D01*
X1805513Y470682D01*
X1805743Y470423D01*
X1806050Y470320D01*
X1806357Y470423D01*
X1806587Y470682D01*
X1806740Y470992D01*
X1806855Y471405D01*
X1806893Y471870D01*
X1806855Y472335D01*
X1806740Y472748D01*
X1806587Y473058D01*
X1806357Y473317D01*
X1806050Y473420D01*
G01X1808498Y470682D02*
X1808767Y470423D01*
X1809073Y470320D01*
X1809380Y470423D01*
X1809648Y470733D01*
X1809840Y471198D01*
X1809917Y471663D01*
Y472232D01*
X1809840Y472697D01*
X1809648Y473110D01*
X1809418Y473317D01*
X1809150Y473420D01*
X1808843Y473317D01*
X1808613Y473110D01*
X1808460Y472800D01*
X1808383Y472387D01*
X1808460Y472025D01*
X1808652Y471663D01*
X1808882Y471457D01*
X1809150Y471405D01*
X1809457Y471508D01*
X1809687Y471767D01*
X1809917Y472232D01*
G01X1790555Y525712D02*
Y528812D01*
G01X1792165D02*
Y525712D01*
G01Y527262D02*
X1790555D01*
G01X1793732Y528295D02*
X1793962Y528605D01*
X1794230Y528760D01*
X1794537Y528812D01*
X1794920Y528709D01*
X1795188Y528450D01*
X1795265Y528140D01*
X1795227Y527830D01*
X1795073Y527572D01*
X1794307Y527055D01*
X1793962Y526694D01*
X1793732Y526177D01*
X1793655Y525712D01*
X1795265D01*
G01X1796908Y526074D02*
X1797177Y525815D01*
X1797483Y525712D01*
X1797790Y525815D01*
X1798058Y526125D01*
X1798250Y526590D01*
X1798327Y527055D01*
Y527624D01*
X1798250Y528089D01*
X1798058Y528502D01*
X1797828Y528709D01*
X1797560Y528812D01*
X1797253Y528709D01*
X1797023Y528502D01*
X1796870Y528192D01*
X1796793Y527779D01*
X1796870Y527417D01*
X1797062Y527055D01*
X1797292Y526849D01*
X1797560Y526797D01*
X1797867Y526900D01*
X1798097Y527159D01*
X1798327Y527624D01*
G01X1791275Y648340D02*
Y651440D01*
G01X1792885D02*
Y648340D01*
G01Y649890D02*
X1791275D01*
G01X1795180Y648340D02*
Y651440D01*
X1794720Y650820D01*
G01Y648340D02*
X1795640D01*
G01X1798280Y651440D02*
X1797973Y651337D01*
X1797743Y651078D01*
X1797590Y650768D01*
X1797475Y650355D01*
X1797437Y649890D01*
X1797475Y649425D01*
X1797590Y649012D01*
X1797743Y648702D01*
X1797973Y648443D01*
X1798280Y648340D01*
X1798587Y648443D01*
X1798817Y648702D01*
X1798970Y649012D01*
X1799085Y649425D01*
X1799123Y649890D01*
X1799085Y650355D01*
X1798970Y650768D01*
X1798817Y651078D01*
X1798587Y651337D01*
X1798280Y651440D01*
G01X1801840Y648340D02*
Y651440D01*
X1800422Y649218D01*
X1802338D01*
G01X1800457Y697211D02*
Y1335007D01*
G01X1786943Y1337302D02*
X1787135Y1336992D01*
X1787365Y1336785D01*
X1787633Y1336682D01*
X1787940Y1336785D01*
X1788170Y1336992D01*
X1788400Y1337302D01*
X1788477Y1337715D01*
Y1339782D01*
G01X1790810Y1336682D02*
Y1339782D01*
X1790350Y1339162D01*
G01Y1336682D02*
X1791270D01*
G01X1793182Y1337974D02*
X1793450Y1338335D01*
X1793680Y1338542D01*
X1793987Y1338645D01*
X1794255Y1338542D01*
X1794447Y1338335D01*
X1794600Y1338025D01*
X1794638Y1337664D01*
X1794600Y1337354D01*
X1794447Y1337044D01*
X1794217Y1336785D01*
X1793948Y1336682D01*
X1793642Y1336785D01*
X1793373Y1337095D01*
X1793220Y1337560D01*
X1793182Y1338077D01*
X1793258Y1338749D01*
X1793373Y1339110D01*
X1793565Y1339472D01*
X1793833Y1339730D01*
X1794102Y1339782D01*
X1794370Y1339679D01*
X1794562Y1339420D01*
G01X1790725Y1383800D02*
Y1386900D01*
G01X1792335D02*
Y1383800D01*
G01Y1385350D02*
X1790725D01*
G01X1793978Y1384162D02*
X1794247Y1383903D01*
X1794553Y1383800D01*
X1794860Y1383903D01*
X1795128Y1384213D01*
X1795320Y1384678D01*
X1795397Y1385143D01*
Y1385712D01*
X1795320Y1386177D01*
X1795128Y1386590D01*
X1794898Y1386797D01*
X1794630Y1386900D01*
X1794323Y1386797D01*
X1794093Y1386590D01*
X1793940Y1386280D01*
X1793863Y1385867D01*
X1793940Y1385505D01*
X1794132Y1385143D01*
X1794362Y1384937D01*
X1794630Y1384885D01*
X1794937Y1384988D01*
X1795167Y1385247D01*
X1795397Y1385712D01*
G01X1797730Y1383800D02*
X1797998Y1383852D01*
X1798305Y1384007D01*
X1798497Y1384265D01*
X1798573Y1384627D01*
X1798497Y1384988D01*
X1798267Y1385298D01*
X1797922Y1385453D01*
X1797538D01*
X1797308Y1385557D01*
X1797117Y1385815D01*
X1797040Y1386177D01*
X1797155Y1386538D01*
X1797423Y1386797D01*
X1797730Y1386900D01*
X1798037Y1386797D01*
X1798305Y1386538D01*
X1798420Y1386177D01*
X1798343Y1385815D01*
X1798152Y1385557D01*
X1797922Y1385453D01*
X1797538D01*
X1797193Y1385298D01*
X1796963Y1384988D01*
X1796887Y1384627D01*
X1796963Y1384265D01*
X1797155Y1384007D01*
X1797462Y1383852D01*
X1797730Y1383800D01*
G01X1838962Y1431913D02*
G03X1837703Y1406826I-19756J-11584D01*
G01X1800550Y1497880D02*
Y1504080D01*
G01X1803750Y1497880D02*
X1800550D01*
G01X1796122Y1497943D02*
Y1504143D01*
G01X1799322Y1497943D02*
X1796122D01*
G01X1799322Y1504143D02*
Y1497943D01*
G01X1793488Y1508138D02*
Y1504938D01*
G01X1787288Y1508138D02*
X1793488D01*
G01X1787288Y1504938D02*
Y1508138D01*
G01X1793488Y1504938D02*
X1787288D01*
G01X1788411Y1516098D02*
X1791611D01*
G01X1788411Y1509898D02*
Y1516098D01*
G01X1791611Y1509898D02*
X1788411D01*
G01X1791611Y1516098D02*
Y1509898D01*
G01X1800550Y1504080D02*
X1803750D01*
G01X1796122Y1504143D02*
X1799322D01*
G01X1794750Y1522182D02*
X1794479D01*
Y1518380D01*
G01Y1513780D02*
Y1509978D01*
X1794750D01*
G01X1793927Y1528966D02*
X1800127D01*
G01D02*
Y1525766D01*
G01D02*
X1793927D01*
G01D02*
Y1528966D01*
G01X1793629Y1530785D02*
Y1533885D01*
X1794549D01*
X1794856Y1533730D01*
X1795086Y1533368D01*
X1795163Y1532955D01*
X1795086Y1532542D01*
X1794894Y1532232D01*
X1794549Y1532077D01*
X1793629D01*
G01X1796653Y1533885D02*
Y1531663D01*
X1796806Y1531198D01*
X1797113Y1530888D01*
X1797496Y1530785D01*
X1797879Y1530888D01*
X1798186Y1531198D01*
X1798339Y1531663D01*
Y1533885D01*
G01X1800596Y1530785D02*
Y1533885D01*
X1800136Y1533265D01*
G01Y1530785D02*
X1801056D01*
G01X1803696D02*
X1803964Y1530837D01*
X1804271Y1530992D01*
X1804463Y1531250D01*
X1804539Y1531612D01*
X1804463Y1531973D01*
X1804233Y1532283D01*
X1803888Y1532438D01*
X1803504D01*
X1803274Y1532542D01*
X1803083Y1532800D01*
X1803006Y1533162D01*
X1803121Y1533523D01*
X1803389Y1533782D01*
X1803696Y1533885D01*
X1804003Y1533782D01*
X1804271Y1533523D01*
X1804386Y1533162D01*
X1804309Y1532800D01*
X1804118Y1532542D01*
X1803888Y1532438D01*
X1803504D01*
X1803159Y1532283D01*
X1802929Y1531973D01*
X1802853Y1531612D01*
X1802929Y1531250D01*
X1803121Y1530992D01*
X1803428Y1530837D01*
X1803696Y1530785D01*
G01X1806796D02*
Y1533885D01*
X1806336Y1533265D01*
G01Y1530785D02*
X1807256D01*
G01X1817642Y1569255D02*
G03I-9450J0D01*
G01X1786424Y1732048D02*
Y1735148D01*
G01X1788034D02*
Y1732048D01*
G01Y1733598D02*
X1786424D01*
G01X1790329Y1732048D02*
X1790597Y1732100D01*
X1790904Y1732255D01*
X1791096Y1732513D01*
X1791172Y1732875D01*
X1791096Y1733236D01*
X1790866Y1733546D01*
X1790521Y1733701D01*
X1790137D01*
X1789907Y1733805D01*
X1789716Y1734063D01*
X1789639Y1734425D01*
X1789754Y1734786D01*
X1790022Y1735045D01*
X1790329Y1735148D01*
X1790636Y1735045D01*
X1790904Y1734786D01*
X1791019Y1734425D01*
X1790942Y1734063D01*
X1790751Y1733805D01*
X1790521Y1733701D01*
X1790137D01*
X1789792Y1733546D01*
X1789562Y1733236D01*
X1789486Y1732875D01*
X1789562Y1732513D01*
X1789754Y1732255D01*
X1790061Y1732100D01*
X1790329Y1732048D01*
G01X1793352D02*
X1793429Y1732720D01*
X1793544Y1733288D01*
X1793697Y1733805D01*
X1793889Y1734373D01*
X1794196Y1735148D01*
X1792662D01*
G01X1809742Y-46096D02*
Y-42996D01*
X1810662D01*
X1810969Y-43151D01*
X1811199Y-43513D01*
X1811276Y-43926D01*
X1811199Y-44339D01*
X1811007Y-44649D01*
X1810662Y-44804D01*
X1809742D01*
G01X1812919Y-46199D02*
X1814299Y-42996D01*
G01X1815827Y-46096D02*
Y-42996D01*
X1817591Y-46096D01*
Y-42996D01*
G01X1819809Y-46199D02*
X1819732Y-46148D01*
Y-46044D01*
X1819809Y-45993D01*
X1819886Y-46044D01*
Y-46148D01*
X1819809Y-46199D01*
G01Y-44804D02*
X1819732Y-44753D01*
Y-44649D01*
X1819809Y-44598D01*
X1819886Y-44649D01*
Y-44753D01*
X1819809Y-44804D01*
G01X1822066Y-46096D02*
Y-42996D01*
X1822832D01*
X1823139Y-43151D01*
X1823369Y-43358D01*
X1823561Y-43668D01*
X1823714Y-44029D01*
X1823752Y-44546D01*
X1823714Y-45063D01*
X1823561Y-45424D01*
X1823369Y-45734D01*
X1823139Y-45941D01*
X1822832Y-46096D01*
X1822066D01*
G01X1825051D02*
X1826009Y-42996D01*
X1826967Y-46096D01*
G01X1826622Y-45011D02*
X1825396D01*
G01X1829109Y-42996D02*
X1828802Y-43099D01*
X1828572Y-43358D01*
X1828419Y-43668D01*
X1828304Y-44081D01*
X1828266Y-44546D01*
X1828304Y-45011D01*
X1828419Y-45424D01*
X1828572Y-45734D01*
X1828802Y-45993D01*
X1829109Y-46096D01*
X1829416Y-45993D01*
X1829646Y-45734D01*
X1829799Y-45424D01*
X1829914Y-45011D01*
X1829952Y-44546D01*
X1829914Y-44081D01*
X1829799Y-43668D01*
X1829646Y-43358D01*
X1829416Y-43099D01*
X1829109Y-42996D01*
G01X1831481Y-46096D02*
Y-42996D01*
X1832937D01*
G01X1832401Y-44494D02*
X1831481D01*
G01X1835309Y-42996D02*
X1835002Y-43099D01*
X1834772Y-43358D01*
X1834619Y-43668D01*
X1834504Y-44081D01*
X1834466Y-44546D01*
X1834504Y-45011D01*
X1834619Y-45424D01*
X1834772Y-45734D01*
X1835002Y-45993D01*
X1835309Y-46096D01*
X1835616Y-45993D01*
X1835846Y-45734D01*
X1835999Y-45424D01*
X1836114Y-45011D01*
X1836152Y-44546D01*
X1836114Y-44081D01*
X1835999Y-43668D01*
X1835846Y-43358D01*
X1835616Y-43099D01*
X1835309Y-42996D01*
G01X1838409D02*
Y-46096D01*
G01X1837527Y-42996D02*
X1839291D01*
G01X1840512Y-46096D02*
Y-42996D01*
X1841509Y-45579D01*
X1842506Y-42996D01*
Y-46096D01*
G01X1844916Y-44443D02*
X1845069Y-44288D01*
X1845184Y-44029D01*
X1845261Y-43668D01*
X1845184Y-43358D01*
X1845031Y-43151D01*
X1844762Y-42996D01*
X1843727D01*
Y-46096D01*
X1844992D01*
X1845261Y-45889D01*
X1845414Y-45579D01*
X1845491Y-45218D01*
X1845414Y-44856D01*
X1845184Y-44546D01*
X1844916Y-44443D01*
X1843727D01*
G01X1847249Y-42996D02*
X1848169D01*
G01X1847709D02*
Y-46096D01*
G01X1847249D02*
X1848169D01*
G01X1850042Y-45476D02*
X1850234Y-45786D01*
X1850464Y-45993D01*
X1850732Y-46096D01*
X1851039Y-45993D01*
X1851269Y-45786D01*
X1851499Y-45476D01*
X1851576Y-45063D01*
Y-42996D01*
G01X1853909D02*
X1853602Y-43099D01*
X1853372Y-43358D01*
X1853219Y-43668D01*
X1853104Y-44081D01*
X1853066Y-44546D01*
X1853104Y-45011D01*
X1853219Y-45424D01*
X1853372Y-45734D01*
X1853602Y-45993D01*
X1853909Y-46096D01*
X1854216Y-45993D01*
X1854446Y-45734D01*
X1854599Y-45424D01*
X1854714Y-45011D01*
X1854752Y-44546D01*
X1854714Y-44081D01*
X1854599Y-43668D01*
X1854446Y-43358D01*
X1854216Y-43099D01*
X1853909Y-42996D01*
G01X1809265Y61437D02*
X1807025D01*
G01X1808238Y59812D02*
Y63062D01*
G01X1805624Y66785D02*
Y55289D01*
G01X1803715Y104120D02*
Y107220D01*
G01X1805325D02*
Y104120D01*
G01Y105670D02*
X1803715D01*
G01X1807620Y104120D02*
Y107220D01*
X1807160Y106600D01*
G01Y104120D02*
X1808080D01*
G01X1810720Y107220D02*
X1810413Y107117D01*
X1810183Y106858D01*
X1810030Y106548D01*
X1809915Y106135D01*
X1809877Y105670D01*
X1809915Y105205D01*
X1810030Y104792D01*
X1810183Y104482D01*
X1810413Y104223D01*
X1810720Y104120D01*
X1811027Y104223D01*
X1811257Y104482D01*
X1811410Y104792D01*
X1811525Y105205D01*
X1811563Y105670D01*
X1811525Y106135D01*
X1811410Y106548D01*
X1811257Y106858D01*
X1811027Y107117D01*
X1810720Y107220D01*
G01X1813092Y105412D02*
X1813360Y105773D01*
X1813590Y105980D01*
X1813897Y106083D01*
X1814165Y105980D01*
X1814357Y105773D01*
X1814510Y105463D01*
X1814548Y105102D01*
X1814510Y104792D01*
X1814357Y104482D01*
X1814127Y104223D01*
X1813858Y104120D01*
X1813552Y104223D01*
X1813283Y104533D01*
X1813130Y104998D01*
X1813092Y105515D01*
X1813168Y106187D01*
X1813283Y106548D01*
X1813475Y106910D01*
X1813743Y107168D01*
X1814012Y107220D01*
X1814280Y107117D01*
X1814472Y106858D01*
G01X1821061Y149201D02*
X1817861D01*
G01D02*
Y155401D01*
G01X1812355Y147620D02*
X1815555D01*
G01X1812355Y141420D02*
Y147620D01*
G01X1815555Y141420D02*
X1812355D01*
G01X1815555Y147620D02*
Y141420D01*
G01X1811828Y157096D02*
Y165758D01*
G01X1822322Y157096D02*
X1811828D01*
G01X1817075Y163558D02*
X1818975Y165758D01*
G01X1815175D02*
X1817075Y163558D01*
G01X1811828Y165758D02*
X1815175D01*
G01X1807890Y158157D02*
Y154957D01*
G01X1817861Y155401D02*
X1821061D01*
G01X1803520Y170176D02*
X1803213Y170228D01*
X1802945Y170434D01*
X1802715Y170744D01*
X1802562Y171106D01*
X1802485Y171519D01*
Y171933D01*
X1802562Y172346D01*
X1802715Y172708D01*
X1802945Y173018D01*
X1803213Y173224D01*
X1803520Y173276D01*
X1803827Y173224D01*
X1804095Y173018D01*
X1804325Y172708D01*
X1804478Y172346D01*
X1804555Y171933D01*
Y171519D01*
X1804478Y171106D01*
X1804325Y170744D01*
X1804095Y170434D01*
X1803827Y170228D01*
X1803520Y170176D01*
G01X1803827Y171003D02*
X1804287Y170176D01*
G01X1806620D02*
Y173276D01*
X1806160Y172656D01*
G01Y170176D02*
X1807080D01*
G01X1808992Y172759D02*
X1809222Y173069D01*
X1809490Y173224D01*
X1809797Y173276D01*
X1810180Y173173D01*
X1810448Y172914D01*
X1810525Y172604D01*
X1810487Y172294D01*
X1810333Y172036D01*
X1809567Y171519D01*
X1809222Y171158D01*
X1808992Y170641D01*
X1808915Y170176D01*
X1810525D01*
G01X1813280D02*
Y173276D01*
X1811862Y171054D01*
X1813778D01*
G01X1808650Y178297D02*
Y181497D01*
G01X1814850Y178297D02*
X1808650D01*
G01X1814850Y181497D02*
Y178297D01*
G01X1808650Y181497D02*
X1814850D01*
G01X1806863Y241632D02*
Y244732D01*
X1807783D01*
X1808090Y244577D01*
X1808320Y244215D01*
X1808397Y243802D01*
X1808320Y243389D01*
X1808128Y243079D01*
X1807783Y242924D01*
X1806863D01*
G01X1809963Y244732D02*
Y241632D01*
X1811497D01*
G01X1814290D02*
Y244732D01*
X1812872Y242510D01*
X1814788D01*
G01X1816087Y242097D02*
X1816317Y241839D01*
X1816585Y241684D01*
X1816930Y241632D01*
X1817275Y241735D01*
X1817543Y241942D01*
X1817735Y242304D01*
X1817773Y242717D01*
X1817697Y243130D01*
X1817505Y243389D01*
X1817237Y243595D01*
X1816968Y243647D01*
X1816700Y243595D01*
X1816355Y243389D01*
X1816470Y244732D01*
X1817505D01*
G01X1844712Y269763D02*
G03I-13386J0D01*
G01X1808986Y282659D02*
Y270659D01*
G01X1802986D02*
Y282659D01*
G01X1808986Y270659D02*
X1802986D01*
G01X1816086Y282659D02*
Y270659D01*
G01X1810086D02*
Y282659D01*
G01X1816086Y270659D02*
X1810086D01*
G01X1807326Y307528D02*
Y295528D01*
G01X1802986Y282659D02*
X1808986D01*
G01X1808386Y295465D02*
Y307465D01*
G01X1814386Y295465D02*
X1808386D01*
G01X1814386Y307465D02*
Y295465D01*
G01X1810086Y282659D02*
X1816086D01*
G01X1844712Y299056D02*
G03I-13386J0D01*
G01X1808386Y307465D02*
X1814386D01*
G01X1803297Y364281D02*
Y372943D01*
G01X1814321Y364281D02*
X1803297D01*
G01X1814321Y372943D02*
Y364281D01*
G01Y372943D02*
X1803297D01*
G01X1815632Y369729D02*
Y372929D01*
G01X1821832Y369729D02*
X1815632D01*
G01Y372929D02*
X1821832D01*
G01X1803857Y383521D02*
Y392183D01*
G01X1814881Y383521D02*
X1803857D01*
G01X1814881Y392183D02*
Y383521D01*
G01Y392183D02*
X1803857D01*
G01X1815469Y393952D02*
Y397152D01*
G01X1821669Y393952D02*
X1815469D01*
G01X1807359Y412387D02*
X1804250D01*
G01X1807359Y403725D02*
Y412387D01*
G01X1815469Y397152D02*
X1821669D01*
G01X1814699Y406332D02*
Y409532D01*
G01X1820899Y406332D02*
X1814699D01*
G01Y409532D02*
X1820899D01*
G01X1814699Y401625D02*
Y404825D01*
G01X1820899Y401625D02*
X1814699D01*
G01Y404825D02*
X1820899D01*
G01X1820399Y411832D02*
X1814199D01*
Y415032D01*
X1820399D01*
Y411832D01*
G01X1807348Y425665D02*
X1804239D01*
G01X1807348Y417003D02*
Y425665D01*
G01X1814199Y419832D02*
Y423032D01*
G01X1820399Y419832D02*
X1814199D01*
G01Y423032D02*
X1820399D01*
G01X1814199Y426332D02*
Y429532D01*
G01X1820399Y426332D02*
X1814199D01*
G01X1820399Y415832D02*
X1814199D01*
Y419032D01*
X1820399D01*
Y415832D01*
G01X1814199Y429532D02*
X1820399D01*
G01X1814141Y470921D02*
Y474121D01*
G01X1820341Y470921D02*
X1814141D01*
G01Y474121D02*
X1820341D01*
G01X1822430Y502472D02*
G03I-9450J0D01*
G01X1804567Y697211D02*
X1830157D01*
G01X1804567Y1335007D02*
Y697211D01*
G01X1830157Y732644D02*
X1804567D01*
G01X1830157Y1299574D02*
X1804567D01*
G01X1830157Y1335007D02*
X1804567D01*
G01X1804725Y1446052D02*
Y1449152D01*
G01X1806335D02*
Y1446052D01*
G01Y1447602D02*
X1804725D01*
G01X1808630Y1446052D02*
Y1449152D01*
X1808170Y1448532D01*
G01Y1446052D02*
X1809090D01*
G01X1811002Y1448635D02*
X1811232Y1448945D01*
X1811500Y1449100D01*
X1811807Y1449152D01*
X1812190Y1449049D01*
X1812458Y1448790D01*
X1812535Y1448480D01*
X1812497Y1448170D01*
X1812343Y1447912D01*
X1811577Y1447395D01*
X1811232Y1447034D01*
X1811002Y1446517D01*
X1810925Y1446052D01*
X1812535D01*
G01X1814753D02*
X1814830Y1446724D01*
X1814945Y1447292D01*
X1815098Y1447809D01*
X1815290Y1448377D01*
X1815597Y1449152D01*
X1814063D01*
G01X1803750Y1504080D02*
Y1497880D01*
G01X1805041Y1492718D02*
Y1495918D01*
G01X1811241Y1492718D02*
X1805041D01*
G01X1811241Y1495918D02*
Y1492718D01*
G01X1805041Y1495918D02*
X1811241D01*
G01X1813614Y1502641D02*
Y1505841D01*
G01X1819814Y1502641D02*
X1813614D01*
G01X1805041Y1496718D02*
Y1499918D01*
G01X1811241Y1496718D02*
X1805041D01*
G01X1811241Y1499918D02*
Y1496718D01*
G01X1805041Y1499918D02*
X1811241D01*
G01X1811243Y1503985D02*
X1811239Y1500785D01*
G01X1805039Y1500791D02*
X1805043Y1503991D01*
G01X1811239Y1500785D02*
X1805039Y1500791D01*
G01X1812100Y1495687D02*
Y1501887D01*
X1815300D01*
Y1495687D01*
X1812100D01*
G01X1813784Y1512671D02*
Y1524671D01*
G01X1819784Y1512671D02*
X1813784D01*
G01X1813614Y1505841D02*
X1819814D01*
G01X1805043Y1503991D02*
X1811243Y1503985D01*
G01X1810621Y1516080D02*
Y1522182D01*
X1810150D01*
G01X1810350Y1509978D02*
X1810621D01*
G01D02*
Y1513780D01*
G01X1813784Y1524671D02*
X1819784D01*
G01X1829770Y149630D02*
Y158292D01*
G01X1840264Y149630D02*
X1829770D01*
G01X1821061Y155401D02*
Y149201D01*
G01X1822322Y165758D02*
Y157096D01*
G01X1818975Y165758D02*
X1822322D01*
G01X1830957Y163098D02*
X1830650Y163150D01*
X1830382Y163356D01*
X1830152Y163666D01*
X1829999Y164028D01*
X1829922Y164441D01*
Y164855D01*
X1829999Y165268D01*
X1830152Y165630D01*
X1830382Y165940D01*
X1830650Y166146D01*
X1830957Y166198D01*
X1831264Y166146D01*
X1831532Y165940D01*
X1831762Y165630D01*
X1831915Y165268D01*
X1831992Y164855D01*
Y164441D01*
X1831915Y164028D01*
X1831762Y163666D01*
X1831532Y163356D01*
X1831264Y163150D01*
X1830957Y163098D01*
G01X1831264Y163925D02*
X1831724Y163098D01*
G01X1834057D02*
Y166198D01*
X1833597Y165578D01*
G01Y163098D02*
X1834517D01*
G01X1836429Y165681D02*
X1836659Y165991D01*
X1836927Y166146D01*
X1837234Y166198D01*
X1837617Y166095D01*
X1837885Y165836D01*
X1837962Y165526D01*
X1837924Y165216D01*
X1837770Y164958D01*
X1837004Y164441D01*
X1836659Y164080D01*
X1836429Y163563D01*
X1836352Y163098D01*
X1837962D01*
G01X1839414Y163718D02*
X1839644Y163356D01*
X1839950Y163150D01*
X1840295Y163098D01*
X1840602Y163150D01*
X1840909Y163408D01*
X1841100Y163718D01*
X1841139Y164028D01*
X1841062Y164390D01*
X1840794Y164648D01*
X1840525Y164751D01*
X1840180D01*
G01X1840525D02*
X1840755Y164906D01*
X1840947Y165165D01*
X1841024Y165475D01*
X1840947Y165785D01*
X1840755Y166043D01*
X1840410Y166198D01*
X1840065Y166146D01*
X1839720Y165940D01*
G01X1833117Y158292D02*
X1835017Y156092D01*
G01X1829770Y158292D02*
X1833117D01*
G01X1827287Y171762D02*
Y168562D01*
G01X1821087D02*
Y171762D01*
G01X1827287Y168562D02*
X1821087D01*
G01X1827082Y174739D02*
Y172517D01*
X1827235Y172052D01*
X1827542Y171742D01*
X1827925Y171639D01*
X1828308Y171742D01*
X1828615Y172052D01*
X1828768Y172517D01*
Y174739D01*
G01X1831025Y171639D02*
X1831293Y171691D01*
X1831600Y171846D01*
X1831792Y172104D01*
X1831868Y172466D01*
X1831792Y172827D01*
X1831562Y173137D01*
X1831217Y173292D01*
X1830833D01*
X1830603Y173396D01*
X1830412Y173654D01*
X1830335Y174016D01*
X1830450Y174377D01*
X1830718Y174636D01*
X1831025Y174739D01*
X1831332Y174636D01*
X1831600Y174377D01*
X1831715Y174016D01*
X1831638Y173654D01*
X1831447Y173396D01*
X1831217Y173292D01*
X1830833D01*
X1830488Y173137D01*
X1830258Y172827D01*
X1830182Y172466D01*
X1830258Y172104D01*
X1830450Y171846D01*
X1830757Y171691D01*
X1831025Y171639D01*
G01X1833397Y174222D02*
X1833627Y174532D01*
X1833895Y174687D01*
X1834202Y174739D01*
X1834585Y174636D01*
X1834853Y174377D01*
X1834930Y174067D01*
X1834892Y173757D01*
X1834738Y173499D01*
X1833972Y172982D01*
X1833627Y172621D01*
X1833397Y172104D01*
X1833320Y171639D01*
X1834930D01*
G01X1832337Y184133D02*
X1821313D01*
G01X1832337D02*
Y175471D01*
G01D02*
X1821313D01*
G01D02*
Y184133D01*
G01X1834235Y181112D02*
Y184312D01*
G01X1840435Y181112D02*
X1834235D01*
G01Y184312D02*
X1840435D01*
G01X1821087Y171762D02*
X1827287D01*
G01X1834205Y194278D02*
X1840405D01*
G01X1834205Y191078D02*
Y194278D01*
G01X1840405Y191078D02*
X1834205D01*
G01X1822204Y235891D02*
Y253607D01*
G01X1825612Y235891D02*
X1822204D01*
G01Y253607D02*
X1825612D01*
G01X1831326Y256377D02*
Y283149D01*
G01Y285670D02*
Y312442D01*
G01X1821951Y362131D02*
Y365331D01*
G01X1828151Y362131D02*
X1821951D01*
G01X1828151Y365331D02*
Y362131D01*
G01X1821832Y372929D02*
Y369729D01*
G01X1821951Y366101D02*
Y369301D01*
G01X1828151Y366101D02*
X1821951D01*
G01X1828151Y369301D02*
Y366101D01*
G01X1821951Y369301D02*
X1828151D01*
G01X1821951Y365331D02*
X1828151D01*
G01X1821569Y377952D02*
Y381152D01*
G01X1827769Y377952D02*
X1821569D01*
G01X1827769Y381152D02*
Y377952D01*
G01X1821669Y397152D02*
Y393952D01*
G01X1821569Y382352D02*
Y385552D01*
G01X1827769Y382352D02*
X1821569D01*
G01X1827769Y385552D02*
Y382352D01*
G01X1821569Y385552D02*
X1827769D01*
G01X1821569Y381152D02*
X1827769D01*
G01X1820899Y409532D02*
Y406332D01*
G01X1833979Y400785D02*
Y397585D01*
G01X1827779Y400785D02*
X1833979D01*
G01X1827779Y397585D02*
Y400785D01*
G01X1833979Y397585D02*
X1827779D01*
G01X1820899Y404825D02*
Y401625D01*
G01X1820399Y423032D02*
Y419832D01*
G01Y429532D02*
Y426332D01*
G01X1828439Y435802D02*
Y432602D01*
G01X1822239Y435802D02*
X1828439D01*
G01X1822239Y432602D02*
Y435802D01*
G01X1828439Y432602D02*
X1822239D01*
G01X1830841Y457521D02*
Y460721D01*
G01X1837041Y457521D02*
X1830841D01*
G01Y460721D02*
X1837041D01*
G01X1830851Y455521D02*
X1837051D01*
G01X1830851Y452321D02*
Y455521D01*
G01X1837051Y452321D02*
X1830851D01*
G01X1820341Y474121D02*
Y470921D01*
G01X1830841Y468921D02*
X1837041D01*
G01X1830841Y465721D02*
Y468921D01*
G01X1837041Y465721D02*
X1830841D01*
G01Y464793D02*
X1837041D01*
G01X1830841Y461593D02*
Y464793D01*
G01X1837041Y461593D02*
X1830841D01*
G01X1830157Y697211D02*
Y1335007D01*
G01X1829633Y1336802D02*
X1829825Y1336492D01*
X1830055Y1336285D01*
X1830323Y1336182D01*
X1830630Y1336285D01*
X1830860Y1336492D01*
X1831090Y1336802D01*
X1831167Y1337215D01*
Y1339282D01*
G01X1833500Y1336182D02*
Y1339282D01*
X1833040Y1338662D01*
G01Y1336182D02*
X1833960D01*
G01X1835757Y1336647D02*
X1835987Y1336389D01*
X1836255Y1336234D01*
X1836600Y1336182D01*
X1836945Y1336285D01*
X1837213Y1336492D01*
X1837405Y1336854D01*
X1837443Y1337267D01*
X1837367Y1337680D01*
X1837175Y1337939D01*
X1836907Y1338145D01*
X1836638Y1338197D01*
X1836370Y1338145D01*
X1836025Y1337939D01*
X1836140Y1339282D01*
X1837175D01*
G01X1833152Y1511891D02*
Y1501891D01*
G01X1828552D02*
Y1511891D01*
G01X1828652Y1501891D02*
X1828552D01*
G01X1833152D02*
X1828552D01*
G01X1819814Y1505841D02*
Y1502641D01*
G01X1820684Y1512671D02*
Y1524671D01*
G01X1826684Y1512671D02*
X1820684D01*
G01X1826684Y1524671D02*
Y1512671D01*
G01X1827584D02*
Y1524671D01*
G01X1833584Y1512671D02*
X1827584D01*
G01X1833584Y1524671D02*
Y1512671D01*
G01X1819784Y1524671D02*
Y1512671D01*
G01X1833152Y1507391D02*
X1828552D01*
G01X1833152Y1511891D02*
X1828552D01*
G01X1833152Y1506391D02*
X1828552D01*
G01X1827675Y1503241D02*
X1824475D01*
G01X1827675Y1509441D02*
Y1503241D01*
G01X1824475Y1509441D02*
X1827675D01*
G01X1824475Y1503241D02*
Y1509441D01*
G01X1820684Y1524671D02*
X1826684D01*
G01X1827584D02*
X1833584D01*
G01X1840264Y158292D02*
Y149630D01*
G01X1836917Y158292D02*
X1840264D01*
G01X1835017Y156092D02*
X1836917Y158292D01*
G01X1847591Y167975D02*
X1850791D01*
G01X1847591Y161775D02*
Y167975D01*
G01X1850791Y161775D02*
X1847591D01*
G01X1850791Y167975D02*
Y161775D01*
G01X1840435Y184312D02*
Y181112D01*
G01X1847560Y173787D02*
Y170587D01*
G01X1841360Y173787D02*
X1847560D01*
G01X1841360Y170587D02*
Y173787D01*
G01X1847560Y170587D02*
X1841360D01*
G01X1841355Y175122D02*
Y178322D01*
G01X1847555Y175122D02*
X1841355D01*
G01X1847555Y178322D02*
Y175122D01*
G01X1841355Y178322D02*
X1847555D01*
G01X1840405Y194278D02*
Y191078D01*
G01X1839920Y235891D02*
X1836512D01*
G01X1839920Y253607D02*
Y235891D01*
G01X1841566Y243446D02*
X1844766D01*
G01Y237246D02*
X1841566D01*
G01X1844766Y243446D02*
Y237246D01*
G01X1841566D02*
Y243446D01*
G01X1836512Y253607D02*
X1839920D01*
G01X1835150Y374883D02*
Y381083D01*
G01X1838350Y374883D02*
X1835150D01*
G01X1838350Y381083D02*
Y374883D01*
G01X1835150Y381083D02*
X1838350D01*
G01X1837041Y460721D02*
Y457521D01*
G01X1837051Y455521D02*
Y452321D01*
G01X1837041Y468921D02*
Y465721D01*
G01Y464793D02*
Y461593D01*
G01X1876655Y478898D02*
X1874155D01*
Y468898D01*
X1874705D01*
G01X1883605D02*
X1884705D01*
G01X1886655Y478898D02*
X1881655D01*
G01X1874500Y570845D02*
X1871400Y572455D01*
G01Y570845D02*
X1874500Y572455D01*
G01Y575210D02*
X1871400D01*
X1873622Y573792D01*
Y575708D01*
G01X1874500Y578310D02*
X1871400D01*
X1873622Y576892D01*
Y578808D01*
G01X1874705Y592848D02*
X1874155D01*
Y582848D01*
G01X1881655D02*
X1886655D01*
G01X1874155D02*
X1876655D01*
G01X1884705Y592848D02*
X1883605D01*
G01X1872000Y717845D02*
X1868900Y719455D01*
G01Y717845D02*
X1872000Y719455D01*
G01Y722210D02*
X1868900D01*
X1871122Y720792D01*
Y722708D01*
G01X1871380Y724007D02*
X1871742Y724237D01*
X1871948Y724543D01*
X1872000Y724888D01*
X1871948Y725195D01*
X1871690Y725502D01*
X1871380Y725693D01*
X1871070Y725732D01*
X1870708Y725655D01*
X1870450Y725387D01*
X1870347Y725118D01*
Y724773D01*
G01Y725118D02*
X1870192Y725348D01*
X1869933Y725540D01*
X1869623Y725617D01*
X1869313Y725540D01*
X1869055Y725348D01*
X1868900Y725003D01*
X1868952Y724658D01*
X1869158Y724313D01*
G01X1876655Y726798D02*
X1874155D01*
Y716798D01*
X1874705D01*
G01X1883605D02*
X1884705D01*
G01X1886655Y726798D02*
X1881655D01*
G01X1872955Y830393D02*
X1869855Y832003D01*
G01Y830393D02*
X1872955Y832003D01*
G01X1872335Y833455D02*
X1872697Y833685D01*
X1872903Y833991D01*
X1872955Y834336D01*
X1872903Y834643D01*
X1872645Y834950D01*
X1872335Y835141D01*
X1872025Y835180D01*
X1871663Y835103D01*
X1871405Y834835D01*
X1871302Y834566D01*
Y834221D01*
G01Y834566D02*
X1871147Y834796D01*
X1870888Y834988D01*
X1870578Y835065D01*
X1870268Y834988D01*
X1870010Y834796D01*
X1869855Y834451D01*
X1869907Y834106D01*
X1870113Y833761D01*
G01X1872490Y836555D02*
X1872748Y836785D01*
X1872903Y837053D01*
X1872955Y837398D01*
X1872852Y837743D01*
X1872645Y838011D01*
X1872283Y838203D01*
X1871870Y838241D01*
X1871457Y838165D01*
X1871198Y837973D01*
X1870992Y837705D01*
X1870940Y837436D01*
X1870992Y837168D01*
X1871198Y836823D01*
X1869855Y836938D01*
Y837973D01*
G01X1874705Y840748D02*
X1874155D01*
Y830748D01*
G01X1881655D02*
X1886655D01*
G01X1874155D02*
X1876655D01*
G01X1884705Y840748D02*
X1883605D01*
G01X1883033Y1846688D02*
X1883225Y1846378D01*
X1883455Y1846171D01*
X1883723Y1846068D01*
X1884030Y1846171D01*
X1884260Y1846378D01*
X1884490Y1846688D01*
X1884567Y1847101D01*
Y1849168D01*
G01X1886133Y1846068D02*
Y1849168D01*
X1887053D01*
X1887360Y1849013D01*
X1887590Y1848651D01*
X1887667Y1848238D01*
X1887590Y1847825D01*
X1887398Y1847515D01*
X1887053Y1847360D01*
X1886133D01*
G01X1890000Y1846068D02*
Y1849168D01*
X1889540Y1848548D01*
G01Y1846068D02*
X1890460D01*
G01X1892372Y1847360D02*
X1892640Y1847721D01*
X1892870Y1847928D01*
X1893177Y1848031D01*
X1893445Y1847928D01*
X1893637Y1847721D01*
X1893790Y1847411D01*
X1893828Y1847050D01*
X1893790Y1846740D01*
X1893637Y1846430D01*
X1893407Y1846171D01*
X1893138Y1846068D01*
X1892832Y1846171D01*
X1892563Y1846481D01*
X1892410Y1846946D01*
X1892372Y1847463D01*
X1892448Y1848135D01*
X1892563Y1848496D01*
X1892755Y1848858D01*
X1893023Y1849116D01*
X1893292Y1849168D01*
X1893560Y1849065D01*
X1893752Y1848806D01*
G01X1895050Y1845035D02*
X1897350D01*
G01X1898572Y1848651D02*
X1898802Y1848961D01*
X1899070Y1849116D01*
X1899377Y1849168D01*
X1899760Y1849065D01*
X1900028Y1848806D01*
X1900105Y1848496D01*
X1900067Y1848186D01*
X1899913Y1847928D01*
X1899147Y1847411D01*
X1898802Y1847050D01*
X1898572Y1846533D01*
X1898495Y1846068D01*
X1900105D01*
G01X1901557Y1846688D02*
X1901787Y1846326D01*
X1902093Y1846120D01*
X1902438Y1846068D01*
X1902745Y1846120D01*
X1903052Y1846378D01*
X1903243Y1846688D01*
X1903282Y1846998D01*
X1903205Y1847360D01*
X1902937Y1847618D01*
X1902668Y1847721D01*
X1902323D01*
G01X1902668D02*
X1902898Y1847876D01*
X1903090Y1848135D01*
X1903167Y1848445D01*
X1903090Y1848755D01*
X1902898Y1849013D01*
X1902553Y1849168D01*
X1902208Y1849116D01*
X1901863Y1848910D01*
G01X1900000Y469845D02*
X1896900Y471455D01*
G01Y469845D02*
X1900000Y471455D01*
G01X1899380Y472907D02*
X1899742Y473137D01*
X1899948Y473443D01*
X1900000Y473788D01*
X1899948Y474095D01*
X1899690Y474402D01*
X1899380Y474593D01*
X1899070Y474632D01*
X1898708Y474555D01*
X1898450Y474287D01*
X1898347Y474018D01*
Y473673D01*
G01Y474018D02*
X1898192Y474248D01*
X1897933Y474440D01*
X1897623Y474517D01*
X1897313Y474440D01*
X1897055Y474248D01*
X1896900Y473903D01*
X1896952Y473558D01*
X1897158Y473213D01*
G01X1898708Y476122D02*
X1898347Y476390D01*
X1898140Y476620D01*
X1898037Y476927D01*
X1898140Y477195D01*
X1898347Y477387D01*
X1898657Y477540D01*
X1899018Y477578D01*
X1899328Y477540D01*
X1899638Y477387D01*
X1899897Y477157D01*
X1900000Y476888D01*
X1899897Y476582D01*
X1899587Y476313D01*
X1899122Y476160D01*
X1898605Y476122D01*
X1897933Y476198D01*
X1897572Y476313D01*
X1897210Y476505D01*
X1896952Y476773D01*
X1896900Y477042D01*
X1897003Y477310D01*
X1897262Y477502D01*
G01X1893605Y468898D02*
X1894155D01*
Y478898D01*
G01D02*
X1891655D01*
G01Y582848D02*
X1894155D01*
Y592848D01*
X1893605D01*
G01Y716798D02*
X1894155D01*
Y726798D01*
G01D02*
X1891655D01*
G01Y830748D02*
X1894155D01*
Y840748D01*
X1893605D01*
G01X1897775Y850758D02*
X1895275D01*
Y840758D01*
X1895825D01*
G01X1894075Y954353D02*
X1890975Y955963D01*
G01Y954353D02*
X1894075Y955963D01*
G01X1893455Y957415D02*
X1893817Y957645D01*
X1894023Y957951D01*
X1894075Y958296D01*
X1894023Y958603D01*
X1893765Y958910D01*
X1893455Y959101D01*
X1893145Y959140D01*
X1892783Y959063D01*
X1892525Y958795D01*
X1892422Y958526D01*
Y958181D01*
G01Y958526D02*
X1892267Y958756D01*
X1892008Y958948D01*
X1891698Y959025D01*
X1891388Y958948D01*
X1891130Y958756D01*
X1890975Y958411D01*
X1891027Y958066D01*
X1891233Y957721D01*
G01X1894075Y961818D02*
X1890975D01*
X1893197Y960400D01*
Y962316D01*
G01X1895825Y964708D02*
X1895275D01*
Y954708D01*
G01D02*
X1897775D01*
G01X1902608Y972530D02*
X1889495Y1007106D01*
G01D02*
X1915721D01*
G01X1889973Y1299444D02*
X1903086Y1334020D01*
G01X1916199Y1299444D02*
X1889973D01*
G01X1902682Y1335503D02*
X1889569Y1370079D01*
G01D02*
X1915795D01*
G01X1915515Y1664472D02*
X1889289D01*
G01X1891707Y1670849D02*
X1902402Y1699048D01*
G01X1891943Y1859597D02*
X1892135Y1859287D01*
X1892365Y1859080D01*
X1892633Y1858977D01*
X1892940Y1859080D01*
X1893170Y1859287D01*
X1893400Y1859597D01*
X1893477Y1860010D01*
Y1862077D01*
G01X1895158Y1859339D02*
X1895427Y1859080D01*
X1895733Y1858977D01*
X1896040Y1859080D01*
X1896308Y1859390D01*
X1896500Y1859855D01*
X1896577Y1860320D01*
Y1860889D01*
X1896500Y1861354D01*
X1896308Y1861767D01*
X1896078Y1861974D01*
X1895810Y1862077D01*
X1895503Y1861974D01*
X1895273Y1861767D01*
X1895120Y1861457D01*
X1895043Y1861044D01*
X1895120Y1860682D01*
X1895312Y1860320D01*
X1895542Y1860114D01*
X1895810Y1860062D01*
X1896117Y1860165D01*
X1896347Y1860424D01*
X1896577Y1860889D01*
G01X1898910Y1862077D02*
X1898603Y1861974D01*
X1898373Y1861715D01*
X1898220Y1861405D01*
X1898105Y1860992D01*
X1898067Y1860527D01*
X1898105Y1860062D01*
X1898220Y1859649D01*
X1898373Y1859339D01*
X1898603Y1859080D01*
X1898910Y1858977D01*
X1899217Y1859080D01*
X1899447Y1859339D01*
X1899600Y1859649D01*
X1899715Y1860062D01*
X1899753Y1860527D01*
X1899715Y1860992D01*
X1899600Y1861405D01*
X1899447Y1861715D01*
X1899217Y1861974D01*
X1898910Y1862077D01*
G01X1900860Y1857944D02*
X1903160D01*
G01X1905953Y1861819D02*
X1905723Y1861974D01*
X1905455Y1862077D01*
X1905148D01*
X1904803Y1861922D01*
X1904535Y1861664D01*
X1904343Y1861354D01*
X1904190Y1860837D01*
X1904152Y1860372D01*
X1904228Y1859907D01*
X1904343Y1859597D01*
X1904573Y1859287D01*
X1904842Y1859080D01*
X1905110Y1858977D01*
X1905378D01*
X1905647Y1859080D01*
X1905877Y1859235D01*
X1906068Y1859442D01*
G01X1908210Y1858977D02*
X1907903Y1859029D01*
X1907635Y1859235D01*
X1907405Y1859545D01*
X1907252Y1859907D01*
X1907175Y1860320D01*
Y1860734D01*
X1907252Y1861147D01*
X1907405Y1861509D01*
X1907635Y1861819D01*
X1907903Y1862025D01*
X1908210Y1862077D01*
X1908517Y1862025D01*
X1908785Y1861819D01*
X1909015Y1861509D01*
X1909168Y1861147D01*
X1909245Y1860734D01*
Y1860320D01*
X1909168Y1859907D01*
X1909015Y1859545D01*
X1908785Y1859235D01*
X1908517Y1859029D01*
X1908210Y1858977D01*
G01X1910428D02*
Y1862077D01*
X1912192Y1858977D01*
Y1862077D01*
G01X1916475Y851113D02*
X1919575Y849503D01*
G01Y851113D02*
X1916475Y849503D01*
G01Y846748D02*
X1919575D01*
X1917353Y848166D01*
Y846250D01*
G01X1919058Y844836D02*
X1919368Y844606D01*
X1919523Y844338D01*
X1919575Y844031D01*
X1919472Y843648D01*
X1919213Y843380D01*
X1918903Y843303D01*
X1918593Y843341D01*
X1918335Y843495D01*
X1917818Y844261D01*
X1917457Y844606D01*
X1916940Y844836D01*
X1916475Y844913D01*
Y843303D01*
G01X1904725Y840758D02*
X1905825D01*
G01X1914725D02*
X1915275D01*
Y850758D01*
G01X1907775D02*
X1902775D01*
G01X1915275D02*
X1912775D01*
G01Y954708D02*
X1915275D01*
Y964708D01*
X1914725D01*
G01X1905825D02*
X1904725D01*
G01X1902775Y954708D02*
X1907775D01*
G01X1913099Y977369D02*
X1909999D01*
Y978135D01*
X1910154Y978442D01*
X1910361Y978672D01*
X1910671Y978864D01*
X1911032Y979017D01*
X1911549Y979055D01*
X1912066Y979017D01*
X1912427Y978864D01*
X1912737Y978672D01*
X1912944Y978442D01*
X1913099Y978135D01*
Y977369D01*
G01X1911446Y981619D02*
X1911291Y981772D01*
X1911032Y981887D01*
X1910671Y981964D01*
X1910361Y981887D01*
X1910154Y981734D01*
X1909999Y981465D01*
Y980430D01*
X1913099D01*
Y981695D01*
X1912892Y981964D01*
X1912582Y982117D01*
X1912221Y982194D01*
X1911859Y982117D01*
X1911549Y981887D01*
X1911446Y981619D01*
Y980430D01*
G01X1913099Y984412D02*
X1909999D01*
X1910619Y983952D01*
G01X1913099D02*
Y984872D01*
G01X1909999Y987512D02*
X1910102Y987205D01*
X1910361Y986975D01*
X1910671Y986822D01*
X1911084Y986707D01*
X1911549Y986669D01*
X1912014Y986707D01*
X1912427Y986822D01*
X1912737Y986975D01*
X1912996Y987205D01*
X1913099Y987512D01*
X1912996Y987819D01*
X1912737Y988049D01*
X1912427Y988202D01*
X1912014Y988317D01*
X1911549Y988355D01*
X1911084Y988317D01*
X1910671Y988202D01*
X1910361Y988049D01*
X1910102Y987819D01*
X1909999Y987512D01*
G01X1915721Y1007106D02*
X1902608Y972530D01*
G01X1903086Y1334020D02*
X1916199Y1299444D01*
G01X1914119Y1319159D02*
X1911019D01*
Y1319925D01*
X1911174Y1320232D01*
X1911381Y1320462D01*
X1911691Y1320654D01*
X1912052Y1320807D01*
X1912569Y1320845D01*
X1913086Y1320807D01*
X1913447Y1320654D01*
X1913757Y1320462D01*
X1913964Y1320232D01*
X1914119Y1319925D01*
Y1319159D01*
G01X1912466Y1323409D02*
X1912311Y1323562D01*
X1912052Y1323677D01*
X1911691Y1323754D01*
X1911381Y1323677D01*
X1911174Y1323524D01*
X1911019Y1323255D01*
Y1322220D01*
X1914119D01*
Y1323485D01*
X1913912Y1323754D01*
X1913602Y1323907D01*
X1913241Y1323984D01*
X1912879Y1323907D01*
X1912569Y1323677D01*
X1912466Y1323409D01*
Y1322220D01*
G01X1913757Y1325550D02*
X1914016Y1325819D01*
X1914119Y1326125D01*
X1914016Y1326432D01*
X1913706Y1326700D01*
X1913241Y1326892D01*
X1912776Y1326969D01*
X1912207D01*
X1911742Y1326892D01*
X1911329Y1326700D01*
X1911122Y1326470D01*
X1911019Y1326202D01*
X1911122Y1325895D01*
X1911329Y1325665D01*
X1911639Y1325512D01*
X1912052Y1325435D01*
X1912414Y1325512D01*
X1912776Y1325704D01*
X1912982Y1325934D01*
X1913034Y1326202D01*
X1912931Y1326509D01*
X1912672Y1326739D01*
X1912207Y1326969D01*
G01X1915795Y1370079D02*
X1902682Y1335503D01*
G01X1914219Y1343649D02*
X1911119D01*
Y1344415D01*
X1911274Y1344722D01*
X1911481Y1344952D01*
X1911791Y1345144D01*
X1912152Y1345297D01*
X1912669Y1345335D01*
X1913186Y1345297D01*
X1913547Y1345144D01*
X1913857Y1344952D01*
X1914064Y1344722D01*
X1914219Y1344415D01*
Y1343649D01*
G01X1912566Y1347899D02*
X1912411Y1348052D01*
X1912152Y1348167D01*
X1911791Y1348244D01*
X1911481Y1348167D01*
X1911274Y1348014D01*
X1911119Y1347745D01*
Y1346710D01*
X1914219D01*
Y1347975D01*
X1914012Y1348244D01*
X1913702Y1348397D01*
X1913341Y1348474D01*
X1912979Y1348397D01*
X1912669Y1348167D01*
X1912566Y1347899D01*
Y1346710D01*
G01X1914219Y1350615D02*
X1913547Y1350692D01*
X1912979Y1350807D01*
X1912462Y1350960D01*
X1911894Y1351152D01*
X1911119Y1351459D01*
Y1349925D01*
G01X1902402Y1699048D02*
X1915515Y1664472D01*
G01X1915339Y1681729D02*
X1912239D01*
Y1682495D01*
X1912394Y1682802D01*
X1912601Y1683032D01*
X1912911Y1683224D01*
X1913272Y1683377D01*
X1913789Y1683415D01*
X1914306Y1683377D01*
X1914667Y1683224D01*
X1914977Y1683032D01*
X1915184Y1682802D01*
X1915339Y1682495D01*
Y1681729D01*
G01X1913686Y1685979D02*
X1913531Y1686132D01*
X1913272Y1686247D01*
X1912911Y1686324D01*
X1912601Y1686247D01*
X1912394Y1686094D01*
X1912239Y1685825D01*
Y1684790D01*
X1915339D01*
Y1686055D01*
X1915132Y1686324D01*
X1914822Y1686477D01*
X1914461Y1686554D01*
X1914099Y1686477D01*
X1913789Y1686247D01*
X1913686Y1685979D01*
Y1684790D01*
G01X1915339Y1688772D02*
X1915287Y1689040D01*
X1915132Y1689347D01*
X1914874Y1689539D01*
X1914512Y1689615D01*
X1914151Y1689539D01*
X1913841Y1689309D01*
X1913686Y1688964D01*
Y1688580D01*
X1913582Y1688350D01*
X1913324Y1688159D01*
X1912962Y1688082D01*
X1912601Y1688197D01*
X1912342Y1688465D01*
X1912239Y1688772D01*
X1912342Y1689079D01*
X1912601Y1689347D01*
X1912962Y1689462D01*
X1913324Y1689385D01*
X1913582Y1689194D01*
X1913686Y1688964D01*
Y1688580D01*
X1913841Y1688235D01*
X1914151Y1688005D01*
X1914512Y1687929D01*
X1914874Y1688005D01*
X1915132Y1688197D01*
X1915287Y1688504D01*
X1915339Y1688772D01*
G01X1913277Y1836307D02*
Y1834085D01*
X1913430Y1833620D01*
X1913737Y1833310D01*
X1914120Y1833207D01*
X1914503Y1833310D01*
X1914810Y1833620D01*
X1914963Y1834085D01*
Y1836307D01*
G01X1916492Y1835790D02*
X1916722Y1836100D01*
X1916990Y1836255D01*
X1917297Y1836307D01*
X1917680Y1836204D01*
X1917948Y1835945D01*
X1918025Y1835635D01*
X1917987Y1835325D01*
X1917833Y1835067D01*
X1917067Y1834550D01*
X1916722Y1834189D01*
X1916492Y1833672D01*
X1916415Y1833207D01*
X1918025D01*
G01X1919170Y1832174D02*
X1921470D01*
G01X1922577Y1833207D02*
Y1836307D01*
X1923343D01*
X1923650Y1836152D01*
X1923880Y1835945D01*
X1924072Y1835635D01*
X1924225Y1835274D01*
X1924263Y1834757D01*
X1924225Y1834240D01*
X1924072Y1833879D01*
X1923880Y1833569D01*
X1923650Y1833362D01*
X1923343Y1833207D01*
X1922577D01*
G01X1927363Y1836049D02*
X1927133Y1836204D01*
X1926865Y1836307D01*
X1926558D01*
X1926213Y1836152D01*
X1925945Y1835894D01*
X1925753Y1835584D01*
X1925600Y1835067D01*
X1925562Y1834602D01*
X1925638Y1834137D01*
X1925753Y1833827D01*
X1925983Y1833517D01*
X1926252Y1833310D01*
X1926520Y1833207D01*
X1926788D01*
X1927057Y1833310D01*
X1927287Y1833465D01*
X1927478Y1833672D01*
G01X1905663Y1864817D02*
X1905855Y1864507D01*
X1906085Y1864300D01*
X1906353Y1864197D01*
X1906660Y1864300D01*
X1906890Y1864507D01*
X1907120Y1864817D01*
X1907197Y1865230D01*
Y1867297D01*
G01X1908763Y1864197D02*
Y1867297D01*
X1909683D01*
X1909990Y1867142D01*
X1910220Y1866780D01*
X1910297Y1866367D01*
X1910220Y1865954D01*
X1910028Y1865644D01*
X1909683Y1865489D01*
X1908763D01*
G01X1913090Y1864197D02*
Y1867297D01*
X1911672Y1865075D01*
X1913588D01*
G01X1915730Y1867297D02*
X1915423Y1867194D01*
X1915193Y1866935D01*
X1915040Y1866625D01*
X1914925Y1866212D01*
X1914887Y1865747D01*
X1914925Y1865282D01*
X1915040Y1864869D01*
X1915193Y1864559D01*
X1915423Y1864300D01*
X1915730Y1864197D01*
X1916037Y1864300D01*
X1916267Y1864559D01*
X1916420Y1864869D01*
X1916535Y1865282D01*
X1916573Y1865747D01*
X1916535Y1866212D01*
X1916420Y1866625D01*
X1916267Y1866935D01*
X1916037Y1867194D01*
X1915730Y1867297D01*
G01X1918830D02*
X1918523Y1867194D01*
X1918293Y1866935D01*
X1918140Y1866625D01*
X1918025Y1866212D01*
X1917987Y1865747D01*
X1918025Y1865282D01*
X1918140Y1864869D01*
X1918293Y1864559D01*
X1918523Y1864300D01*
X1918830Y1864197D01*
X1919137Y1864300D01*
X1919367Y1864559D01*
X1919520Y1864869D01*
X1919635Y1865282D01*
X1919673Y1865747D01*
X1919635Y1866212D01*
X1919520Y1866625D01*
X1919367Y1866935D01*
X1919137Y1867194D01*
X1918830Y1867297D01*
G01X1921087Y1864817D02*
X1921317Y1864455D01*
X1921623Y1864249D01*
X1921968Y1864197D01*
X1922275Y1864249D01*
X1922582Y1864507D01*
X1922773Y1864817D01*
X1922812Y1865127D01*
X1922735Y1865489D01*
X1922467Y1865747D01*
X1922198Y1865850D01*
X1921853D01*
G01X1922198D02*
X1922428Y1866005D01*
X1922620Y1866264D01*
X1922697Y1866574D01*
X1922620Y1866884D01*
X1922428Y1867142D01*
X1922083Y1867297D01*
X1921738Y1867245D01*
X1921393Y1867039D01*
G01X1923880Y1863164D02*
X1926180D01*
G01X1928130Y1864197D02*
Y1867297D01*
X1927670Y1866677D01*
G01Y1864197D02*
X1928590D01*
G01X1930502Y1866780D02*
X1930732Y1867090D01*
X1931000Y1867245D01*
X1931307Y1867297D01*
X1931690Y1867194D01*
X1931958Y1866935D01*
X1932035Y1866625D01*
X1931997Y1866315D01*
X1931843Y1866057D01*
X1931077Y1865540D01*
X1930732Y1865179D01*
X1930502Y1864662D01*
X1930425Y1864197D01*
X1932035D01*
G01X1916395Y-9332D02*
Y-19332D01*
G01X1925845D02*
X1926945D01*
G01X1916395D02*
X1916945D01*
G01X1921683Y-3701D02*
X1918583Y-2091D01*
G01Y-3701D02*
X1921683Y-2091D01*
G01Y204D02*
X1918583D01*
X1919203Y-256D01*
G01X1921683D02*
Y664D01*
G01X1920391Y2576D02*
X1920030Y2844D01*
X1919823Y3074D01*
X1919720Y3381D01*
X1919823Y3649D01*
X1920030Y3841D01*
X1920340Y3994D01*
X1920701Y4032D01*
X1921011Y3994D01*
X1921321Y3841D01*
X1921580Y3611D01*
X1921683Y3342D01*
X1921580Y3036D01*
X1921270Y2767D01*
X1920805Y2614D01*
X1920288Y2576D01*
X1919616Y2652D01*
X1919255Y2767D01*
X1918893Y2959D01*
X1918635Y3227D01*
X1918583Y3496D01*
X1918686Y3764D01*
X1918945Y3956D01*
G01X1928895Y-9332D02*
X1923895D01*
G01X1918895D02*
X1916395D01*
G01Y592868D02*
Y582868D01*
G01D02*
X1918895D01*
G01X1923895D02*
X1928895D01*
G01X1916945Y592868D02*
X1916395D01*
G01X1926945D02*
X1925845D01*
G01X1919167Y1858687D02*
Y1856465D01*
X1919320Y1856000D01*
X1919627Y1855690D01*
X1920010Y1855587D01*
X1920393Y1855690D01*
X1920700Y1856000D01*
X1920853Y1856465D01*
Y1858687D01*
G01X1923110Y1855587D02*
Y1858687D01*
X1922650Y1858067D01*
G01Y1855587D02*
X1923570D01*
G01X1925060Y1854554D02*
X1927360D01*
G01X1929617Y1857240D02*
X1929770Y1857395D01*
X1929885Y1857654D01*
X1929962Y1858015D01*
X1929885Y1858325D01*
X1929732Y1858532D01*
X1929463Y1858687D01*
X1928428D01*
Y1855587D01*
X1929693D01*
X1929962Y1855794D01*
X1930115Y1856104D01*
X1930192Y1856465D01*
X1930115Y1856827D01*
X1929885Y1857137D01*
X1929617Y1857240D01*
X1928428D01*
G01X1931643Y1858687D02*
Y1855587D01*
X1933177D01*
G01X1936395Y-19332D02*
Y-9332D01*
G01X1935845Y-19332D02*
X1936395D01*
G01Y-9332D02*
X1933895D01*
G01X1936660Y569365D02*
X1933560Y570975D01*
G01Y569365D02*
X1936660Y570975D01*
G01X1934077Y572542D02*
X1933767Y572772D01*
X1933612Y573040D01*
X1933560Y573347D01*
X1933663Y573730D01*
X1933922Y573998D01*
X1934232Y574075D01*
X1934542Y574037D01*
X1934800Y573883D01*
X1935317Y573117D01*
X1935678Y572772D01*
X1936195Y572542D01*
X1936660Y572465D01*
Y574075D01*
G01X1934077Y575642D02*
X1933767Y575872D01*
X1933612Y576140D01*
X1933560Y576447D01*
X1933663Y576830D01*
X1933922Y577098D01*
X1934232Y577175D01*
X1934542Y577137D01*
X1934800Y576983D01*
X1935317Y576217D01*
X1935678Y575872D01*
X1936195Y575642D01*
X1936660Y575565D01*
Y577175D01*
G01X1936395Y582868D02*
Y592868D01*
G01X1933895Y582868D02*
X1936395D01*
G01X1949895Y603048D02*
X1944895D01*
G01X1939895D02*
X1937395D01*
G01D02*
Y593048D01*
G01X1946845D02*
X1947945D01*
G01X1937395D02*
X1937945D01*
G01X1936395Y592868D02*
X1935845D01*
G01X1942290Y608655D02*
X1939190Y610265D01*
G01Y608655D02*
X1942290Y610265D01*
G01Y613020D02*
X1939190D01*
X1941412Y611602D01*
Y613518D01*
G01X1937945Y1205248D02*
X1937395D01*
G01D02*
Y1195248D01*
G01X1947945Y1205248D02*
X1946845D01*
G01X1937395Y1195248D02*
X1939895D01*
G01X1944895D02*
X1949895D01*
G01X1951178Y1333805D02*
X1938065Y1368381D01*
G01D02*
X1964291D01*
G01X1937371Y1664713D02*
X1937824Y1665907D01*
G01X1963597Y1664713D02*
X1937371D01*
G01X1940630Y1673306D02*
X1950484Y1699289D01*
G01X1934247Y1838707D02*
Y1836485D01*
X1934400Y1836020D01*
X1934707Y1835710D01*
X1935090Y1835607D01*
X1935473Y1835710D01*
X1935780Y1836020D01*
X1935933Y1836485D01*
Y1838707D01*
G01X1938190Y1835607D02*
Y1838707D01*
X1937730Y1838087D01*
G01Y1835607D02*
X1938650D01*
G01X1940140Y1834574D02*
X1942440D01*
G01X1943547Y1835607D02*
Y1838707D01*
X1944313D01*
X1944620Y1838552D01*
X1944850Y1838345D01*
X1945042Y1838035D01*
X1945195Y1837674D01*
X1945233Y1837157D01*
X1945195Y1836640D01*
X1945042Y1836279D01*
X1944850Y1835969D01*
X1944620Y1835762D01*
X1944313Y1835607D01*
X1943547D01*
G01X1948333Y1838449D02*
X1948103Y1838604D01*
X1947835Y1838707D01*
X1947528D01*
X1947183Y1838552D01*
X1946915Y1838294D01*
X1946723Y1837984D01*
X1946570Y1837467D01*
X1946532Y1837002D01*
X1946608Y1836537D01*
X1946723Y1836227D01*
X1946953Y1835917D01*
X1947222Y1835710D01*
X1947490Y1835607D01*
X1947758D01*
X1948027Y1835710D01*
X1948257Y1835865D01*
X1948448Y1836072D01*
G01X1937227Y1869037D02*
Y1866815D01*
X1937380Y1866350D01*
X1937687Y1866040D01*
X1938070Y1865937D01*
X1938453Y1866040D01*
X1938760Y1866350D01*
X1938913Y1866815D01*
Y1869037D01*
G01X1941170Y1865937D02*
Y1869037D01*
X1940710Y1868417D01*
G01Y1865937D02*
X1941630D01*
G01X1943120Y1864904D02*
X1945420D01*
G01X1947677Y1867590D02*
X1947830Y1867745D01*
X1947945Y1868004D01*
X1948022Y1868365D01*
X1947945Y1868675D01*
X1947792Y1868882D01*
X1947523Y1869037D01*
X1946488D01*
Y1865937D01*
X1947753D01*
X1948022Y1866144D01*
X1948175Y1866454D01*
X1948252Y1866815D01*
X1948175Y1867177D01*
X1947945Y1867487D01*
X1947677Y1867590D01*
X1946488D01*
G01X1949703Y1865937D02*
Y1869037D01*
X1950623D01*
X1950930Y1868882D01*
X1951160Y1868520D01*
X1951237Y1868107D01*
X1951160Y1867694D01*
X1950968Y1867384D01*
X1950623Y1867229D01*
X1949703D01*
G01X1958362Y-9190D02*
Y-19190D01*
G01D02*
X1958912D01*
G01X1962490Y-3585D02*
X1959390Y-1975D01*
G01Y-3585D02*
X1962490Y-1975D01*
G01X1959907Y-408D02*
X1959597Y-178D01*
X1959442Y90D01*
X1959390Y397D01*
X1959493Y780D01*
X1959752Y1048D01*
X1960062Y1125D01*
X1960372Y1087D01*
X1960630Y933D01*
X1961147Y167D01*
X1961508Y-178D01*
X1962025Y-408D01*
X1962490Y-485D01*
Y1125D01*
G01Y3420D02*
X1959390D01*
X1960010Y2960D01*
G01X1962490D02*
Y3880D01*
G01X1960862Y-9190D02*
X1958362D01*
G01Y593010D02*
Y583010D01*
G01D02*
X1960862D01*
G01X1958912Y593010D02*
X1958362D01*
G01X1957395Y603048D02*
X1954895D01*
G01X1957395Y593048D02*
Y603048D01*
G01X1956845Y593048D02*
X1957395D01*
G01X1955820Y1181885D02*
X1952720Y1183495D01*
G01Y1181885D02*
X1955820Y1183495D01*
G01Y1185790D02*
X1952720D01*
X1953340Y1185330D01*
G01X1955820D02*
Y1186250D01*
G01X1952720Y1188890D02*
X1952823Y1188583D01*
X1953082Y1188353D01*
X1953392Y1188200D01*
X1953805Y1188085D01*
X1954270Y1188047D01*
X1954735Y1188085D01*
X1955148Y1188200D01*
X1955458Y1188353D01*
X1955717Y1188583D01*
X1955820Y1188890D01*
X1955717Y1189197D01*
X1955458Y1189427D01*
X1955148Y1189580D01*
X1954735Y1189695D01*
X1954270Y1189733D01*
X1953805Y1189695D01*
X1953392Y1189580D01*
X1953082Y1189427D01*
X1952823Y1189197D01*
X1952720Y1188890D01*
G01X1957395Y1195248D02*
Y1205248D01*
G01D02*
X1956845D01*
G01X1954895Y1195248D02*
X1957395D01*
G01X1964291Y1368381D02*
X1951178Y1333805D01*
G01X1961228Y1340465D02*
X1958128D01*
Y1341231D01*
X1958283Y1341538D01*
X1958490Y1341768D01*
X1958800Y1341960D01*
X1959161Y1342113D01*
X1959678Y1342151D01*
X1960195Y1342113D01*
X1960556Y1341960D01*
X1960866Y1341768D01*
X1961073Y1341538D01*
X1961228Y1341231D01*
Y1340465D01*
G01X1959575Y1344715D02*
X1959420Y1344868D01*
X1959161Y1344983D01*
X1958800Y1345060D01*
X1958490Y1344983D01*
X1958283Y1344830D01*
X1958128Y1344561D01*
Y1343526D01*
X1961228D01*
Y1344791D01*
X1961021Y1345060D01*
X1960711Y1345213D01*
X1960350Y1345290D01*
X1959988Y1345213D01*
X1959678Y1344983D01*
X1959575Y1344715D01*
Y1343526D01*
G01X1961228Y1347508D02*
X1958128D01*
X1958748Y1347048D01*
G01X1961228D02*
Y1347968D01*
G01X1950484Y1699289D02*
X1963597Y1664713D01*
G01X1962578Y1683265D02*
X1959478D01*
Y1684031D01*
X1959633Y1684338D01*
X1959840Y1684568D01*
X1960150Y1684760D01*
X1960511Y1684913D01*
X1961028Y1684951D01*
X1961545Y1684913D01*
X1961906Y1684760D01*
X1962216Y1684568D01*
X1962423Y1684338D01*
X1962578Y1684031D01*
Y1683265D01*
G01X1960925Y1687515D02*
X1960770Y1687668D01*
X1960511Y1687783D01*
X1960150Y1687860D01*
X1959840Y1687783D01*
X1959633Y1687630D01*
X1959478Y1687361D01*
Y1686326D01*
X1962578D01*
Y1687591D01*
X1962371Y1687860D01*
X1962061Y1688013D01*
X1961700Y1688090D01*
X1961338Y1688013D01*
X1961028Y1687783D01*
X1960925Y1687515D01*
Y1686326D01*
G01X1962578Y1690768D02*
X1959478D01*
X1961700Y1689350D01*
Y1691266D01*
G01X1956642Y1859855D02*
Y1857633D01*
X1956795Y1857168D01*
X1957102Y1856858D01*
X1957485Y1856755D01*
X1957868Y1856858D01*
X1958175Y1857168D01*
X1958328Y1857633D01*
Y1859855D01*
G01X1959857Y1859338D02*
X1960087Y1859648D01*
X1960355Y1859803D01*
X1960662Y1859855D01*
X1961045Y1859752D01*
X1961313Y1859493D01*
X1961390Y1859183D01*
X1961352Y1858873D01*
X1961198Y1858615D01*
X1960432Y1858098D01*
X1960087Y1857737D01*
X1959857Y1857220D01*
X1959780Y1856755D01*
X1961390D01*
G01X1962535Y1855722D02*
X1964835D01*
G01X1967092Y1858408D02*
X1967245Y1858563D01*
X1967360Y1858822D01*
X1967437Y1859183D01*
X1967360Y1859493D01*
X1967207Y1859700D01*
X1966938Y1859855D01*
X1965903D01*
Y1856755D01*
X1967168D01*
X1967437Y1856962D01*
X1967590Y1857272D01*
X1967667Y1857633D01*
X1967590Y1857995D01*
X1967360Y1858305D01*
X1967092Y1858408D01*
X1965903D01*
G01X1969118Y1856755D02*
Y1859855D01*
X1970038D01*
X1970345Y1859700D01*
X1970575Y1859338D01*
X1970652Y1858925D01*
X1970575Y1858512D01*
X1970383Y1858202D01*
X1970038Y1858047D01*
X1969118D01*
G01X1956037Y1869207D02*
Y1866985D01*
X1956190Y1866520D01*
X1956497Y1866210D01*
X1956880Y1866107D01*
X1957263Y1866210D01*
X1957570Y1866520D01*
X1957723Y1866985D01*
Y1869207D01*
G01X1959252Y1868690D02*
X1959482Y1869000D01*
X1959750Y1869155D01*
X1960057Y1869207D01*
X1960440Y1869104D01*
X1960708Y1868845D01*
X1960785Y1868535D01*
X1960747Y1868225D01*
X1960593Y1867967D01*
X1959827Y1867450D01*
X1959482Y1867089D01*
X1959252Y1866572D01*
X1959175Y1866107D01*
X1960785D01*
G01X1961930Y1865074D02*
X1964230D01*
G01X1966487Y1867760D02*
X1966640Y1867915D01*
X1966755Y1868174D01*
X1966832Y1868535D01*
X1966755Y1868845D01*
X1966602Y1869052D01*
X1966333Y1869207D01*
X1965298D01*
Y1866107D01*
X1966563D01*
X1966832Y1866314D01*
X1966985Y1866624D01*
X1967062Y1866985D01*
X1966985Y1867347D01*
X1966755Y1867657D01*
X1966487Y1867760D01*
X1965298D01*
G01X1968513Y1869207D02*
Y1866107D01*
X1970047D01*
G01X1978362Y-19190D02*
Y-9190D01*
G01X1967812Y-19190D02*
X1968912D01*
G01X1977812D02*
X1978362D01*
G01X1970862Y-9190D02*
X1965862D01*
G01X1978362D02*
X1975862D01*
G01X1977850Y569865D02*
X1974750Y571475D01*
G01Y569865D02*
X1977850Y571475D01*
G01Y573770D02*
X1974750D01*
X1975370Y573310D01*
G01X1977850D02*
Y574230D01*
G01X1977385Y576027D02*
X1977643Y576257D01*
X1977798Y576525D01*
X1977850Y576870D01*
X1977747Y577215D01*
X1977540Y577483D01*
X1977178Y577675D01*
X1976765Y577713D01*
X1976352Y577637D01*
X1976093Y577445D01*
X1975887Y577177D01*
X1975835Y576908D01*
X1975887Y576640D01*
X1976093Y576295D01*
X1974750Y576410D01*
Y577445D01*
G01X1978362Y583010D02*
Y593010D01*
G01X1965862Y583010D02*
X1970862D01*
G01X1975862D02*
X1978362D01*
G01X1981982Y603020D02*
X1979482D01*
G01D02*
Y593020D01*
G01D02*
X1980032D01*
G01X1968912Y593010D02*
X1967812D01*
G01X1978362D02*
X1977812D01*
G01X1980032Y1205220D02*
X1979482D01*
G01D02*
Y1195220D01*
G01D02*
X1981982D01*
G01X1980505Y1368681D02*
X2006731D01*
G01X1993618Y1334105D02*
X1980505Y1368681D01*
G01X1980034Y1664091D02*
X1993147Y1698667D01*
G01X2006260Y1664091D02*
X1980034D01*
G01X1972018Y1852169D02*
X1972210Y1851859D01*
X1972440Y1851652D01*
X1972708Y1851549D01*
X1973015Y1851652D01*
X1973245Y1851859D01*
X1973475Y1852169D01*
X1973552Y1852582D01*
Y1854649D01*
G01X1975118Y1851549D02*
Y1854649D01*
X1976038D01*
X1976345Y1854494D01*
X1976575Y1854132D01*
X1976652Y1853719D01*
X1976575Y1853306D01*
X1976383Y1852996D01*
X1976038Y1852841D01*
X1975118D01*
G01X1978985Y1851549D02*
Y1854649D01*
X1978525Y1854029D01*
G01Y1851549D02*
X1979445D01*
G01X1981242Y1852014D02*
X1981472Y1851756D01*
X1981740Y1851601D01*
X1982085Y1851549D01*
X1982430Y1851652D01*
X1982698Y1851859D01*
X1982890Y1852221D01*
X1982928Y1852634D01*
X1982852Y1853047D01*
X1982660Y1853306D01*
X1982392Y1853512D01*
X1982123Y1853564D01*
X1981855Y1853512D01*
X1981510Y1853306D01*
X1981625Y1854649D01*
X1982660D01*
G01X1984035Y1850516D02*
X1986335D01*
G01X1987557Y1854132D02*
X1987787Y1854442D01*
X1988055Y1854597D01*
X1988362Y1854649D01*
X1988745Y1854546D01*
X1989013Y1854287D01*
X1989090Y1853977D01*
X1989052Y1853667D01*
X1988898Y1853409D01*
X1988132Y1852892D01*
X1987787Y1852531D01*
X1987557Y1852014D01*
X1987480Y1851549D01*
X1989090D01*
G01X1990542Y1852169D02*
X1990772Y1851807D01*
X1991078Y1851601D01*
X1991423Y1851549D01*
X1991730Y1851601D01*
X1992037Y1851859D01*
X1992228Y1852169D01*
X1992267Y1852479D01*
X1992190Y1852841D01*
X1991922Y1853099D01*
X1991653Y1853202D01*
X1991308D01*
G01X1991653D02*
X1991883Y1853357D01*
X1992075Y1853616D01*
X1992152Y1853926D01*
X1992075Y1854236D01*
X1991883Y1854494D01*
X1991538Y1854649D01*
X1991193Y1854597D01*
X1990848Y1854391D01*
G01X1991982Y603020D02*
X1986982D01*
G01X1999482D02*
X1996982D01*
G01X1988932Y593020D02*
X1990032D01*
G01X1985050Y608771D02*
X1981950Y610381D01*
G01Y608771D02*
X1985050Y610381D01*
G01X1984688Y612024D02*
X1984947Y612293D01*
X1985050Y612599D01*
X1984947Y612906D01*
X1984637Y613174D01*
X1984172Y613366D01*
X1983707Y613443D01*
X1983138D01*
X1982673Y613366D01*
X1982260Y613174D01*
X1982053Y612944D01*
X1981950Y612676D01*
X1982053Y612369D01*
X1982260Y612139D01*
X1982570Y611986D01*
X1982983Y611909D01*
X1983345Y611986D01*
X1983707Y612178D01*
X1983913Y612408D01*
X1983965Y612676D01*
X1983862Y612983D01*
X1983603Y613213D01*
X1983138Y613443D01*
G01X1998330Y1185181D02*
X1995230Y1186791D01*
G01Y1185181D02*
X1998330Y1186791D01*
G01X1997710Y1188243D02*
X1998072Y1188473D01*
X1998278Y1188779D01*
X1998330Y1189124D01*
X1998278Y1189431D01*
X1998020Y1189738D01*
X1997710Y1189929D01*
X1997400Y1189968D01*
X1997038Y1189891D01*
X1996780Y1189623D01*
X1996677Y1189354D01*
Y1189009D01*
G01Y1189354D02*
X1996522Y1189584D01*
X1996263Y1189776D01*
X1995953Y1189853D01*
X1995643Y1189776D01*
X1995385Y1189584D01*
X1995230Y1189239D01*
X1995282Y1188894D01*
X1995488Y1188549D01*
G01X1990032Y1205220D02*
X1988932D01*
G01X1986982Y1195220D02*
X1991982D01*
G01X1996982D02*
X1999482D01*
G01X2006731Y1368681D02*
X1993618Y1334105D01*
G01X1993147Y1698667D02*
X2006260Y1664091D01*
G01X2000452Y-9180D02*
Y-19180D01*
G01D02*
X2001002D01*
G01X2009902D02*
X2011002D01*
G01X2004010Y-3789D02*
X2000910Y-2179D01*
G01Y-3789D02*
X2004010Y-2179D01*
G01X2001427Y-612D02*
X2001117Y-382D01*
X2000962Y-114D01*
X2000910Y193D01*
X2001013Y576D01*
X2001272Y844D01*
X2001582Y921D01*
X2001892Y883D01*
X2002150Y729D01*
X2002667Y-37D01*
X2003028Y-382D01*
X2003545Y-612D01*
X2004010Y-689D01*
Y921D01*
G01X2000910Y3216D02*
X2001013Y2909D01*
X2001272Y2679D01*
X2001582Y2526D01*
X2001995Y2411D01*
X2002460Y2373D01*
X2002925Y2411D01*
X2003338Y2526D01*
X2003648Y2679D01*
X2003907Y2909D01*
X2004010Y3216D01*
X2003907Y3523D01*
X2003648Y3753D01*
X2003338Y3906D01*
X2002925Y4021D01*
X2002460Y4059D01*
X2001995Y4021D01*
X2001582Y3906D01*
X2001272Y3753D01*
X2001013Y3523D01*
X2000910Y3216D01*
G01X2002952Y-9180D02*
X2000452D01*
G01X2012952D02*
X2007952D01*
G01X2000452Y593020D02*
Y583020D01*
G01X2007952D02*
X2012952D01*
G01X2000452D02*
X2002952D01*
G01X2001002Y593020D02*
X2000452D01*
G01X2011002D02*
X2009902D01*
G01X1999482D02*
Y603020D01*
G01X1998932Y593020D02*
X1999482D01*
G01Y1195220D02*
Y1205220D01*
G01D02*
X1998932D01*
G01X2005698Y1344745D02*
X2002598D01*
Y1345511D01*
X2002753Y1345818D01*
X2002960Y1346048D01*
X2003270Y1346240D01*
X2003631Y1346393D01*
X2004148Y1346431D01*
X2004665Y1346393D01*
X2005026Y1346240D01*
X2005336Y1346048D01*
X2005543Y1345818D01*
X2005698Y1345511D01*
Y1344745D01*
G01X2004045Y1348995D02*
X2003890Y1349148D01*
X2003631Y1349263D01*
X2003270Y1349340D01*
X2002960Y1349263D01*
X2002753Y1349110D01*
X2002598Y1348841D01*
Y1347806D01*
X2005698D01*
Y1349071D01*
X2005491Y1349340D01*
X2005181Y1349493D01*
X2004820Y1349570D01*
X2004458Y1349493D01*
X2004148Y1349263D01*
X2004045Y1348995D01*
Y1347806D01*
G01X2003115Y1351060D02*
X2002805Y1351290D01*
X2002650Y1351558D01*
X2002598Y1351865D01*
X2002701Y1352248D01*
X2002960Y1352516D01*
X2003270Y1352593D01*
X2003580Y1352555D01*
X2003838Y1352401D01*
X2004355Y1351635D01*
X2004716Y1351290D01*
X2005233Y1351060D01*
X2005698Y1350983D01*
Y1352593D01*
G01X2005148Y1682145D02*
X2002048D01*
Y1682911D01*
X2002203Y1683218D01*
X2002410Y1683448D01*
X2002720Y1683640D01*
X2003081Y1683793D01*
X2003598Y1683831D01*
X2004115Y1683793D01*
X2004476Y1683640D01*
X2004786Y1683448D01*
X2004993Y1683218D01*
X2005148Y1682911D01*
Y1682145D01*
G01X2003495Y1686395D02*
X2003340Y1686548D01*
X2003081Y1686663D01*
X2002720Y1686740D01*
X2002410Y1686663D01*
X2002203Y1686510D01*
X2002048Y1686241D01*
Y1685206D01*
X2005148D01*
Y1686471D01*
X2004941Y1686740D01*
X2004631Y1686893D01*
X2004270Y1686970D01*
X2003908Y1686893D01*
X2003598Y1686663D01*
X2003495Y1686395D01*
Y1685206D01*
G01X2004528Y1688345D02*
X2004890Y1688575D01*
X2005096Y1688881D01*
X2005148Y1689226D01*
X2005096Y1689533D01*
X2004838Y1689840D01*
X2004528Y1690031D01*
X2004218Y1690070D01*
X2003856Y1689993D01*
X2003598Y1689725D01*
X2003495Y1689456D01*
Y1689111D01*
G01Y1689456D02*
X2003340Y1689686D01*
X2003081Y1689878D01*
X2002771Y1689955D01*
X2002461Y1689878D01*
X2002203Y1689686D01*
X2002048Y1689341D01*
X2002100Y1688996D01*
X2002306Y1688651D01*
G01X2020452Y-19180D02*
Y-9180D01*
G01X2019902Y-19180D02*
X2020452D01*
G01Y-9180D02*
X2017952D01*
G01X2019030Y569911D02*
X2015930Y571521D01*
G01Y569911D02*
X2019030Y571521D01*
G01Y573816D02*
X2015930D01*
X2016550Y573356D01*
G01X2019030D02*
Y574276D01*
G01Y577376D02*
X2015930D01*
X2018152Y575958D01*
Y577874D01*
G01X2020452Y583020D02*
Y593020D01*
G01X2017952Y583020D02*
X2020452D01*
G01Y593020D02*
X2019902D01*
G01X2023952Y603200D02*
X2021452D01*
G01D02*
Y593200D01*
G01X2033952Y603200D02*
X2028952D01*
G01X2021452Y593200D02*
X2022002D01*
G01X2026702Y608965D02*
X2023602Y610575D01*
G01Y608965D02*
X2026702Y610575D01*
G01X2024119Y612142D02*
X2023809Y612372D01*
X2023654Y612640D01*
X2023602Y612947D01*
X2023705Y613330D01*
X2023964Y613598D01*
X2024274Y613675D01*
X2024584Y613637D01*
X2024842Y613483D01*
X2025359Y612717D01*
X2025720Y612372D01*
X2026237Y612142D01*
X2026702Y612065D01*
Y613675D01*
G01X2022002Y1205400D02*
X2021452D01*
G01D02*
Y1195400D01*
G01X2028952D02*
X2033952D01*
G01X2021452D02*
X2023952D01*
G01X2042419Y-9038D02*
Y-19038D01*
G01D02*
X2042969D01*
G01X2045730Y-3449D02*
X2042630Y-1839D01*
G01Y-3449D02*
X2045730Y-1839D01*
G01Y456D02*
X2042630D01*
X2043250Y-4D01*
G01X2045730D02*
Y916D01*
G01X2045110Y2713D02*
X2045472Y2943D01*
X2045678Y3249D01*
X2045730Y3594D01*
X2045678Y3901D01*
X2045420Y4208D01*
X2045110Y4399D01*
X2044800Y4438D01*
X2044438Y4361D01*
X2044180Y4093D01*
X2044077Y3824D01*
Y3479D01*
G01Y3824D02*
X2043922Y4054D01*
X2043663Y4246D01*
X2043353Y4323D01*
X2043043Y4246D01*
X2042785Y4054D01*
X2042630Y3709D01*
X2042682Y3364D01*
X2042888Y3019D01*
G01X2044919Y-9038D02*
X2042419D01*
G01Y593162D02*
Y583162D01*
G01D02*
X2044919D01*
G01X2042969Y593162D02*
X2042419D01*
G01X2041452Y593200D02*
Y603200D01*
G01D02*
X2038952D01*
G01X2030902Y593200D02*
X2032002D01*
G01X2040902D02*
X2041452D01*
G01X2039830Y1184981D02*
X2036730Y1186591D01*
G01Y1184981D02*
X2039830Y1186591D01*
G01Y1188886D02*
X2039778Y1189154D01*
X2039623Y1189461D01*
X2039365Y1189653D01*
X2039003Y1189729D01*
X2038642Y1189653D01*
X2038332Y1189423D01*
X2038177Y1189078D01*
Y1188694D01*
X2038073Y1188464D01*
X2037815Y1188273D01*
X2037453Y1188196D01*
X2037092Y1188311D01*
X2036833Y1188579D01*
X2036730Y1188886D01*
X2036833Y1189193D01*
X2037092Y1189461D01*
X2037453Y1189576D01*
X2037815Y1189499D01*
X2038073Y1189308D01*
X2038177Y1189078D01*
Y1188694D01*
X2038332Y1188349D01*
X2038642Y1188119D01*
X2039003Y1188043D01*
X2039365Y1188119D01*
X2039623Y1188311D01*
X2039778Y1188618D01*
X2039830Y1188886D01*
G01X2041452Y1195400D02*
Y1205400D01*
G01D02*
X2040902D01*
G01X2032002D02*
X2030902D01*
G01X2038952Y1195400D02*
X2041452D01*
G01X2043552Y1770004D02*
Y1773104D01*
X2044472D01*
X2044779Y1772949D01*
X2045009Y1772587D01*
X2045086Y1772174D01*
X2045009Y1771761D01*
X2044817Y1771451D01*
X2044472Y1771296D01*
X2043552D01*
G01X2046729Y1769901D02*
X2048109Y1773104D01*
G01X2049637Y1770004D02*
Y1773104D01*
X2051401Y1770004D01*
Y1773104D01*
G01X2053619Y1769901D02*
X2053542Y1769952D01*
Y1770056D01*
X2053619Y1770107D01*
X2053696Y1770056D01*
Y1769952D01*
X2053619Y1769901D01*
G01Y1771296D02*
X2053542Y1771347D01*
Y1771451D01*
X2053619Y1771502D01*
X2053696Y1771451D01*
Y1771347D01*
X2053619Y1771296D01*
G01X2055876Y1770004D02*
Y1773104D01*
X2056642D01*
X2056949Y1772949D01*
X2057179Y1772742D01*
X2057371Y1772432D01*
X2057524Y1772071D01*
X2057562Y1771554D01*
X2057524Y1771037D01*
X2057371Y1770676D01*
X2057179Y1770366D01*
X2056949Y1770159D01*
X2056642Y1770004D01*
X2055876D01*
G01X2058861D02*
X2059819Y1773104D01*
X2060777Y1770004D01*
G01X2060432Y1771089D02*
X2059206D01*
G01X2062919Y1773104D02*
X2062612Y1773001D01*
X2062382Y1772742D01*
X2062229Y1772432D01*
X2062114Y1772019D01*
X2062076Y1771554D01*
X2062114Y1771089D01*
X2062229Y1770676D01*
X2062382Y1770366D01*
X2062612Y1770107D01*
X2062919Y1770004D01*
X2063226Y1770107D01*
X2063456Y1770366D01*
X2063609Y1770676D01*
X2063724Y1771089D01*
X2063762Y1771554D01*
X2063724Y1772019D01*
X2063609Y1772432D01*
X2063456Y1772742D01*
X2063226Y1773001D01*
X2062919Y1773104D01*
G01X2065291Y1770004D02*
Y1773104D01*
X2066747D01*
G01X2066211Y1771606D02*
X2065291D01*
G01X2069119Y1773104D02*
X2068812Y1773001D01*
X2068582Y1772742D01*
X2068429Y1772432D01*
X2068314Y1772019D01*
X2068276Y1771554D01*
X2068314Y1771089D01*
X2068429Y1770676D01*
X2068582Y1770366D01*
X2068812Y1770107D01*
X2069119Y1770004D01*
X2069426Y1770107D01*
X2069656Y1770366D01*
X2069809Y1770676D01*
X2069924Y1771089D01*
X2069962Y1771554D01*
X2069924Y1772019D01*
X2069809Y1772432D01*
X2069656Y1772742D01*
X2069426Y1773001D01*
X2069119Y1773104D01*
G01X2072219D02*
Y1770004D01*
G01X2071337Y1773104D02*
X2073101D01*
G01X2074322Y1770004D02*
Y1773104D01*
X2075319Y1770521D01*
X2076316Y1773104D01*
Y1770004D01*
G01X2078726Y1771657D02*
X2078879Y1771812D01*
X2078994Y1772071D01*
X2079071Y1772432D01*
X2078994Y1772742D01*
X2078841Y1772949D01*
X2078572Y1773104D01*
X2077537D01*
Y1770004D01*
X2078802D01*
X2079071Y1770211D01*
X2079224Y1770521D01*
X2079301Y1770882D01*
X2079224Y1771244D01*
X2078994Y1771554D01*
X2078726Y1771657D01*
X2077537D01*
G01X2081059Y1773104D02*
X2081979D01*
G01X2081519D02*
Y1770004D01*
G01X2081059D02*
X2081979D01*
G01X2083852Y1770624D02*
X2084044Y1770314D01*
X2084274Y1770107D01*
X2084542Y1770004D01*
X2084849Y1770107D01*
X2085079Y1770314D01*
X2085309Y1770624D01*
X2085386Y1771037D01*
Y1773104D01*
G01X2087719D02*
X2087412Y1773001D01*
X2087182Y1772742D01*
X2087029Y1772432D01*
X2086914Y1772019D01*
X2086876Y1771554D01*
X2086914Y1771089D01*
X2087029Y1770676D01*
X2087182Y1770366D01*
X2087412Y1770107D01*
X2087719Y1770004D01*
X2088026Y1770107D01*
X2088256Y1770366D01*
X2088409Y1770676D01*
X2088524Y1771089D01*
X2088562Y1771554D01*
X2088524Y1772019D01*
X2088409Y1772432D01*
X2088256Y1772742D01*
X2088026Y1773001D01*
X2087719Y1773104D01*
G01X2053072Y-46886D02*
Y-43786D01*
X2053992D01*
X2054299Y-43941D01*
X2054529Y-44303D01*
X2054606Y-44716D01*
X2054529Y-45129D01*
X2054337Y-45439D01*
X2053992Y-45594D01*
X2053072D01*
G01X2056249Y-46989D02*
X2057629Y-43786D01*
G01X2059157Y-46886D02*
Y-43786D01*
X2060921Y-46886D01*
Y-43786D01*
G01X2063139Y-46989D02*
X2063062Y-46938D01*
Y-46834D01*
X2063139Y-46783D01*
X2063216Y-46834D01*
Y-46938D01*
X2063139Y-46989D01*
G01Y-45594D02*
X2063062Y-45543D01*
Y-45439D01*
X2063139Y-45388D01*
X2063216Y-45439D01*
Y-45543D01*
X2063139Y-45594D01*
G01X2065396Y-46886D02*
Y-43786D01*
X2066162D01*
X2066469Y-43941D01*
X2066699Y-44148D01*
X2066891Y-44458D01*
X2067044Y-44819D01*
X2067082Y-45336D01*
X2067044Y-45853D01*
X2066891Y-46214D01*
X2066699Y-46524D01*
X2066469Y-46731D01*
X2066162Y-46886D01*
X2065396D01*
G01X2068381D02*
X2069339Y-43786D01*
X2070297Y-46886D01*
G01X2069952Y-45801D02*
X2068726D01*
G01X2072439Y-43786D02*
X2072132Y-43889D01*
X2071902Y-44148D01*
X2071749Y-44458D01*
X2071634Y-44871D01*
X2071596Y-45336D01*
X2071634Y-45801D01*
X2071749Y-46214D01*
X2071902Y-46524D01*
X2072132Y-46783D01*
X2072439Y-46886D01*
X2072746Y-46783D01*
X2072976Y-46524D01*
X2073129Y-46214D01*
X2073244Y-45801D01*
X2073282Y-45336D01*
X2073244Y-44871D01*
X2073129Y-44458D01*
X2072976Y-44148D01*
X2072746Y-43889D01*
X2072439Y-43786D01*
G01X2074811Y-46886D02*
Y-43786D01*
X2076267D01*
G01X2075731Y-45284D02*
X2074811D01*
G01X2078639Y-43786D02*
X2078332Y-43889D01*
X2078102Y-44148D01*
X2077949Y-44458D01*
X2077834Y-44871D01*
X2077796Y-45336D01*
X2077834Y-45801D01*
X2077949Y-46214D01*
X2078102Y-46524D01*
X2078332Y-46783D01*
X2078639Y-46886D01*
X2078946Y-46783D01*
X2079176Y-46524D01*
X2079329Y-46214D01*
X2079444Y-45801D01*
X2079482Y-45336D01*
X2079444Y-44871D01*
X2079329Y-44458D01*
X2079176Y-44148D01*
X2078946Y-43889D01*
X2078639Y-43786D01*
G01X2081739D02*
Y-46886D01*
G01X2080857Y-43786D02*
X2082621D01*
G01X2083842Y-46886D02*
Y-43786D01*
X2084839Y-46369D01*
X2085836Y-43786D01*
Y-46886D01*
G01X2088246Y-45233D02*
X2088399Y-45078D01*
X2088514Y-44819D01*
X2088591Y-44458D01*
X2088514Y-44148D01*
X2088361Y-43941D01*
X2088092Y-43786D01*
X2087057D01*
Y-46886D01*
X2088322D01*
X2088591Y-46679D01*
X2088744Y-46369D01*
X2088821Y-46008D01*
X2088744Y-45646D01*
X2088514Y-45336D01*
X2088246Y-45233D01*
X2087057D01*
G01X2090579Y-43786D02*
X2091499D01*
G01X2091039D02*
Y-46886D01*
G01X2090579D02*
X2091499D01*
G01X2093372Y-46266D02*
X2093564Y-46576D01*
X2093794Y-46783D01*
X2094062Y-46886D01*
X2094369Y-46783D01*
X2094599Y-46576D01*
X2094829Y-46266D01*
X2094906Y-45853D01*
Y-43786D01*
G01X2097239D02*
X2096932Y-43889D01*
X2096702Y-44148D01*
X2096549Y-44458D01*
X2096434Y-44871D01*
X2096396Y-45336D01*
X2096434Y-45801D01*
X2096549Y-46214D01*
X2096702Y-46524D01*
X2096932Y-46783D01*
X2097239Y-46886D01*
X2097546Y-46783D01*
X2097776Y-46524D01*
X2097929Y-46214D01*
X2098044Y-45801D01*
X2098082Y-45336D01*
X2098044Y-44871D01*
X2097929Y-44458D01*
X2097776Y-44148D01*
X2097546Y-43889D01*
X2097239Y-43786D01*
G01X2051869Y-19038D02*
X2052969D01*
G01X2061869D02*
X2062419D01*
G01D02*
Y-9038D01*
G01X2054919D02*
X2049919D01*
G01X2062419D02*
X2059919D01*
G01X2058820Y569681D02*
X2055720Y571291D01*
G01Y569681D02*
X2058820Y571291D01*
G01Y573586D02*
X2055720D01*
X2056340Y573126D01*
G01X2058820D02*
Y574046D01*
G01X2058458Y576034D02*
X2058717Y576303D01*
X2058820Y576609D01*
X2058717Y576916D01*
X2058407Y577184D01*
X2057942Y577376D01*
X2057477Y577453D01*
X2056908D01*
X2056443Y577376D01*
X2056030Y577184D01*
X2055823Y576954D01*
X2055720Y576686D01*
X2055823Y576379D01*
X2056030Y576149D01*
X2056340Y575996D01*
X2056753Y575919D01*
X2057115Y575996D01*
X2057477Y576188D01*
X2057683Y576418D01*
X2057735Y576686D01*
X2057632Y576993D01*
X2057373Y577223D01*
X2056908Y577453D01*
G01X2059919Y583162D02*
X2062419D01*
G01D02*
Y593162D01*
G01X2049919Y583162D02*
X2054919D01*
G01X2062419Y593162D02*
X2061869D01*
G01X2052969D02*
X2051869D01*
G01X2066039Y603172D02*
X2063539D01*
G01D02*
Y593172D01*
G01X2076039Y603172D02*
X2071039D01*
G01X2063539Y593172D02*
X2064089D01*
G01X2072989D02*
X2074089D01*
G01X2069189Y608617D02*
X2066089Y610227D01*
G01Y608617D02*
X2069189Y610227D01*
G01Y612445D02*
X2068517Y612522D01*
X2067949Y612637D01*
X2067432Y612790D01*
X2066864Y612982D01*
X2066089Y613289D01*
Y611755D01*
G01X2064089Y1205372D02*
X2063539D01*
G01D02*
Y1195372D01*
G01X2074089Y1205372D02*
X2072989D01*
G01X2063539Y1195372D02*
X2066039D01*
G01X2071039D02*
X2076039D01*
G01X2083539Y593172D02*
Y603172D01*
G01D02*
X2081039D01*
G01X2082989Y593172D02*
X2083539D01*
G01X2082230Y1185501D02*
X2079130Y1187111D01*
G01Y1185501D02*
X2082230Y1187111D01*
G01Y1189406D02*
X2079130D01*
X2079750Y1188946D01*
G01X2082230D02*
Y1189866D01*
G01X2083539Y1195372D02*
Y1205372D01*
G01D02*
X2082989D01*
G01X2081039Y1195372D02*
X2083539D01*
M02*
